G04 ================== begin FILE IDENTIFICATION RECORD ==================*
G04 Layout Name:  15669-1.brd*
G04 Film Name:    NOTICE*
G04 File Format:  Gerber RS274X*
G04 File Origin:  Cadence Allegro 16.5-S056*
G04 Origin Date:  Wed Nov 16 04:08:30 2016*
G04 *
G04 Layer:  MANUFACTURING/THERMAL*
G04 *
G04 Offset:    (0.00 0.00)*
G04 Mirror:    No*
G04 Mode:      Positive*
G04 Rotation:  0*
G04 FullContactRelief:  No*
G04 UndefLineWidth:     6.00*
G04 ================== end FILE IDENTIFICATION RECORD ====================*
%FSLAX35Y35*MOIN*%
%IR0*IPPOS*OFA0.00000B0.00000*MIA0B0*SFA1.00000B1.00000*%
%ADD10C,.004*%
%ADD11C,.006*%
%ADD12C,.0033*%
%ADD13C,.008*%
%ADD14C,.0055*%
G75*
%LPD*%
G75*
G36*
G01X301800Y213890D02*
G02X352500Y214150I25558J-40503D01*
G01X341350Y192820D01*
X312850D01*
X301800Y213890D01*
G37*
G36*
G01X298620Y274980D02*
X307300D01*
G03X341410Y274970I17058J11442D01*
G01X348960D01*
X338090Y253970D01*
X309590D01*
X298620Y274980D01*
G37*
G54D10*
G01X820594Y153868D02*
X808594Y155868D01*
G01X820009Y224740D02*
Y167889D01*
G01X820594Y161868D02*
Y141868D01*
G01X808594Y155868D02*
Y151868D01*
G01D02*
X820594Y153868D01*
G01X790009Y177889D02*
Y207889D01*
G01X796594Y153868D02*
X820594D01*
G01X770009Y177889D02*
X790009D01*
G01X820009Y167889D02*
X770009D01*
G01D02*
Y177889D01*
G01X810005Y234744D02*
X810009Y234740D01*
G01Y297889D02*
Y234740D01*
G01D02*
X820009Y224740D01*
G01X790009Y257889D02*
Y287889D01*
G01Y217889D02*
Y247889D01*
G01X770009Y257889D02*
X790009D01*
G01X770009Y247889D02*
Y257889D01*
G01X790009Y247889D02*
X770009D01*
G01Y217889D02*
X790009D01*
G01X770009Y207889D02*
Y217889D01*
G01X790009Y207889D02*
X770009D01*
G01X838514Y309548D02*
Y305548D01*
G01X850514Y307548D02*
X838514Y309548D01*
G01Y305548D02*
X850514Y307548D01*
G01X810514Y319548D02*
Y299548D01*
G01X822514Y305548D02*
Y309548D01*
G01X810514Y307548D02*
X822514Y305548D01*
G01Y309548D02*
X810514Y307548D01*
G01D02*
X850514D01*
G01X770009Y297889D02*
X810009D01*
G01X770009Y287889D02*
Y297889D01*
G01X790009Y287889D02*
X770009D01*
G01X890009Y167889D02*
Y177889D01*
G01X870009D02*
Y207889D01*
G01X890009Y177889D02*
X870009D01*
G01X852594Y151868D02*
Y155868D01*
G01X840009Y167889D02*
X890009D01*
G01X840009Y225249D02*
Y167889D01*
G01X859454Y153868D02*
X840594D01*
G01X852594Y155868D02*
X840594Y153868D01*
G01Y141868D02*
Y161868D01*
G01Y153868D02*
X852594Y151868D01*
G01X895009Y217889D02*
X961000D01*
G01X845009Y225249D02*
X961000D01*
G01X890009Y247889D02*
Y257889D01*
G01Y207889D02*
X890000Y217800D01*
G01X870009Y257889D02*
Y287889D01*
G01X890009Y257889D02*
X870009D01*
G01Y247889D02*
X890009D01*
G01X870009Y217889D02*
Y247889D01*
G01X890009Y217889D02*
X870009D01*
G01Y207889D02*
X890009D01*
G01X850009Y297889D02*
Y235249D01*
G01D02*
X840009Y225249D01*
G01X890009Y287889D02*
Y297889D01*
G01X870009Y287889D02*
X890009D01*
G01X850514Y319548D02*
Y299548D01*
G01Y307548D02*
X859374D01*
G01X890009Y297889D02*
X850009D01*
G01X954000Y237249D02*
X956000Y225249D01*
X958000Y237249D01*
X954000D01*
G01X956000Y249249D02*
Y225249D01*
G01X958000Y205889D02*
X956000Y217889D01*
X954000Y205889D01*
X958000D01*
G01X956000Y193889D02*
Y217889D01*
G01X1121654Y169388D02*
Y232028D01*
G01Y151388D02*
X1133654Y149388D01*
G01Y153388D02*
X1121654Y151388D01*
G01D02*
X1161654D01*
G01X1121654Y163388D02*
Y143388D01*
G01X1101654Y209388D02*
Y179388D01*
G01D02*
X1081654D01*
G01Y169388D02*
X1121654D01*
G01X1081654Y179388D02*
Y169388D01*
G01X1121654Y232028D02*
X1131654Y242028D01*
G01X1101654Y289388D02*
Y259388D01*
G01Y249388D02*
Y219388D01*
G01X1081654Y249388D02*
X1101654D01*
G01X1081654Y259388D02*
Y249388D01*
G01X1101654Y259388D02*
X1081654D01*
G01Y209388D02*
X1101654D01*
G01X1081654Y219388D02*
Y209388D01*
G01X1101654Y219388D02*
X1081654D01*
G01X1119654Y321388D02*
Y317388D01*
G01X1131654Y319388D02*
X1119654Y321388D01*
G01Y317388D02*
X1131654Y319388D01*
G01X1107654D02*
X1131654D01*
G01Y299388D02*
X1081654D01*
G01Y289388D02*
X1101654D01*
G01X1081654Y299388D02*
Y289388D01*
G01X1201654Y179388D02*
Y169388D01*
G01X1181654Y179388D02*
X1201654D01*
G01X1181654Y209388D02*
Y179388D01*
G01X1161654Y169388D02*
Y232537D01*
G01X1201654Y169388D02*
X1161654D01*
G01X1149654Y153388D02*
Y149388D01*
G01X1161654Y151388D02*
X1149654Y153388D01*
G01Y149388D02*
X1161654Y151388D01*
G01D02*
X1170514D01*
G01X1161654Y163388D02*
Y143388D01*
G01X1133654Y149388D02*
Y153388D01*
G01X1201654Y259388D02*
Y249388D01*
G01Y219388D02*
Y209388D01*
G01Y249388D02*
X1181654D01*
G01Y259388D02*
X1201654D01*
G01X1181654Y289388D02*
Y259388D01*
G01X1201654Y209388D02*
X1181654D01*
G01Y219388D02*
X1201654D01*
G01X1181654Y249388D02*
Y219388D01*
G01X1161658Y232533D02*
X1161654Y232537D01*
G01X1151654Y242537D02*
Y299388D01*
G01X1161654Y232537D02*
X1151654Y242537D01*
G01X1131654Y242028D02*
Y299388D01*
G01X1201654D02*
Y289388D01*
G01X1163654Y317388D02*
Y321388D01*
G01X1201654Y289388D02*
X1181654D01*
G01X1170514Y319388D02*
X1151654D01*
G01D02*
X1163654Y317388D01*
G01Y321388D02*
X1151654Y319388D01*
G01Y307388D02*
Y327388D01*
G01Y299388D02*
X1201654D01*
G01X1131654Y327388D02*
Y307388D01*
G54D11*
G01X4300Y524700D02*
X4250D01*
G01X54300Y770700D02*
X54250D01*
G01X288350Y208820D02*
X283350D01*
Y182820D01*
X288350D01*
G01Y187820D02*
X307850D01*
X296850Y208820D01*
X288350D01*
Y213820D01*
X301850D01*
X312850Y192820D01*
X341350D01*
X352350Y213820D01*
X365850D01*
Y208820D01*
X357350D01*
X346350Y187820D01*
X365850D01*
G01X288350D02*
Y182820D01*
X365850D01*
Y187820D01*
G01X285090Y269970D02*
X280090D01*
Y243970D01*
X285090D01*
G01Y248970D02*
X304590D01*
X293590Y269970D01*
X285090D01*
Y274970D01*
X298590D01*
X309590Y253970D01*
X338090D01*
X349090Y274970D01*
X362590D01*
Y269970D01*
X354090D01*
X343090Y248970D01*
X362590D01*
G01X285090D02*
Y243970D01*
X362590D01*
Y248970D01*
G01X329290Y266000D02*
X387990D01*
G01X315090Y310830D02*
X303090Y308830D01*
X315090Y306830D01*
Y310830D01*
G01X306290Y308830D02*
X303090D01*
G01X339590D02*
X304090D01*
G01X283590Y340830D02*
X278590D01*
Y314830D01*
X283590D01*
G01Y319830D02*
Y314830D01*
X361090D01*
Y319830D01*
G01X283590D02*
X303090D01*
X292090Y340830D01*
X283590D01*
Y345830D01*
X297090D01*
X308090Y324830D01*
X336590D01*
X347590Y345830D01*
X361090D01*
Y340830D01*
X352590D01*
X341590Y319830D01*
X361090D01*
G01X304090Y354830D02*
X292090Y352830D01*
X304090Y350830D01*
Y354830D01*
G01X311290Y352830D02*
X292090D01*
G01X365850Y208820D02*
X370850D01*
Y182820D01*
X365850D01*
G01X385140Y233310D02*
X383140Y221310D01*
X381140Y233310D01*
X385140D01*
G01X383140Y237850D02*
Y221310D01*
G01X385140Y202130D02*
X383140Y214130D01*
X381140Y202130D01*
X385140D01*
G01X383140Y197250D02*
Y214130D01*
G01X357370D02*
X388140D01*
G01X332370Y221310D02*
X388140D01*
G01X384990Y254000D02*
X382990Y266000D01*
X380990Y254000D01*
X384990D01*
G01X382990Y250500D02*
Y266000D01*
G01X362590Y269970D02*
X367590D01*
Y243970D01*
X362590D01*
G01X384990Y287010D02*
X382990Y275010D01*
X380990Y287010D01*
X384990D01*
G01X382990Y275010D02*
Y290150D01*
G01X346210Y275010D02*
X387990D01*
G01X329590Y306830D02*
X341590Y308830D01*
X329590Y310830D01*
Y306830D01*
G01X339890Y308830D02*
X341590D01*
G01X361090Y340830D02*
X366090D01*
Y314830D01*
X361090D01*
G01X340590Y350830D02*
X352590Y352830D01*
X340590Y354830D01*
Y350830D01*
G01X334890Y352830D02*
X352590D01*
G01X849500Y-12451D02*
X821000Y-12500D01*
G01X837503Y-14472D02*
X849500Y-12451D01*
X837497Y-10472D01*
X837503Y-14472D01*
G01X827500Y639629D02*
X830000Y624629D01*
X832500Y639629D01*
X827500D01*
G01X830000Y661875D02*
Y624629D01*
G01X931340D02*
X820000D01*
G01X830000Y693125D02*
Y725829D01*
G01X832500Y710829D02*
X830000Y725829D01*
X827500Y710829D01*
X832500D01*
G01X846340Y725829D02*
X820000D01*
G01X849500Y-12500D02*
Y59500D01*
X893500D01*
Y-12500D01*
X849500D01*
G01X903500D02*
X944500D01*
G01X903500Y59500D02*
X944500D01*
G01X878500Y67000D02*
X893500Y69500D01*
X878500Y72000D01*
Y67000D01*
G01X901475Y69500D02*
X893500D01*
G01X864500Y72000D02*
X849500Y69500D01*
X864500Y67000D01*
Y72000D01*
G01X893500Y69500D02*
X849500D01*
G01X893500Y64500D02*
Y79500D01*
G01X849500Y64500D02*
Y79500D01*
G01X937000Y44500D02*
X934500Y59500D01*
X932000Y44500D01*
X937000D01*
G01X934500Y43125D02*
Y59500D01*
G01X932000Y2500D02*
X934500Y-12500D01*
X937000Y2500D01*
X932000D01*
G01X934500Y11875D02*
Y-12500D01*
G01X1114953Y628479D02*
X1131500Y617000D01*
X1132500D01*
G01X1119916Y626861D02*
X1114953Y628479D01*
X1118206Y624397D01*
X1119916Y626861D01*
G01X1156654Y242537D02*
X1274500D01*
G01X1267500Y261388D02*
X1269500Y249388D01*
X1271500Y261388D01*
X1267500D01*
G01X1269500Y277200D02*
Y249388D01*
G01X1271500Y230537D02*
X1269500Y242537D01*
X1267500Y230537D01*
X1271500D01*
G01X1269500Y218537D02*
Y242537D01*
G01X1206654Y249388D02*
X1274500D01*
G01X11750Y-48833D02*
X12417Y-49250D01*
X13167Y-49500D01*
X13833D01*
X14500Y-49250D01*
X15000Y-48833D01*
X15250Y-48250D01*
X15083Y-47667D01*
X14667Y-47167D01*
X13917Y-46833D01*
X12917Y-46667D01*
X12333Y-46333D01*
X12083Y-45750D01*
X12250Y-45167D01*
X12667Y-44750D01*
X13250Y-44500D01*
X13833D01*
X14417Y-44667D01*
X14917Y-45083D01*
G01X19100Y-46167D02*
Y-49500D01*
G01Y-44833D02*
X18933Y-44750D01*
Y-44583D01*
X19100Y-44500D01*
X19267Y-44583D01*
Y-44750D01*
X19100Y-44833D01*
G01X24700Y-49500D02*
Y-44500D01*
G01X28883Y-49500D02*
Y-44500D01*
G01X31550Y-46167D02*
X28883Y-48083D01*
G01X29967Y-47333D02*
X31717Y-49500D01*
G01X34650Y-48917D02*
X35067Y-49250D01*
X35650Y-49500D01*
X36150D01*
X36650Y-49333D01*
X36983Y-49083D01*
X37150Y-48750D01*
X37067Y-48250D01*
X36733Y-48000D01*
X35233Y-47500D01*
X34900Y-46917D01*
X35067Y-46500D01*
X35400Y-46250D01*
X35900Y-46167D01*
X36400Y-46250D01*
X36900Y-46500D01*
G01X42833Y-46583D02*
X42250Y-46250D01*
X41750Y-46167D01*
X41083Y-46333D01*
X40583Y-46667D01*
X40250Y-47250D01*
X40167Y-47833D01*
X40250Y-48417D01*
X40583Y-48917D01*
X41083Y-49333D01*
X41750Y-49500D01*
X42333Y-49333D01*
X42833Y-49000D01*
G01X45933Y-49500D02*
Y-46167D01*
G01Y-46833D02*
X46350Y-46500D01*
X46767Y-46250D01*
X47350Y-46167D01*
X47767Y-46250D01*
X48267Y-46500D01*
G01X51450Y-47250D02*
X54117D01*
X53867Y-46667D01*
X53450Y-46333D01*
X52867Y-46167D01*
X52283Y-46250D01*
X51783Y-46500D01*
X51450Y-47083D01*
X51283Y-47583D01*
Y-48083D01*
X51450Y-48583D01*
X51867Y-49083D01*
X52367Y-49417D01*
X52950Y-49500D01*
X53533Y-49333D01*
X54117Y-48833D01*
G01X57050Y-47250D02*
X59717D01*
X59467Y-46667D01*
X59050Y-46333D01*
X58467Y-46167D01*
X57883Y-46250D01*
X57383Y-46500D01*
X57050Y-47083D01*
X56883Y-47583D01*
Y-48083D01*
X57050Y-48583D01*
X57467Y-49083D01*
X57967Y-49417D01*
X58550Y-49500D01*
X59133Y-49333D01*
X59717Y-48833D01*
G01X62483Y-49500D02*
Y-46167D01*
G01Y-47000D02*
X62817Y-46583D01*
X63317Y-46250D01*
X63983Y-46167D01*
X64567Y-46250D01*
X65067Y-46583D01*
X65317Y-47167D01*
Y-49500D01*
G01X0Y716000D02*
Y-69500D01*
G01D02*
X694500D01*
G01X11750Y-3833D02*
X12417Y-4250D01*
X13167Y-4500D01*
X13833D01*
X14500Y-4250D01*
X15000Y-3833D01*
X15250Y-3250D01*
X15083Y-2667D01*
X14667Y-2167D01*
X13917Y-1833D01*
X12917Y-1667D01*
X12333Y-1333D01*
X12083Y-750D01*
X12250Y-167D01*
X12667Y250D01*
X13250Y500D01*
X13833D01*
X14417Y333D01*
X14917Y-83D01*
G01X19100Y-4500D02*
X18600Y-4417D01*
X18100Y-4083D01*
X17767Y-3500D01*
X17600Y-2833D01*
X17767Y-2167D01*
X18100Y-1583D01*
X18600Y-1250D01*
X19100Y-1167D01*
X19600Y-1250D01*
X20100Y-1583D01*
X20433Y-2167D01*
X20517Y-2833D01*
X20433Y-3500D01*
X20100Y-4083D01*
X19600Y-4417D01*
X19100Y-4500D01*
G01X24700D02*
Y500D01*
G01X31800D02*
Y-4500D01*
G01Y-3750D02*
X31467Y-4167D01*
X30967Y-4417D01*
X30383Y-4500D01*
X29717Y-4333D01*
X29217Y-3917D01*
X28883Y-3417D01*
X28800Y-2833D01*
X28883Y-2250D01*
X29217Y-1750D01*
X29717Y-1333D01*
X30383Y-1167D01*
X30967Y-1250D01*
X31383Y-1417D01*
X31800Y-1750D01*
G01X34650Y-2250D02*
X37317D01*
X37067Y-1667D01*
X36650Y-1333D01*
X36067Y-1167D01*
X35483Y-1250D01*
X34983Y-1500D01*
X34650Y-2083D01*
X34483Y-2583D01*
Y-3083D01*
X34650Y-3583D01*
X35067Y-4083D01*
X35567Y-4417D01*
X36150Y-4500D01*
X36733Y-4333D01*
X37317Y-3833D01*
G01X40333Y-4500D02*
Y-1167D01*
G01Y-1833D02*
X40750Y-1500D01*
X41167Y-1250D01*
X41750Y-1167D01*
X42167Y-1250D01*
X42667Y-1500D01*
G01X50200Y-4500D02*
Y-1167D01*
G01Y-2083D02*
X50450Y-1667D01*
X50867Y-1333D01*
X51450Y-1167D01*
X52033Y-1333D01*
X52450Y-1667D01*
X52700Y-2083D01*
Y-4500D01*
G01Y-2083D02*
X52950Y-1667D01*
X53367Y-1333D01*
X53950Y-1167D01*
X54533Y-1333D01*
X54950Y-1667D01*
X55200Y-2167D01*
Y-4500D01*
G01X59800D02*
Y-1167D01*
G01Y-1750D02*
X59467Y-1417D01*
X58967Y-1250D01*
X58383Y-1167D01*
X57800Y-1333D01*
X57300Y-1667D01*
X56967Y-2167D01*
X56800Y-2833D01*
X56967Y-3500D01*
X57300Y-4000D01*
X57800Y-4333D01*
X58383Y-4500D01*
X58967Y-4417D01*
X59467Y-4167D01*
X59800Y-3833D01*
G01X62650Y-3917D02*
X63067Y-4250D01*
X63650Y-4500D01*
X64150D01*
X64650Y-4333D01*
X64983Y-4083D01*
X65150Y-3750D01*
X65067Y-3250D01*
X64733Y-3000D01*
X63233Y-2500D01*
X62900Y-1917D01*
X63067Y-1500D01*
X63400Y-1250D01*
X63900Y-1167D01*
X64400Y-1250D01*
X64900Y-1500D01*
G01X68083Y-4500D02*
Y500D01*
G01X70750Y-1167D02*
X68083Y-3083D01*
G01X69167Y-2333D02*
X70917Y-4500D01*
G01X0Y-24500D02*
X694500D01*
G01X0Y19500D02*
X694500D01*
G01X15167Y64000D02*
X11833D01*
Y69000D01*
X15167D01*
G01X13833Y66583D02*
X11833D01*
G01X19100Y69000D02*
Y64000D01*
G01X17933Y67333D02*
X20267D01*
G01X26033Y66917D02*
X25450Y67250D01*
X24950Y67333D01*
X24283Y67167D01*
X23783Y66833D01*
X23450Y66250D01*
X23367Y65667D01*
X23450Y65083D01*
X23783Y64583D01*
X24283Y64167D01*
X24950Y64000D01*
X25533Y64167D01*
X26033Y64500D01*
G01X28883Y64000D02*
Y69000D01*
G01Y66583D02*
X29300Y67000D01*
X29717Y67250D01*
X30383Y67333D01*
X30883Y67250D01*
X31467Y66917D01*
X31717Y66417D01*
Y64000D01*
G01X15167Y111500D02*
X11833D01*
Y116500D01*
X15167D01*
G01X13833Y114083D02*
X11833D01*
G01X17850Y114833D02*
X20350Y111500D01*
G01Y114833D02*
X17850Y111500D01*
G01X24700Y116500D02*
Y111500D01*
G01X23533Y114833D02*
X25867D01*
G01X29050Y113750D02*
X31717D01*
X31467Y114333D01*
X31050Y114667D01*
X30467Y114833D01*
X29883Y114750D01*
X29383Y114500D01*
X29050Y113917D01*
X28883Y113417D01*
Y112917D01*
X29050Y112417D01*
X29467Y111917D01*
X29967Y111583D01*
X30550Y111500D01*
X31133Y111667D01*
X31717Y112167D01*
G01X34733Y111500D02*
Y114833D01*
G01Y114167D02*
X35150Y114500D01*
X35567Y114750D01*
X36150Y114833D01*
X36567Y114750D01*
X37067Y114500D01*
G01X40083Y111500D02*
Y114833D01*
G01Y114000D02*
X40417Y114417D01*
X40917Y114750D01*
X41583Y114833D01*
X42167Y114750D01*
X42667Y114417D01*
X42917Y113833D01*
Y111500D01*
G01X48600D02*
Y114833D01*
G01Y114250D02*
X48267Y114583D01*
X47767Y114750D01*
X47183Y114833D01*
X46600Y114667D01*
X46100Y114333D01*
X45767Y113833D01*
X45600Y113167D01*
X45767Y112500D01*
X46100Y112000D01*
X46600Y111667D01*
X47183Y111500D01*
X47767Y111583D01*
X48267Y111833D01*
X48600Y112167D01*
G01X52700Y111500D02*
Y116500D01*
G01X63900Y111500D02*
Y116500D01*
G01X71000Y111500D02*
Y114833D01*
G01Y114250D02*
X70667Y114583D01*
X70167Y114750D01*
X69583Y114833D01*
X69000Y114667D01*
X68500Y114333D01*
X68167Y113833D01*
X68000Y113167D01*
X68167Y112500D01*
X68500Y112000D01*
X69000Y111667D01*
X69583Y111500D01*
X70167Y111583D01*
X70667Y111833D01*
X71000Y112167D01*
G01X73350Y110000D02*
X73850Y109833D01*
X74517Y110000D01*
X74933Y110333D01*
X75267Y110750D01*
X75767Y112083D01*
X76850Y114833D01*
G01X74183D02*
X75767Y112083D01*
G01X79450Y113750D02*
X82117D01*
X81867Y114333D01*
X81450Y114667D01*
X80867Y114833D01*
X80283Y114750D01*
X79783Y114500D01*
X79450Y113917D01*
X79283Y113417D01*
Y112917D01*
X79450Y112417D01*
X79867Y111917D01*
X80367Y111583D01*
X80950Y111500D01*
X81533Y111667D01*
X82117Y112167D01*
G01X85133Y111500D02*
Y114833D01*
G01Y114167D02*
X85550Y114500D01*
X85967Y114750D01*
X86550Y114833D01*
X86967Y114750D01*
X87467Y114500D01*
G01X0Y105500D02*
X694500D01*
G01X15333Y146083D02*
X14833Y146333D01*
X14250Y146500D01*
X13583D01*
X12833Y146250D01*
X12250Y145833D01*
X11833Y145333D01*
X11500Y144500D01*
X11417Y143750D01*
X11583Y143000D01*
X11833Y142500D01*
X12333Y142000D01*
X12917Y141667D01*
X13500Y141500D01*
X14083D01*
X14667Y141667D01*
X15167Y141917D01*
X15583Y142250D01*
G01X19100Y141500D02*
X18600Y141583D01*
X18100Y141917D01*
X17767Y142500D01*
X17600Y143167D01*
X17767Y143833D01*
X18100Y144417D01*
X18600Y144750D01*
X19100Y144833D01*
X19600Y144750D01*
X20100Y144417D01*
X20433Y143833D01*
X20517Y143167D01*
X20433Y142500D01*
X20100Y141917D01*
X19600Y141583D01*
X19100Y141500D01*
G01X23200Y139833D02*
Y144833D01*
G01Y144083D02*
X23617Y144500D01*
X24033Y144750D01*
X24700Y144833D01*
X25283Y144750D01*
X25867Y144333D01*
X26117Y143750D01*
X26200Y143167D01*
X26117Y142583D01*
X25867Y142000D01*
X25367Y141667D01*
X24700Y141500D01*
X24117Y141583D01*
X23533Y141833D01*
X23200Y142167D01*
G01X28800Y139833D02*
Y144833D01*
G01Y144083D02*
X29217Y144500D01*
X29633Y144750D01*
X30300Y144833D01*
X30883Y144750D01*
X31467Y144333D01*
X31717Y143750D01*
X31800Y143167D01*
X31717Y142583D01*
X31467Y142000D01*
X30967Y141667D01*
X30300Y141500D01*
X29717Y141583D01*
X29133Y141833D01*
X28800Y142167D01*
G01X34650Y143750D02*
X37317D01*
X37067Y144333D01*
X36650Y144667D01*
X36067Y144833D01*
X35483Y144750D01*
X34983Y144500D01*
X34650Y143917D01*
X34483Y143417D01*
Y142917D01*
X34650Y142417D01*
X35067Y141917D01*
X35567Y141583D01*
X36150Y141500D01*
X36733Y141667D01*
X37317Y142167D01*
G01X40333Y141500D02*
Y144833D01*
G01Y144167D02*
X40750Y144500D01*
X41167Y144750D01*
X41750Y144833D01*
X42167Y144750D01*
X42667Y144500D01*
G01X51033Y141500D02*
Y146500D01*
X53033D01*
X53700Y146250D01*
X54200Y145667D01*
X54367Y145000D01*
X54200Y144333D01*
X53783Y143833D01*
X53033Y143583D01*
X51033D01*
G01X58300Y141500D02*
Y146500D01*
G01X65400Y141500D02*
Y144833D01*
G01Y144250D02*
X65067Y144583D01*
X64567Y144750D01*
X63983Y144833D01*
X63400Y144667D01*
X62900Y144333D01*
X62567Y143833D01*
X62400Y143167D01*
X62567Y142500D01*
X62900Y142000D01*
X63400Y141667D01*
X63983Y141500D01*
X64567Y141583D01*
X65067Y141833D01*
X65400Y142167D01*
G01X69500Y146500D02*
Y141500D01*
G01X68333Y144833D02*
X70667D01*
G01X75100D02*
Y141500D01*
G01Y146167D02*
X74933Y146250D01*
Y146417D01*
X75100Y146500D01*
X75267Y146417D01*
Y146250D01*
X75100Y146167D01*
G01X79283Y141500D02*
Y144833D01*
G01Y144000D02*
X79617Y144417D01*
X80117Y144750D01*
X80783Y144833D01*
X81367Y144750D01*
X81867Y144417D01*
X82117Y143833D01*
Y141500D01*
G01X85133Y140250D02*
X85717Y139917D01*
X86383Y139833D01*
X86967Y139917D01*
X87467Y140333D01*
X87800Y140917D01*
Y144833D01*
G01Y144167D02*
X87467Y144500D01*
X86967Y144750D01*
X86383Y144833D01*
X85717Y144667D01*
X85300Y144333D01*
X84967Y143750D01*
X84800Y143167D01*
X84883Y142667D01*
X85217Y142083D01*
X85717Y141667D01*
X86383Y141500D01*
X86883Y141583D01*
X87467Y141917D01*
X87800Y142250D01*
G01X1500Y175500D02*
X694500D01*
G01X0Y120500D02*
X694500D01*
G01X11667Y459000D02*
Y464000D01*
X13333D01*
X14000Y463750D01*
X14500Y463417D01*
X14917Y462917D01*
X15250Y462333D01*
X15333Y461500D01*
X15250Y460667D01*
X14917Y460083D01*
X14500Y459583D01*
X14000Y459250D01*
X13333Y459000D01*
X11667D01*
G01X17933D02*
Y462333D01*
G01Y461667D02*
X18350Y462000D01*
X18767Y462250D01*
X19350Y462333D01*
X19767Y462250D01*
X20267Y462000D01*
G01X24700Y462333D02*
Y459000D01*
G01Y463667D02*
X24533Y463750D01*
Y463917D01*
X24700Y464000D01*
X24867Y463917D01*
Y463750D01*
X24700Y463667D01*
G01X30300Y459000D02*
Y464000D01*
G01X35900Y459000D02*
Y464000D01*
G01X24960Y626740D02*
X26960D01*
G01X25960D02*
Y621740D01*
G01X24960D02*
X26960D01*
G01X30143D02*
Y625073D01*
G01Y624240D02*
X30477Y624657D01*
X30977Y624990D01*
X31643Y625073D01*
X32227Y624990D01*
X32727Y624657D01*
X32977Y624073D01*
Y621740D01*
G01X35743D02*
Y625073D01*
G01Y624240D02*
X36077Y624657D01*
X36577Y624990D01*
X37243Y625073D01*
X37827Y624990D01*
X38327Y624657D01*
X38577Y624073D01*
Y621740D01*
G01X41510Y623990D02*
X44177D01*
X43927Y624573D01*
X43510Y624907D01*
X42927Y625073D01*
X42343Y624990D01*
X41843Y624740D01*
X41510Y624157D01*
X41343Y623657D01*
Y623157D01*
X41510Y622657D01*
X41927Y622157D01*
X42427Y621823D01*
X43010Y621740D01*
X43593Y621907D01*
X44177Y622407D01*
G01X47193Y621740D02*
Y625073D01*
G01Y624407D02*
X47610Y624740D01*
X48027Y624990D01*
X48610Y625073D01*
X49027Y624990D01*
X49527Y624740D01*
G01X59560Y621740D02*
Y626740D01*
G01X66660Y621740D02*
Y625073D01*
G01Y624490D02*
X66327Y624823D01*
X65827Y624990D01*
X65243Y625073D01*
X64660Y624907D01*
X64160Y624573D01*
X63827Y624073D01*
X63660Y623407D01*
X63827Y622740D01*
X64160Y622240D01*
X64660Y621907D01*
X65243Y621740D01*
X65827Y621823D01*
X66327Y622073D01*
X66660Y622407D01*
G01X69010Y620240D02*
X69510Y620073D01*
X70177Y620240D01*
X70593Y620573D01*
X70927Y620990D01*
X71427Y622323D01*
X72510Y625073D01*
G01X69843D02*
X71427Y622323D01*
G01X75110Y623990D02*
X77777D01*
X77527Y624573D01*
X77110Y624907D01*
X76527Y625073D01*
X75943Y624990D01*
X75443Y624740D01*
X75110Y624157D01*
X74943Y623657D01*
Y623157D01*
X75110Y622657D01*
X75527Y622157D01*
X76027Y621823D01*
X76610Y621740D01*
X77193Y621907D01*
X77777Y622407D01*
G01X80793Y621740D02*
Y625073D01*
G01Y624407D02*
X81210Y624740D01*
X81627Y624990D01*
X82210Y625073D01*
X82627Y624990D01*
X83127Y624740D01*
G01X0Y599000D02*
X694500D01*
G01X9917Y693667D02*
X10417Y694167D01*
X11000Y694417D01*
X11667Y694500D01*
X12500Y694333D01*
X13083Y693917D01*
X13250Y693417D01*
X13167Y692917D01*
X12833Y692500D01*
X11167Y691667D01*
X10417Y691083D01*
X9917Y690250D01*
X9750Y689500D01*
X13250D01*
G01X17100Y689333D02*
X16933Y689417D01*
Y689583D01*
X17100Y689667D01*
X17267Y689583D01*
Y689417D01*
X17100Y689333D01*
G01X22700Y694500D02*
Y689500D01*
G01X20783Y694500D02*
X24617D01*
G01X28300Y689500D02*
X27800Y689583D01*
X27300Y689917D01*
X26967Y690500D01*
X26800Y691167D01*
X26967Y691833D01*
X27300Y692417D01*
X27800Y692750D01*
X28300Y692833D01*
X28800Y692750D01*
X29300Y692417D01*
X29633Y691833D01*
X29717Y691167D01*
X29633Y690500D01*
X29300Y689917D01*
X28800Y689583D01*
X28300Y689500D01*
G01X33900D02*
Y694500D01*
G01X38250Y691750D02*
X40917D01*
X40667Y692333D01*
X40250Y692667D01*
X39667Y692833D01*
X39083Y692750D01*
X38583Y692500D01*
X38250Y691917D01*
X38083Y691417D01*
Y690917D01*
X38250Y690417D01*
X38667Y689917D01*
X39167Y689583D01*
X39750Y689500D01*
X40333Y689667D01*
X40917Y690167D01*
G01X43933Y689500D02*
Y692833D01*
G01Y692167D02*
X44350Y692500D01*
X44767Y692750D01*
X45350Y692833D01*
X45767Y692750D01*
X46267Y692500D01*
G01X52200Y689500D02*
Y692833D01*
G01Y692250D02*
X51867Y692583D01*
X51367Y692750D01*
X50783Y692833D01*
X50200Y692667D01*
X49700Y692333D01*
X49367Y691833D01*
X49200Y691167D01*
X49367Y690500D01*
X49700Y690000D01*
X50200Y689667D01*
X50783Y689500D01*
X51367Y689583D01*
X51867Y689833D01*
X52200Y690167D01*
G01X54883Y689500D02*
Y692833D01*
G01Y692000D02*
X55217Y692417D01*
X55717Y692750D01*
X56383Y692833D01*
X56967Y692750D01*
X57467Y692417D01*
X57717Y691833D01*
Y689500D01*
G01X63233Y692417D02*
X62650Y692750D01*
X62150Y692833D01*
X61483Y692667D01*
X60983Y692333D01*
X60650Y691750D01*
X60567Y691167D01*
X60650Y690583D01*
X60983Y690083D01*
X61483Y689667D01*
X62150Y689500D01*
X62733Y689667D01*
X63233Y690000D01*
G01X66250Y691750D02*
X68917D01*
X68667Y692333D01*
X68250Y692667D01*
X67667Y692833D01*
X67083Y692750D01*
X66583Y692500D01*
X66250Y691917D01*
X66083Y691417D01*
Y690917D01*
X66250Y690417D01*
X66667Y689917D01*
X67167Y689583D01*
X67750Y689500D01*
X68333Y689667D01*
X68917Y690167D01*
G01X78700Y694500D02*
Y689500D01*
G01X77533Y692833D02*
X79867D01*
G01X85800Y689500D02*
Y692833D01*
G01Y692250D02*
X85467Y692583D01*
X84967Y692750D01*
X84383Y692833D01*
X83800Y692667D01*
X83300Y692333D01*
X82967Y691833D01*
X82800Y691167D01*
X82967Y690500D01*
X83300Y690000D01*
X83800Y689667D01*
X84383Y689500D01*
X84967Y689583D01*
X85467Y689833D01*
X85800Y690167D01*
G01X88400Y689500D02*
Y694500D01*
G01Y692000D02*
X88817Y692500D01*
X89317Y692750D01*
X89817Y692833D01*
X90567Y692667D01*
X91067Y692333D01*
X91400Y691750D01*
Y691083D01*
X91233Y690417D01*
X90900Y689917D01*
X90317Y689583D01*
X89817Y689500D01*
X89317Y689583D01*
X88817Y689833D01*
X88400Y690250D01*
G01X95500Y689500D02*
Y694500D01*
G01X99850Y691750D02*
X102517D01*
X102267Y692333D01*
X101850Y692667D01*
X101267Y692833D01*
X100683Y692750D01*
X100183Y692500D01*
X99850Y691917D01*
X99683Y691417D01*
Y690917D01*
X99850Y690417D01*
X100267Y689917D01*
X100767Y689583D01*
X101350Y689500D01*
X101933Y689667D01*
X102517Y690167D01*
G01X106700Y689333D02*
X106533Y689417D01*
Y689583D01*
X106700Y689667D01*
X106867Y689583D01*
Y689417D01*
X106700Y689333D01*
G01Y691583D02*
X106533Y691667D01*
Y691833D01*
X106700Y691917D01*
X106867Y691833D01*
Y691667D01*
X106700Y691583D01*
G01X34000Y663333D02*
Y668333D01*
G01Y667583D02*
X34417Y668000D01*
X34833Y668250D01*
X35500Y668333D01*
X36083Y668250D01*
X36667Y667833D01*
X36917Y667250D01*
X37000Y666667D01*
X36917Y666083D01*
X36667Y665500D01*
X36167Y665167D01*
X35500Y665000D01*
X34917Y665083D01*
X34333Y665333D01*
X34000Y665667D01*
G01X39933Y665000D02*
Y668333D01*
G01Y667667D02*
X40350Y668000D01*
X40767Y668250D01*
X41350Y668333D01*
X41767Y668250D01*
X42267Y668000D01*
G01X46700Y665000D02*
X46200Y665083D01*
X45700Y665417D01*
X45367Y666000D01*
X45200Y666667D01*
X45367Y667333D01*
X45700Y667917D01*
X46200Y668250D01*
X46700Y668333D01*
X47200Y668250D01*
X47700Y667917D01*
X48033Y667333D01*
X48117Y666667D01*
X48033Y666000D01*
X47700Y665417D01*
X47200Y665083D01*
X46700Y665000D01*
G01X53633Y667917D02*
X53050Y668250D01*
X52550Y668333D01*
X51883Y668167D01*
X51383Y667833D01*
X51050Y667250D01*
X50967Y666667D01*
X51050Y666083D01*
X51383Y665583D01*
X51883Y665167D01*
X52550Y665000D01*
X53133Y665167D01*
X53633Y665500D01*
G01X56650Y667250D02*
X59317D01*
X59067Y667833D01*
X58650Y668167D01*
X58067Y668333D01*
X57483Y668250D01*
X56983Y668000D01*
X56650Y667417D01*
X56483Y666917D01*
Y666417D01*
X56650Y665917D01*
X57067Y665417D01*
X57567Y665083D01*
X58150Y665000D01*
X58733Y665167D01*
X59317Y665667D01*
G01X62250Y665583D02*
X62667Y665250D01*
X63250Y665000D01*
X63750D01*
X64250Y665167D01*
X64583Y665417D01*
X64750Y665750D01*
X64667Y666250D01*
X64333Y666500D01*
X62833Y667000D01*
X62500Y667583D01*
X62667Y668000D01*
X63000Y668250D01*
X63500Y668333D01*
X64000Y668250D01*
X64500Y668000D01*
G01X67850Y665583D02*
X68267Y665250D01*
X68850Y665000D01*
X69350D01*
X69850Y665167D01*
X70183Y665417D01*
X70350Y665750D01*
X70267Y666250D01*
X69933Y666500D01*
X68433Y667000D01*
X68100Y667583D01*
X68267Y668000D01*
X68600Y668250D01*
X69100Y668333D01*
X69600Y668250D01*
X70100Y668000D01*
G01X0Y679000D02*
X694500D01*
G01X-1000Y654000D02*
X694500D01*
G01X0Y850500D02*
Y709000D01*
X694500D01*
Y850500D01*
G01X7000Y832500D02*
Y837500D01*
X6000Y836500D01*
G01Y832500D02*
X8000D01*
G01X12600Y832333D02*
X12433Y832417D01*
Y832583D01*
X12600Y832667D01*
X12767Y832583D01*
Y832417D01*
X12600Y832333D01*
G01X16450Y833167D02*
X17117Y832750D01*
X17867Y832500D01*
X18533D01*
X19200Y832750D01*
X19700Y833167D01*
X19950Y833750D01*
X19783Y834333D01*
X19367Y834833D01*
X18617Y835167D01*
X17617Y835333D01*
X17033Y835667D01*
X16783Y836250D01*
X16950Y836833D01*
X17367Y837250D01*
X17950Y837500D01*
X18533D01*
X19117Y837333D01*
X19617Y836917D01*
G01X22300Y830833D02*
Y835833D01*
G01Y835083D02*
X22717Y835500D01*
X23133Y835750D01*
X23800Y835833D01*
X24383Y835750D01*
X24967Y835333D01*
X25217Y834750D01*
X25300Y834167D01*
X25217Y833583D01*
X24967Y833000D01*
X24467Y832667D01*
X23800Y832500D01*
X23217Y832583D01*
X22633Y832833D01*
X22300Y833167D01*
G01X28150Y834750D02*
X30817D01*
X30567Y835333D01*
X30150Y835667D01*
X29567Y835833D01*
X28983Y835750D01*
X28483Y835500D01*
X28150Y834917D01*
X27983Y834417D01*
Y833917D01*
X28150Y833417D01*
X28567Y832917D01*
X29067Y832583D01*
X29650Y832500D01*
X30233Y832667D01*
X30817Y833167D01*
G01X36333Y835417D02*
X35750Y835750D01*
X35250Y835833D01*
X34583Y835667D01*
X34083Y835333D01*
X33750Y834750D01*
X33667Y834167D01*
X33750Y833583D01*
X34083Y833083D01*
X34583Y832667D01*
X35250Y832500D01*
X35833Y832667D01*
X36333Y833000D01*
G01X40600Y835833D02*
Y832500D01*
G01Y837167D02*
X40433Y837250D01*
Y837417D01*
X40600Y837500D01*
X40767Y837417D01*
Y837250D01*
X40600Y837167D01*
G01X45700Y832500D02*
Y836750D01*
X45867Y837167D01*
X46200Y837417D01*
X46700Y837500D01*
X47200Y837333D01*
X47450Y836917D01*
G01X46450Y835500D02*
X44783D01*
G01X51800Y835833D02*
Y832500D01*
G01Y837167D02*
X51633Y837250D01*
Y837417D01*
X51800Y837500D01*
X51967Y837417D01*
Y837250D01*
X51800Y837167D01*
G01X58733Y835417D02*
X58150Y835750D01*
X57650Y835833D01*
X56983Y835667D01*
X56483Y835333D01*
X56150Y834750D01*
X56067Y834167D01*
X56150Y833583D01*
X56483Y833083D01*
X56983Y832667D01*
X57650Y832500D01*
X58233Y832667D01*
X58733Y833000D01*
G01X64500Y832500D02*
Y835833D01*
G01Y835250D02*
X64167Y835583D01*
X63667Y835750D01*
X63083Y835833D01*
X62500Y835667D01*
X62000Y835333D01*
X61667Y834833D01*
X61500Y834167D01*
X61667Y833500D01*
X62000Y833000D01*
X62500Y832667D01*
X63083Y832500D01*
X63667Y832583D01*
X64167Y832833D01*
X64500Y833167D01*
G01X68600Y837500D02*
Y832500D01*
G01X67433Y835833D02*
X69767D01*
G01X74200D02*
Y832500D01*
G01Y837167D02*
X74033Y837250D01*
Y837417D01*
X74200Y837500D01*
X74367Y837417D01*
Y837250D01*
X74200Y837167D01*
G01X79800Y832500D02*
X79300Y832583D01*
X78800Y832917D01*
X78467Y833500D01*
X78300Y834167D01*
X78467Y834833D01*
X78800Y835417D01*
X79300Y835750D01*
X79800Y835833D01*
X80300Y835750D01*
X80800Y835417D01*
X81133Y834833D01*
X81217Y834167D01*
X81133Y833500D01*
X80800Y832917D01*
X80300Y832583D01*
X79800Y832500D01*
G01X83983D02*
Y835833D01*
G01Y835000D02*
X84317Y835417D01*
X84817Y835750D01*
X85483Y835833D01*
X86067Y835750D01*
X86567Y835417D01*
X86817Y834833D01*
Y832500D01*
G01X98100Y837500D02*
Y832500D01*
G01Y833250D02*
X97767Y832833D01*
X97267Y832583D01*
X96683Y832500D01*
X96017Y832667D01*
X95517Y833083D01*
X95183Y833583D01*
X95100Y834167D01*
X95183Y834750D01*
X95517Y835250D01*
X96017Y835667D01*
X96683Y835833D01*
X97267Y835750D01*
X97683Y835583D01*
X98100Y835250D01*
G01X102200Y832500D02*
X101700Y832583D01*
X101200Y832917D01*
X100867Y833500D01*
X100700Y834167D01*
X100867Y834833D01*
X101200Y835417D01*
X101700Y835750D01*
X102200Y835833D01*
X102700Y835750D01*
X103200Y835417D01*
X103533Y834833D01*
X103617Y834167D01*
X103533Y833500D01*
X103200Y832917D01*
X102700Y832583D01*
X102200Y832500D01*
G01X109133Y835417D02*
X108550Y835750D01*
X108050Y835833D01*
X107383Y835667D01*
X106883Y835333D01*
X106550Y834750D01*
X106467Y834167D01*
X106550Y833583D01*
X106883Y833083D01*
X107383Y832667D01*
X108050Y832500D01*
X108633Y832667D01*
X109133Y833000D01*
G01X111983Y835833D02*
Y833500D01*
X112317Y832917D01*
X112817Y832583D01*
X113400Y832500D01*
X113983Y832583D01*
X114483Y832917D01*
X114817Y833500D01*
G01Y832500D02*
Y835833D01*
G01X116500Y832500D02*
Y835833D01*
G01Y834917D02*
X116750Y835333D01*
X117167Y835667D01*
X117750Y835833D01*
X118333Y835667D01*
X118750Y835333D01*
X119000Y834917D01*
Y832500D01*
G01Y834917D02*
X119250Y835333D01*
X119667Y835667D01*
X120250Y835833D01*
X120833Y835667D01*
X121250Y835333D01*
X121500Y834833D01*
Y832500D01*
G01X123350Y834750D02*
X126017D01*
X125767Y835333D01*
X125350Y835667D01*
X124767Y835833D01*
X124183Y835750D01*
X123683Y835500D01*
X123350Y834917D01*
X123183Y834417D01*
Y833917D01*
X123350Y833417D01*
X123767Y832917D01*
X124267Y832583D01*
X124850Y832500D01*
X125433Y832667D01*
X126017Y833167D01*
G01X128783Y832500D02*
Y835833D01*
G01Y835000D02*
X129117Y835417D01*
X129617Y835750D01*
X130283Y835833D01*
X130867Y835750D01*
X131367Y835417D01*
X131617Y834833D01*
Y832500D01*
G01X135800Y837500D02*
Y832500D01*
G01X134633Y835833D02*
X136967D01*
G01X141400Y832333D02*
X141233Y832417D01*
Y832583D01*
X141400Y832667D01*
X141567Y832583D01*
Y832417D01*
X141400Y832333D01*
G01Y834583D02*
X141233Y834667D01*
Y834833D01*
X141400Y834917D01*
X141567Y834833D01*
Y834667D01*
X141400Y834583D01*
G01X0Y820500D02*
X694500D01*
G01X0Y850500D02*
X694500D01*
G01X103500Y679000D02*
Y-69500D01*
G01Y-54500D02*
X694500D01*
G01X113070Y36130D02*
X114737D01*
Y34630D01*
X114237Y34130D01*
X113653Y33797D01*
X112820Y33630D01*
X111987Y33797D01*
X111403Y34130D01*
X110903Y34630D01*
X110570Y35213D01*
X110403Y35880D01*
Y36463D01*
X110570Y36963D01*
X110903Y37547D01*
X111403Y38047D01*
X111903Y38380D01*
X112570Y38630D01*
X113153D01*
X113820Y38463D01*
X114320Y38130D01*
G01X118170Y33630D02*
X117670Y33713D01*
X117170Y34047D01*
X116837Y34630D01*
X116670Y35297D01*
X116837Y35963D01*
X117170Y36547D01*
X117670Y36880D01*
X118170Y36963D01*
X118670Y36880D01*
X119170Y36547D01*
X119503Y35963D01*
X119587Y35297D01*
X119503Y34630D01*
X119170Y34047D01*
X118670Y33713D01*
X118170Y33630D01*
G01X123770D02*
Y38630D01*
G01X130870D02*
Y33630D01*
G01Y34380D02*
X130537Y33963D01*
X130037Y33713D01*
X129453Y33630D01*
X128787Y33797D01*
X128287Y34213D01*
X127953Y34713D01*
X127870Y35297D01*
X127953Y35880D01*
X128287Y36380D01*
X128787Y36797D01*
X129453Y36963D01*
X130037Y36880D01*
X130453Y36713D01*
X130870Y36380D01*
G01X133720Y35880D02*
X136387D01*
X136137Y36463D01*
X135720Y36797D01*
X135137Y36963D01*
X134553Y36880D01*
X134053Y36630D01*
X133720Y36047D01*
X133553Y35547D01*
Y35047D01*
X133720Y34547D01*
X134137Y34047D01*
X134637Y33713D01*
X135220Y33630D01*
X135803Y33797D01*
X136387Y34297D01*
G01X139153Y33630D02*
Y36963D01*
G01Y36130D02*
X139487Y36547D01*
X139987Y36880D01*
X140653Y36963D01*
X141237Y36880D01*
X141737Y36547D01*
X141987Y35963D01*
Y33630D01*
G01X151270D02*
Y37880D01*
X151437Y38297D01*
X151770Y38547D01*
X152270Y38630D01*
X152770Y38463D01*
X153020Y38047D01*
G01X152020Y36630D02*
X150353D01*
G01X157370Y36963D02*
Y33630D01*
G01Y38297D02*
X157203Y38380D01*
Y38547D01*
X157370Y38630D01*
X157537Y38547D01*
Y38380D01*
X157370Y38297D01*
G01X161553Y33630D02*
Y36963D01*
G01Y36130D02*
X161887Y36547D01*
X162387Y36880D01*
X163053Y36963D01*
X163637Y36880D01*
X164137Y36547D01*
X164387Y35963D01*
Y33630D01*
G01X167403Y32380D02*
X167987Y32047D01*
X168653Y31963D01*
X169237Y32047D01*
X169737Y32463D01*
X170070Y33047D01*
Y36963D01*
G01Y36297D02*
X169737Y36630D01*
X169237Y36880D01*
X168653Y36963D01*
X167987Y36797D01*
X167570Y36463D01*
X167237Y35880D01*
X167070Y35297D01*
X167153Y34797D01*
X167487Y34213D01*
X167987Y33797D01*
X168653Y33630D01*
X169153Y33713D01*
X169737Y34047D01*
X170070Y34380D01*
G01X172920Y35880D02*
X175587D01*
X175337Y36463D01*
X174920Y36797D01*
X174337Y36963D01*
X173753Y36880D01*
X173253Y36630D01*
X172920Y36047D01*
X172753Y35547D01*
Y35047D01*
X172920Y34547D01*
X173337Y34047D01*
X173837Y33713D01*
X174420Y33630D01*
X175003Y33797D01*
X175587Y34297D01*
G01X178603Y33630D02*
Y36963D01*
G01Y36297D02*
X179020Y36630D01*
X179437Y36880D01*
X180020Y36963D01*
X180437Y36880D01*
X180937Y36630D01*
G01X189303Y33630D02*
Y38630D01*
X191303D01*
X191970Y38380D01*
X192470Y37797D01*
X192637Y37130D01*
X192470Y36463D01*
X192053Y35963D01*
X191303Y35713D01*
X189303D01*
G01X194487Y33630D02*
X196570Y38630D01*
X198653Y33630D01*
G01X197903Y35380D02*
X195237D01*
G01X200337Y33630D02*
Y38630D01*
X202003D01*
X202670Y38380D01*
X203170Y38047D01*
X203587Y37547D01*
X203920Y36963D01*
X204003Y36130D01*
X203920Y35297D01*
X203587Y34713D01*
X203170Y34213D01*
X202670Y33880D01*
X202003Y33630D01*
X200337D01*
G01X211870Y33463D02*
X214870Y38630D01*
G01X217387Y33630D02*
Y38630D01*
X220553D01*
G01X219387Y36213D02*
X217387D01*
G01X224570Y36963D02*
Y33630D01*
G01Y38297D02*
X224403Y38380D01*
Y38547D01*
X224570Y38630D01*
X224737Y38547D01*
Y38380D01*
X224570Y38297D01*
G01X231670Y38630D02*
Y33630D01*
G01Y34380D02*
X231337Y33963D01*
X230837Y33713D01*
X230253Y33630D01*
X229587Y33797D01*
X229087Y34213D01*
X228753Y34713D01*
X228670Y35297D01*
X228753Y35880D01*
X229087Y36380D01*
X229587Y36797D01*
X230253Y36963D01*
X230837Y36880D01*
X231253Y36713D01*
X231670Y36380D01*
G01X234353Y36963D02*
Y34630D01*
X234687Y34047D01*
X235187Y33713D01*
X235770Y33630D01*
X236353Y33713D01*
X236853Y34047D01*
X237187Y34630D01*
G01Y33630D02*
Y36963D01*
G01X242703Y36547D02*
X242120Y36880D01*
X241620Y36963D01*
X240953Y36797D01*
X240453Y36463D01*
X240120Y35880D01*
X240037Y35297D01*
X240120Y34713D01*
X240453Y34213D01*
X240953Y33797D01*
X241620Y33630D01*
X242203Y33797D01*
X242703Y34130D01*
G01X246970Y36963D02*
Y33630D01*
G01Y38297D02*
X246803Y38380D01*
Y38547D01*
X246970Y38630D01*
X247137Y38547D01*
Y38380D01*
X246970Y38297D01*
G01X254070Y33630D02*
Y36963D01*
G01Y36380D02*
X253737Y36713D01*
X253237Y36880D01*
X252653Y36963D01*
X252070Y36797D01*
X251570Y36463D01*
X251237Y35963D01*
X251070Y35297D01*
X251237Y34630D01*
X251570Y34130D01*
X252070Y33797D01*
X252653Y33630D01*
X253237Y33713D01*
X253737Y33963D01*
X254070Y34297D01*
G01X258170Y33630D02*
Y38630D01*
G01X112743Y42673D02*
X111910Y43507D01*
X111493Y44340D01*
Y47673D01*
X111910Y48507D01*
X112743Y49340D01*
G01X116260Y44340D02*
Y47673D01*
G01Y46757D02*
X116510Y47173D01*
X116927Y47507D01*
X117510Y47673D01*
X118093Y47507D01*
X118510Y47173D01*
X118760Y46757D01*
Y44340D01*
G01Y46757D02*
X119010Y47173D01*
X119427Y47507D01*
X120010Y47673D01*
X120593Y47507D01*
X121010Y47173D01*
X121260Y46673D01*
Y44340D01*
G01X123110Y46590D02*
X125777D01*
X125527Y47173D01*
X125110Y47507D01*
X124527Y47673D01*
X123943Y47590D01*
X123443Y47340D01*
X123110Y46757D01*
X122943Y46257D01*
Y45757D01*
X123110Y45257D01*
X123527Y44757D01*
X124027Y44423D01*
X124610Y44340D01*
X125193Y44507D01*
X125777Y45007D01*
G01X131460Y44340D02*
Y47673D01*
G01Y47090D02*
X131127Y47423D01*
X130627Y47590D01*
X130043Y47673D01*
X129460Y47507D01*
X128960Y47173D01*
X128627Y46673D01*
X128460Y46007D01*
X128627Y45340D01*
X128960Y44840D01*
X129460Y44507D01*
X130043Y44340D01*
X130627Y44423D01*
X131127Y44673D01*
X131460Y45007D01*
G01X134310Y44923D02*
X134727Y44590D01*
X135310Y44340D01*
X135810D01*
X136310Y44507D01*
X136643Y44757D01*
X136810Y45090D01*
X136727Y45590D01*
X136393Y45840D01*
X134893Y46340D01*
X134560Y46923D01*
X134727Y47340D01*
X135060Y47590D01*
X135560Y47673D01*
X136060Y47590D01*
X136560Y47340D01*
G01X139743Y47673D02*
Y45340D01*
X140077Y44757D01*
X140577Y44423D01*
X141160Y44340D01*
X141743Y44423D01*
X142243Y44757D01*
X142577Y45340D01*
G01Y44340D02*
Y47673D01*
G01X145593Y44340D02*
Y47673D01*
G01Y47007D02*
X146010Y47340D01*
X146427Y47590D01*
X147010Y47673D01*
X147427Y47590D01*
X147927Y47340D01*
G01X151110Y46590D02*
X153777D01*
X153527Y47173D01*
X153110Y47507D01*
X152527Y47673D01*
X151943Y47590D01*
X151443Y47340D01*
X151110Y46757D01*
X150943Y46257D01*
Y45757D01*
X151110Y45257D01*
X151527Y44757D01*
X152027Y44423D01*
X152610Y44340D01*
X153193Y44507D01*
X153777Y45007D01*
G01X163560Y49340D02*
Y44340D01*
G01X162393Y47673D02*
X164727D01*
G01X169160Y44340D02*
X168660Y44423D01*
X168160Y44757D01*
X167827Y45340D01*
X167660Y46007D01*
X167827Y46673D01*
X168160Y47257D01*
X168660Y47590D01*
X169160Y47673D01*
X169660Y47590D01*
X170160Y47257D01*
X170493Y46673D01*
X170577Y46007D01*
X170493Y45340D01*
X170160Y44757D01*
X169660Y44423D01*
X169160Y44340D01*
G01X173260Y42673D02*
Y47673D01*
G01Y46923D02*
X173677Y47340D01*
X174093Y47590D01*
X174760Y47673D01*
X175343Y47590D01*
X175927Y47173D01*
X176177Y46590D01*
X176260Y46007D01*
X176177Y45423D01*
X175927Y44840D01*
X175427Y44507D01*
X174760Y44340D01*
X174177Y44423D01*
X173593Y44673D01*
X173260Y45007D01*
G01X184710Y44923D02*
X185127Y44590D01*
X185710Y44340D01*
X186210D01*
X186710Y44507D01*
X187043Y44757D01*
X187210Y45090D01*
X187127Y45590D01*
X186793Y45840D01*
X185293Y46340D01*
X184960Y46923D01*
X185127Y47340D01*
X185460Y47590D01*
X185960Y47673D01*
X186460Y47590D01*
X186960Y47340D01*
G01X191560Y47673D02*
Y44340D01*
G01Y49007D02*
X191393Y49090D01*
Y49257D01*
X191560Y49340D01*
X191727Y49257D01*
Y49090D01*
X191560Y49007D01*
G01X195910Y47673D02*
X198410D01*
X195910Y44340D01*
X198410D01*
G01X201510Y46590D02*
X204177D01*
X203927Y47173D01*
X203510Y47507D01*
X202927Y47673D01*
X202343Y47590D01*
X201843Y47340D01*
X201510Y46757D01*
X201343Y46257D01*
Y45757D01*
X201510Y45257D01*
X201927Y44757D01*
X202427Y44423D01*
X203010Y44340D01*
X203593Y44507D01*
X204177Y45007D01*
G01X213960Y44340D02*
X213460Y44423D01*
X212960Y44757D01*
X212627Y45340D01*
X212460Y46007D01*
X212627Y46673D01*
X212960Y47257D01*
X213460Y47590D01*
X213960Y47673D01*
X214460Y47590D01*
X214960Y47257D01*
X215293Y46673D01*
X215377Y46007D01*
X215293Y45340D01*
X214960Y44757D01*
X214460Y44423D01*
X213960Y44340D01*
G01X219060D02*
Y48590D01*
X219227Y49007D01*
X219560Y49257D01*
X220060Y49340D01*
X220560Y49173D01*
X220810Y48757D01*
G01X219810Y47340D02*
X218143D01*
G01X229093Y44340D02*
Y49340D01*
X231093D01*
X231760Y49090D01*
X232260Y48507D01*
X232427Y47840D01*
X232260Y47173D01*
X231843Y46673D01*
X231093Y46423D01*
X229093D01*
G01X234277Y44340D02*
X236360Y49340D01*
X238443Y44340D01*
G01X237693Y46090D02*
X235027D01*
G01X240127Y44340D02*
Y49340D01*
X241793D01*
X242460Y49090D01*
X242960Y48757D01*
X243377Y48257D01*
X243710Y47673D01*
X243793Y46840D01*
X243710Y46007D01*
X243377Y45423D01*
X242960Y44923D01*
X242460Y44590D01*
X241793Y44340D01*
X240127D01*
G01X251660Y44173D02*
X254660Y49340D01*
G01X103500Y-9500D02*
X694500D01*
G01X103500Y60500D02*
X694500D01*
G01X105000Y364500D02*
X694500D01*
G01X103500Y449000D02*
X694500D01*
G01X104000Y464000D02*
X694500D01*
G01X103500Y424000D02*
X694500D01*
G01X103500Y614000D02*
X694500D01*
G01X103500Y584000D02*
X694500D01*
G01X103500Y629000D02*
X694500D01*
G01X111843Y639590D02*
Y644590D01*
X115677Y639590D01*
Y644590D01*
G01X119360Y639590D02*
X118860Y639673D01*
X118360Y640007D01*
X118027Y640590D01*
X117860Y641257D01*
X118027Y641923D01*
X118360Y642507D01*
X118860Y642840D01*
X119360Y642923D01*
X119860Y642840D01*
X120360Y642507D01*
X120693Y641923D01*
X120777Y641257D01*
X120693Y640590D01*
X120360Y640007D01*
X119860Y639673D01*
X119360Y639590D01*
G01X123543D02*
Y642923D01*
G01Y642090D02*
X123877Y642507D01*
X124377Y642840D01*
X125043Y642923D01*
X125627Y642840D01*
X126127Y642507D01*
X126377Y641923D01*
Y639590D01*
G01X129477Y641257D02*
X131643D01*
G01X135660Y639590D02*
Y643840D01*
X135827Y644257D01*
X136160Y644507D01*
X136660Y644590D01*
X137160Y644423D01*
X137410Y644007D01*
G01X136410Y642590D02*
X134743D01*
G01X140343Y642923D02*
Y640590D01*
X140677Y640007D01*
X141177Y639673D01*
X141760Y639590D01*
X142343Y639673D01*
X142843Y640007D01*
X143177Y640590D01*
G01Y639590D02*
Y642923D01*
G01X145943Y639590D02*
Y642923D01*
G01Y642090D02*
X146277Y642507D01*
X146777Y642840D01*
X147443Y642923D01*
X148027Y642840D01*
X148527Y642507D01*
X148777Y641923D01*
Y639590D01*
G01X154293Y642507D02*
X153710Y642840D01*
X153210Y642923D01*
X152543Y642757D01*
X152043Y642423D01*
X151710Y641840D01*
X151627Y641257D01*
X151710Y640673D01*
X152043Y640173D01*
X152543Y639757D01*
X153210Y639590D01*
X153793Y639757D01*
X154293Y640090D01*
G01X158560Y644590D02*
Y639590D01*
G01X157393Y642923D02*
X159727D01*
G01X164160D02*
Y639590D01*
G01Y644257D02*
X163993Y644340D01*
Y644507D01*
X164160Y644590D01*
X164327Y644507D01*
Y644340D01*
X164160Y644257D01*
G01X169760Y639590D02*
X169260Y639673D01*
X168760Y640007D01*
X168427Y640590D01*
X168260Y641257D01*
X168427Y641923D01*
X168760Y642507D01*
X169260Y642840D01*
X169760Y642923D01*
X170260Y642840D01*
X170760Y642507D01*
X171093Y641923D01*
X171177Y641257D01*
X171093Y640590D01*
X170760Y640007D01*
X170260Y639673D01*
X169760Y639590D01*
G01X173943D02*
Y642923D01*
G01Y642090D02*
X174277Y642507D01*
X174777Y642840D01*
X175443Y642923D01*
X176027Y642840D01*
X176527Y642507D01*
X176777Y641923D01*
Y639590D01*
G01X182460D02*
Y642923D01*
G01Y642340D02*
X182127Y642673D01*
X181627Y642840D01*
X181043Y642923D01*
X180460Y642757D01*
X179960Y642423D01*
X179627Y641923D01*
X179460Y641257D01*
X179627Y640590D01*
X179960Y640090D01*
X180460Y639757D01*
X181043Y639590D01*
X181627Y639673D01*
X182127Y639923D01*
X182460Y640257D01*
G01X186560Y639590D02*
Y644590D01*
G01X196260Y637923D02*
Y642923D01*
G01Y642173D02*
X196677Y642590D01*
X197093Y642840D01*
X197760Y642923D01*
X198343Y642840D01*
X198927Y642423D01*
X199177Y641840D01*
X199260Y641257D01*
X199177Y640673D01*
X198927Y640090D01*
X198427Y639757D01*
X197760Y639590D01*
X197177Y639673D01*
X196593Y639923D01*
X196260Y640257D01*
G01X204860Y639590D02*
Y642923D01*
G01Y642340D02*
X204527Y642673D01*
X204027Y642840D01*
X203443Y642923D01*
X202860Y642757D01*
X202360Y642423D01*
X202027Y641923D01*
X201860Y641257D01*
X202027Y640590D01*
X202360Y640090D01*
X202860Y639757D01*
X203443Y639590D01*
X204027Y639673D01*
X204527Y639923D01*
X204860Y640257D01*
G01X210460Y644590D02*
Y639590D01*
G01Y640340D02*
X210127Y639923D01*
X209627Y639673D01*
X209043Y639590D01*
X208377Y639757D01*
X207877Y640173D01*
X207543Y640673D01*
X207460Y641257D01*
X207543Y641840D01*
X207877Y642340D01*
X208377Y642757D01*
X209043Y642923D01*
X209627Y642840D01*
X210043Y642673D01*
X210460Y642340D01*
G01X67000Y725433D02*
X66833Y725517D01*
Y725683D01*
X67000Y725767D01*
X67167Y725683D01*
Y725517D01*
X67000Y725433D01*
G01Y734433D02*
X66833Y734517D01*
Y734683D01*
X67000Y734767D01*
X67167Y734683D01*
Y734517D01*
X67000Y734433D01*
G01Y743433D02*
X66833Y743517D01*
Y743683D01*
X67000Y743767D01*
X67167Y743683D01*
Y743517D01*
X67000Y743433D01*
G01Y752433D02*
X66833Y752517D01*
Y752683D01*
X67000Y752767D01*
X67167Y752683D01*
Y752517D01*
X67000Y752433D01*
G01Y761433D02*
X66833Y761517D01*
Y761683D01*
X67000Y761767D01*
X67167Y761683D01*
Y761517D01*
X67000Y761433D01*
G01Y770433D02*
X66833Y770517D01*
Y770683D01*
X67000Y770767D01*
X67167Y770683D01*
Y770517D01*
X67000Y770433D01*
G01X71000Y729600D02*
X73000D01*
G01X72000D02*
Y724600D01*
G01X71000D02*
X73000D01*
G01X75933D02*
Y729600D01*
X77933D01*
X78600Y729350D01*
X79100Y728767D01*
X79267Y728100D01*
X79100Y727433D01*
X78683Y726933D01*
X77933Y726683D01*
X75933D01*
G01X85033Y729183D02*
X84533Y729433D01*
X83950Y729600D01*
X83283D01*
X82533Y729350D01*
X81950Y728933D01*
X81533Y728433D01*
X81200Y727600D01*
X81117Y726850D01*
X81283Y726100D01*
X81533Y725600D01*
X82033Y725100D01*
X82617Y724767D01*
X83200Y724600D01*
X83783D01*
X84367Y724767D01*
X84867Y725017D01*
X85283Y725350D01*
G01X87717Y726267D02*
X89883D01*
G01X92733Y729600D02*
Y724600D01*
X96067D01*
G01X98917Y726267D02*
X101083D01*
G01X105600Y724600D02*
Y729600D01*
X104600Y728600D01*
G01Y724600D02*
X106600D01*
G01X111200Y729600D02*
X110533Y729433D01*
X110033Y729017D01*
X109700Y728517D01*
X109450Y727850D01*
X109367Y727100D01*
X109450Y726350D01*
X109700Y725683D01*
X110033Y725183D01*
X110533Y724767D01*
X111200Y724600D01*
X111867Y724767D01*
X112367Y725183D01*
X112700Y725683D01*
X112950Y726350D01*
X113033Y727100D01*
X112950Y727850D01*
X112700Y728517D01*
X112367Y729017D01*
X111867Y729433D01*
X111200Y729600D01*
G01X115383Y725183D02*
X115967Y724767D01*
X116633Y724600D01*
X117300Y724767D01*
X117883Y725267D01*
X118300Y726017D01*
X118467Y726767D01*
Y727683D01*
X118300Y728433D01*
X117883Y729100D01*
X117383Y729433D01*
X116800Y729600D01*
X116133Y729433D01*
X115633Y729100D01*
X115300Y728600D01*
X115133Y727933D01*
X115300Y727350D01*
X115717Y726767D01*
X116217Y726433D01*
X116800Y726350D01*
X117467Y726517D01*
X117967Y726933D01*
X118467Y727683D01*
G01X126250Y725267D02*
X126917Y724850D01*
X127667Y724600D01*
X128333D01*
X129000Y724850D01*
X129500Y725267D01*
X129750Y725850D01*
X129583Y726433D01*
X129167Y726933D01*
X128417Y727267D01*
X127417Y727433D01*
X126833Y727767D01*
X126583Y728350D01*
X126750Y728933D01*
X127167Y729350D01*
X127750Y729600D01*
X128333D01*
X128917Y729433D01*
X129417Y729017D01*
G01X132100Y722933D02*
Y727933D01*
G01Y727183D02*
X132517Y727600D01*
X132933Y727850D01*
X133600Y727933D01*
X134183Y727850D01*
X134767Y727433D01*
X135017Y726850D01*
X135100Y726267D01*
X135017Y725683D01*
X134767Y725100D01*
X134267Y724767D01*
X133600Y724600D01*
X133017Y724683D01*
X132433Y724933D01*
X132100Y725267D01*
G01X137950Y726850D02*
X140617D01*
X140367Y727433D01*
X139950Y727767D01*
X139367Y727933D01*
X138783Y727850D01*
X138283Y727600D01*
X137950Y727017D01*
X137783Y726517D01*
Y726017D01*
X137950Y725517D01*
X138367Y725017D01*
X138867Y724683D01*
X139450Y724600D01*
X140033Y724767D01*
X140617Y725267D01*
G01X146133Y727517D02*
X145550Y727850D01*
X145050Y727933D01*
X144383Y727767D01*
X143883Y727433D01*
X143550Y726850D01*
X143467Y726267D01*
X143550Y725683D01*
X143883Y725183D01*
X144383Y724767D01*
X145050Y724600D01*
X145633Y724767D01*
X146133Y725100D01*
G01X150400Y727933D02*
Y724600D01*
G01Y729267D02*
X150233Y729350D01*
Y729517D01*
X150400Y729600D01*
X150567Y729517D01*
Y729350D01*
X150400Y729267D01*
G01X155500Y724600D02*
Y728850D01*
X155667Y729267D01*
X156000Y729517D01*
X156500Y729600D01*
X157000Y729433D01*
X157250Y729017D01*
G01X156250Y727600D02*
X154583D01*
G01X161600Y727933D02*
Y724600D01*
G01Y729267D02*
X161433Y729350D01*
Y729517D01*
X161600Y729600D01*
X161767Y729517D01*
Y729350D01*
X161600Y729267D01*
G01X168533Y727517D02*
X167950Y727850D01*
X167450Y727933D01*
X166783Y727767D01*
X166283Y727433D01*
X165950Y726850D01*
X165867Y726267D01*
X165950Y725683D01*
X166283Y725183D01*
X166783Y724767D01*
X167450Y724600D01*
X168033Y724767D01*
X168533Y725100D01*
G01X174300Y724600D02*
Y727933D01*
G01Y727350D02*
X173967Y727683D01*
X173467Y727850D01*
X172883Y727933D01*
X172300Y727767D01*
X171800Y727433D01*
X171467Y726933D01*
X171300Y726267D01*
X171467Y725600D01*
X171800Y725100D01*
X172300Y724767D01*
X172883Y724600D01*
X173467Y724683D01*
X173967Y724933D01*
X174300Y725267D01*
G01X178400Y729600D02*
Y724600D01*
G01X177233Y727933D02*
X179567D01*
G01X184000D02*
Y724600D01*
G01Y729267D02*
X183833Y729350D01*
Y729517D01*
X184000Y729600D01*
X184167Y729517D01*
Y729350D01*
X184000Y729267D01*
G01X189600Y724600D02*
X189100Y724683D01*
X188600Y725017D01*
X188267Y725600D01*
X188100Y726267D01*
X188267Y726933D01*
X188600Y727517D01*
X189100Y727850D01*
X189600Y727933D01*
X190100Y727850D01*
X190600Y727517D01*
X190933Y726933D01*
X191017Y726267D01*
X190933Y725600D01*
X190600Y725017D01*
X190100Y724683D01*
X189600Y724600D01*
G01X193783D02*
Y727933D01*
G01Y727100D02*
X194117Y727517D01*
X194617Y727850D01*
X195283Y727933D01*
X195867Y727850D01*
X196367Y727517D01*
X196617Y726933D01*
Y724600D01*
G01X205900D02*
Y728850D01*
X206067Y729267D01*
X206400Y729517D01*
X206900Y729600D01*
X207400Y729433D01*
X207650Y729017D01*
G01X206650Y727600D02*
X204983D01*
G01X212000Y724600D02*
X211500Y724683D01*
X211000Y725017D01*
X210667Y725600D01*
X210500Y726267D01*
X210667Y726933D01*
X211000Y727517D01*
X211500Y727850D01*
X212000Y727933D01*
X212500Y727850D01*
X213000Y727517D01*
X213333Y726933D01*
X213417Y726267D01*
X213333Y725600D01*
X213000Y725017D01*
X212500Y724683D01*
X212000Y724600D01*
G01X216433D02*
Y727933D01*
G01Y727267D02*
X216850Y727600D01*
X217267Y727850D01*
X217850Y727933D01*
X218267Y727850D01*
X218767Y727600D01*
G01X227133Y724600D02*
Y729600D01*
X229217D01*
X229883Y729350D01*
X230300Y729017D01*
X230467Y728350D01*
X230300Y727683D01*
X229800Y727267D01*
X229217Y727017D01*
X227133D01*
G01X229217D02*
X230467Y724600D01*
G01X233150Y726850D02*
X235817D01*
X235567Y727433D01*
X235150Y727767D01*
X234567Y727933D01*
X233983Y727850D01*
X233483Y727600D01*
X233150Y727017D01*
X232983Y726517D01*
Y726017D01*
X233150Y725517D01*
X233567Y725017D01*
X234067Y724683D01*
X234650Y724600D01*
X235233Y724767D01*
X235817Y725267D01*
G01X238750Y725183D02*
X239167Y724850D01*
X239750Y724600D01*
X240250D01*
X240750Y724767D01*
X241083Y725017D01*
X241250Y725350D01*
X241167Y725850D01*
X240833Y726100D01*
X239333Y726600D01*
X239000Y727183D01*
X239167Y727600D01*
X239500Y727850D01*
X240000Y727933D01*
X240500Y727850D01*
X241000Y727600D01*
G01X245600Y727933D02*
Y724600D01*
G01Y729267D02*
X245433Y729350D01*
Y729517D01*
X245600Y729600D01*
X245767Y729517D01*
Y729350D01*
X245600Y729267D01*
G01X249783Y724600D02*
Y727933D01*
G01Y727100D02*
X250117Y727517D01*
X250617Y727850D01*
X251283Y727933D01*
X251867Y727850D01*
X252367Y727517D01*
X252617Y726933D01*
Y724600D01*
G01X261400Y729600D02*
X263400D01*
G01X262400D02*
Y724600D01*
G01X261400D02*
X263400D01*
G01X265500D02*
Y727933D01*
G01Y727017D02*
X265750Y727433D01*
X266167Y727767D01*
X266750Y727933D01*
X267333Y727767D01*
X267750Y727433D01*
X268000Y727017D01*
Y724600D01*
G01Y727017D02*
X268250Y727433D01*
X268667Y727767D01*
X269250Y727933D01*
X269833Y727767D01*
X270250Y727433D01*
X270500Y726933D01*
Y724600D01*
G01X272100Y722933D02*
Y727933D01*
G01Y727183D02*
X272517Y727600D01*
X272933Y727850D01*
X273600Y727933D01*
X274183Y727850D01*
X274767Y727433D01*
X275017Y726850D01*
X275100Y726267D01*
X275017Y725683D01*
X274767Y725100D01*
X274267Y724767D01*
X273600Y724600D01*
X273017Y724683D01*
X272433Y724933D01*
X272100Y725267D01*
G01X278033Y724600D02*
Y727933D01*
G01Y727267D02*
X278450Y727600D01*
X278867Y727850D01*
X279450Y727933D01*
X279867Y727850D01*
X280367Y727600D01*
G01X283550Y726850D02*
X286217D01*
X285967Y727433D01*
X285550Y727767D01*
X284967Y727933D01*
X284383Y727850D01*
X283883Y727600D01*
X283550Y727017D01*
X283383Y726517D01*
Y726017D01*
X283550Y725517D01*
X283967Y725017D01*
X284467Y724683D01*
X285050Y724600D01*
X285633Y724767D01*
X286217Y725267D01*
G01X289233Y723350D02*
X289817Y723017D01*
X290483Y722933D01*
X291067Y723017D01*
X291567Y723433D01*
X291900Y724017D01*
Y727933D01*
G01Y727267D02*
X291567Y727600D01*
X291067Y727850D01*
X290483Y727933D01*
X289817Y727767D01*
X289400Y727433D01*
X289067Y726850D01*
X288900Y726267D01*
X288983Y725767D01*
X289317Y725183D01*
X289817Y724767D01*
X290483Y724600D01*
X290983Y724683D01*
X291567Y725017D01*
X291900Y725350D01*
G01X294583Y724600D02*
Y727933D01*
G01Y727100D02*
X294917Y727517D01*
X295417Y727850D01*
X296083Y727933D01*
X296667Y727850D01*
X297167Y727517D01*
X297417Y726933D01*
Y724600D01*
G01X303100D02*
Y727933D01*
G01Y727350D02*
X302767Y727683D01*
X302267Y727850D01*
X301683Y727933D01*
X301100Y727767D01*
X300600Y727433D01*
X300267Y726933D01*
X300100Y726267D01*
X300267Y725600D01*
X300600Y725100D01*
X301100Y724767D01*
X301683Y724600D01*
X302267Y724683D01*
X302767Y724933D01*
X303100Y725267D01*
G01X307200Y729600D02*
Y724600D01*
G01X306033Y727933D02*
X308367D01*
G01X311550Y726850D02*
X314217D01*
X313967Y727433D01*
X313550Y727767D01*
X312967Y727933D01*
X312383Y727850D01*
X311883Y727600D01*
X311550Y727017D01*
X311383Y726517D01*
Y726017D01*
X311550Y725517D01*
X311967Y725017D01*
X312467Y724683D01*
X313050Y724600D01*
X313633Y724767D01*
X314217Y725267D01*
G01X319900Y729600D02*
Y724600D01*
G01Y725350D02*
X319567Y724933D01*
X319067Y724683D01*
X318483Y724600D01*
X317817Y724767D01*
X317317Y725183D01*
X316983Y725683D01*
X316900Y726267D01*
X316983Y726850D01*
X317317Y727350D01*
X317817Y727767D01*
X318483Y727933D01*
X319067Y727850D01*
X319483Y727683D01*
X319900Y727350D01*
G01X328017Y724600D02*
Y729600D01*
X331183D01*
G01X330017Y727183D02*
X328017D01*
G01X336700Y724600D02*
Y727933D01*
G01Y727350D02*
X336367Y727683D01*
X335867Y727850D01*
X335283Y727933D01*
X334700Y727767D01*
X334200Y727433D01*
X333867Y726933D01*
X333700Y726267D01*
X333867Y725600D01*
X334200Y725100D01*
X334700Y724767D01*
X335283Y724600D01*
X335867Y724683D01*
X336367Y724933D01*
X336700Y725267D01*
G01X339300Y724600D02*
Y729600D01*
G01Y727100D02*
X339717Y727600D01*
X340217Y727850D01*
X340717Y727933D01*
X341467Y727767D01*
X341967Y727433D01*
X342300Y726850D01*
Y726183D01*
X342133Y725517D01*
X341800Y725017D01*
X341217Y724683D01*
X340717Y724600D01*
X340217Y724683D01*
X339717Y724933D01*
X339300Y725350D01*
G01X345233Y724600D02*
Y727933D01*
G01Y727267D02*
X345650Y727600D01*
X346067Y727850D01*
X346650Y727933D01*
X347067Y727850D01*
X347567Y727600D01*
G01X352000Y727933D02*
Y724600D01*
G01Y729267D02*
X351833Y729350D01*
Y729517D01*
X352000Y729600D01*
X352167Y729517D01*
Y729350D01*
X352000Y729267D01*
G01X358933Y727517D02*
X358350Y727850D01*
X357850Y727933D01*
X357183Y727767D01*
X356683Y727433D01*
X356350Y726850D01*
X356267Y726267D01*
X356350Y725683D01*
X356683Y725183D01*
X357183Y724767D01*
X357850Y724600D01*
X358433Y724767D01*
X358933Y725100D01*
G01X362783Y722933D02*
X361950Y723767D01*
X361533Y724600D01*
Y727933D01*
X361950Y728767D01*
X362783Y729600D01*
G01X367133Y724600D02*
Y729600D01*
X369133D01*
X369800Y729350D01*
X370300Y728767D01*
X370467Y728100D01*
X370300Y727433D01*
X369883Y726933D01*
X369133Y726683D01*
X367133D01*
G01X373233Y724600D02*
Y727933D01*
G01Y727267D02*
X373650Y727600D01*
X374067Y727850D01*
X374650Y727933D01*
X375067Y727850D01*
X375567Y727600D01*
G01X378750Y726850D02*
X381417D01*
X381167Y727433D01*
X380750Y727767D01*
X380167Y727933D01*
X379583Y727850D01*
X379083Y727600D01*
X378750Y727017D01*
X378583Y726517D01*
Y726017D01*
X378750Y725517D01*
X379167Y725017D01*
X379667Y724683D01*
X380250Y724600D01*
X380833Y724767D01*
X381417Y725267D01*
G01X384100Y722933D02*
Y727933D01*
G01Y727183D02*
X384517Y727600D01*
X384933Y727850D01*
X385600Y727933D01*
X386183Y727850D01*
X386767Y727433D01*
X387017Y726850D01*
X387100Y726267D01*
X387017Y725683D01*
X386767Y725100D01*
X386267Y724767D01*
X385600Y724600D01*
X385017Y724683D01*
X384433Y724933D01*
X384100Y725267D01*
G01X390033Y724600D02*
Y727933D01*
G01Y727267D02*
X390450Y727600D01*
X390867Y727850D01*
X391450Y727933D01*
X391867Y727850D01*
X392367Y727600D01*
G01X395550Y726850D02*
X398217D01*
X397967Y727433D01*
X397550Y727767D01*
X396967Y727933D01*
X396383Y727850D01*
X395883Y727600D01*
X395550Y727017D01*
X395383Y726517D01*
Y726017D01*
X395550Y725517D01*
X395967Y725017D01*
X396467Y724683D01*
X397050Y724600D01*
X397633Y724767D01*
X398217Y725267D01*
G01X401233Y723350D02*
X401817Y723017D01*
X402483Y722933D01*
X403067Y723017D01*
X403567Y723433D01*
X403900Y724017D01*
Y727933D01*
G01Y727267D02*
X403567Y727600D01*
X403067Y727850D01*
X402483Y727933D01*
X401817Y727767D01*
X401400Y727433D01*
X401067Y726850D01*
X400900Y726267D01*
X400983Y725767D01*
X401317Y725183D01*
X401817Y724767D01*
X402483Y724600D01*
X402983Y724683D01*
X403567Y725017D01*
X403900Y725350D01*
G01X408417Y722933D02*
X409250Y723767D01*
X409667Y724600D01*
Y727933D01*
X409250Y728767D01*
X408417Y729600D01*
G01X418700Y724600D02*
Y728850D01*
X418867Y729267D01*
X419200Y729517D01*
X419700Y729600D01*
X420200Y729433D01*
X420450Y729017D01*
G01X419450Y727600D02*
X417783D01*
G01X424800Y724600D02*
X424300Y724683D01*
X423800Y725017D01*
X423467Y725600D01*
X423300Y726267D01*
X423467Y726933D01*
X423800Y727517D01*
X424300Y727850D01*
X424800Y727933D01*
X425300Y727850D01*
X425800Y727517D01*
X426133Y726933D01*
X426217Y726267D01*
X426133Y725600D01*
X425800Y725017D01*
X425300Y724683D01*
X424800Y724600D01*
G01X429233D02*
Y727933D01*
G01Y727267D02*
X429650Y727600D01*
X430067Y727850D01*
X430650Y727933D01*
X431067Y727850D01*
X431567Y727600D01*
G01X439433Y724600D02*
Y729600D01*
X441600Y725433D01*
X443767Y729600D01*
Y724600D01*
G01X445783Y727933D02*
Y725600D01*
X446117Y725017D01*
X446617Y724683D01*
X447200Y724600D01*
X447783Y724683D01*
X448283Y725017D01*
X448617Y725600D01*
G01Y724600D02*
Y727933D01*
G01X452800Y724600D02*
Y729600D01*
G01X458400D02*
Y724600D01*
G01X457233Y727933D02*
X459567D01*
G01X464000D02*
Y724600D01*
G01Y729267D02*
X463833Y729350D01*
Y729517D01*
X464000Y729600D01*
X464167Y729517D01*
Y729350D01*
X464000Y729267D01*
G01X469600Y724600D02*
Y729600D01*
G01X476700Y724600D02*
Y727933D01*
G01Y727350D02*
X476367Y727683D01*
X475867Y727850D01*
X475283Y727933D01*
X474700Y727767D01*
X474200Y727433D01*
X473867Y726933D01*
X473700Y726267D01*
X473867Y725600D01*
X474200Y725100D01*
X474700Y724767D01*
X475283Y724600D01*
X475867Y724683D01*
X476367Y724933D01*
X476700Y725267D01*
G01X479050Y723100D02*
X479550Y722933D01*
X480217Y723100D01*
X480633Y723433D01*
X480967Y723850D01*
X481467Y725183D01*
X482550Y727933D01*
G01X479883D02*
X481467Y725183D01*
G01X485150Y726850D02*
X487817D01*
X487567Y727433D01*
X487150Y727767D01*
X486567Y727933D01*
X485983Y727850D01*
X485483Y727600D01*
X485150Y727017D01*
X484983Y726517D01*
Y726017D01*
X485150Y725517D01*
X485567Y725017D01*
X486067Y724683D01*
X486650Y724600D01*
X487233Y724767D01*
X487817Y725267D01*
G01X490833Y724600D02*
Y727933D01*
G01Y727267D02*
X491250Y727600D01*
X491667Y727850D01*
X492250Y727933D01*
X492667Y727850D01*
X493167Y727600D01*
G01X501533Y724600D02*
Y729600D01*
X503533D01*
X504200Y729350D01*
X504700Y728767D01*
X504867Y728100D01*
X504700Y727433D01*
X504283Y726933D01*
X503533Y726683D01*
X501533D01*
G01X507633Y724600D02*
Y727933D01*
G01Y727267D02*
X508050Y727600D01*
X508467Y727850D01*
X509050Y727933D01*
X509467Y727850D01*
X509967Y727600D01*
G01X514400Y727933D02*
Y724600D01*
G01Y729267D02*
X514233Y729350D01*
Y729517D01*
X514400Y729600D01*
X514567Y729517D01*
Y729350D01*
X514400Y729267D01*
G01X518583Y724600D02*
Y727933D01*
G01Y727100D02*
X518917Y727517D01*
X519417Y727850D01*
X520083Y727933D01*
X520667Y727850D01*
X521167Y727517D01*
X521417Y726933D01*
Y724600D01*
G01X525600Y729600D02*
Y724600D01*
G01X524433Y727933D02*
X526767D01*
G01X529950Y726850D02*
X532617D01*
X532367Y727433D01*
X531950Y727767D01*
X531367Y727933D01*
X530783Y727850D01*
X530283Y727600D01*
X529950Y727017D01*
X529783Y726517D01*
Y726017D01*
X529950Y725517D01*
X530367Y725017D01*
X530867Y724683D01*
X531450Y724600D01*
X532033Y724767D01*
X532617Y725267D01*
G01X538300Y729600D02*
Y724600D01*
G01Y725350D02*
X537967Y724933D01*
X537467Y724683D01*
X536883Y724600D01*
X536217Y724767D01*
X535717Y725183D01*
X535383Y725683D01*
X535300Y726267D01*
X535383Y726850D01*
X535717Y727350D01*
X536217Y727767D01*
X536883Y727933D01*
X537467Y727850D01*
X537883Y727683D01*
X538300Y727350D01*
G01X548667Y727267D02*
X549000Y727517D01*
X549250Y727933D01*
X549417Y728517D01*
X549250Y729017D01*
X548917Y729350D01*
X548333Y729600D01*
X546083D01*
Y724600D01*
X548833D01*
X549417Y724933D01*
X549750Y725433D01*
X549917Y726017D01*
X549750Y726600D01*
X549250Y727100D01*
X548667Y727267D01*
X546083D01*
G01X553600Y724600D02*
X553100Y724683D01*
X552600Y725017D01*
X552267Y725600D01*
X552100Y726267D01*
X552267Y726933D01*
X552600Y727517D01*
X553100Y727850D01*
X553600Y727933D01*
X554100Y727850D01*
X554600Y727517D01*
X554933Y726933D01*
X555017Y726267D01*
X554933Y725600D01*
X554600Y725017D01*
X554100Y724683D01*
X553600Y724600D01*
G01X560700D02*
Y727933D01*
G01Y727350D02*
X560367Y727683D01*
X559867Y727850D01*
X559283Y727933D01*
X558700Y727767D01*
X558200Y727433D01*
X557867Y726933D01*
X557700Y726267D01*
X557867Y725600D01*
X558200Y725100D01*
X558700Y724767D01*
X559283Y724600D01*
X559867Y724683D01*
X560367Y724933D01*
X560700Y725267D01*
G01X563633Y724600D02*
Y727933D01*
G01Y727267D02*
X564050Y727600D01*
X564467Y727850D01*
X565050Y727933D01*
X565467Y727850D01*
X565967Y727600D01*
G01X571900Y729600D02*
Y724600D01*
G01Y725350D02*
X571567Y724933D01*
X571067Y724683D01*
X570483Y724600D01*
X569817Y724767D01*
X569317Y725183D01*
X568983Y725683D01*
X568900Y726267D01*
X568983Y726850D01*
X569317Y727350D01*
X569817Y727767D01*
X570483Y727933D01*
X571067Y727850D01*
X571483Y727683D01*
X571900Y727350D01*
G01X574750Y725183D02*
X575167Y724850D01*
X575750Y724600D01*
X576250D01*
X576750Y724767D01*
X577083Y725017D01*
X577250Y725350D01*
X577167Y725850D01*
X576833Y726100D01*
X575333Y726600D01*
X575000Y727183D01*
X575167Y727600D01*
X575500Y727850D01*
X576000Y727933D01*
X576500Y727850D01*
X577000Y727600D01*
G01X71000Y738600D02*
X73000D01*
G01X72000D02*
Y733600D01*
G01X71000D02*
X73000D01*
G01X75933D02*
Y738600D01*
X77933D01*
X78600Y738350D01*
X79100Y737767D01*
X79267Y737100D01*
X79100Y736433D01*
X78683Y735933D01*
X77933Y735683D01*
X75933D01*
G01X85033Y738183D02*
X84533Y738433D01*
X83950Y738600D01*
X83283D01*
X82533Y738350D01*
X81950Y737933D01*
X81533Y737433D01*
X81200Y736600D01*
X81117Y735850D01*
X81283Y735100D01*
X81533Y734600D01*
X82033Y734100D01*
X82617Y733767D01*
X83200Y733600D01*
X83783D01*
X84367Y733767D01*
X84867Y734017D01*
X85283Y734350D01*
G01X87717Y735267D02*
X89883D01*
G01X92233Y733600D02*
Y738600D01*
X94400Y734433D01*
X96567Y738600D01*
Y733600D01*
G01X98417D02*
Y738600D01*
X101583D01*
G01X100417Y736183D02*
X98417D01*
G01X104517Y735267D02*
X106683D01*
G01X111200Y733600D02*
Y738600D01*
X110200Y737600D01*
G01Y733600D02*
X112200D01*
G01X114967Y734350D02*
X115467Y733933D01*
X116050Y733683D01*
X116800Y733600D01*
X117550Y733767D01*
X118133Y734100D01*
X118550Y734683D01*
X118633Y735350D01*
X118467Y736017D01*
X118050Y736433D01*
X117467Y736767D01*
X116883Y736850D01*
X116300Y736767D01*
X115550Y736433D01*
X115800Y738600D01*
X118050D01*
G01X122400D02*
X121733Y738433D01*
X121233Y738017D01*
X120900Y737517D01*
X120650Y736850D01*
X120567Y736100D01*
X120650Y735350D01*
X120900Y734683D01*
X121233Y734183D01*
X121733Y733767D01*
X122400Y733600D01*
X123067Y733767D01*
X123567Y734183D01*
X123900Y734683D01*
X124150Y735350D01*
X124233Y736100D01*
X124150Y736850D01*
X123900Y737517D01*
X123567Y738017D01*
X123067Y738433D01*
X122400Y738600D01*
G01X131433Y733600D02*
Y738600D01*
X133600Y734433D01*
X135767Y738600D01*
Y733600D01*
G01X137950Y735850D02*
X140617D01*
X140367Y736433D01*
X139950Y736767D01*
X139367Y736933D01*
X138783Y736850D01*
X138283Y736600D01*
X137950Y736017D01*
X137783Y735517D01*
Y735017D01*
X137950Y734517D01*
X138367Y734017D01*
X138867Y733683D01*
X139450Y733600D01*
X140033Y733767D01*
X140617Y734267D01*
G01X144800Y738600D02*
Y733600D01*
G01X143633Y736933D02*
X145967D01*
G01X151900Y733600D02*
Y736933D01*
G01Y736350D02*
X151567Y736683D01*
X151067Y736850D01*
X150483Y736933D01*
X149900Y736767D01*
X149400Y736433D01*
X149067Y735933D01*
X148900Y735267D01*
X149067Y734600D01*
X149400Y734100D01*
X149900Y733767D01*
X150483Y733600D01*
X151067Y733683D01*
X151567Y733933D01*
X151900Y734267D01*
G01X156000Y733600D02*
Y738600D01*
G01X165617Y733600D02*
Y738600D01*
X168783D01*
G01X167617Y736183D02*
X165617D01*
G01X172800Y733600D02*
X172300Y733683D01*
X171800Y734017D01*
X171467Y734600D01*
X171300Y735267D01*
X171467Y735933D01*
X171800Y736517D01*
X172300Y736850D01*
X172800Y736933D01*
X173300Y736850D01*
X173800Y736517D01*
X174133Y735933D01*
X174217Y735267D01*
X174133Y734600D01*
X173800Y734017D01*
X173300Y733683D01*
X172800Y733600D01*
G01X178400Y736933D02*
Y733600D01*
G01Y738267D02*
X178233Y738350D01*
Y738517D01*
X178400Y738600D01*
X178567Y738517D01*
Y738350D01*
X178400Y738267D01*
G01X184000Y733600D02*
Y738600D01*
G01X194700Y733600D02*
Y737850D01*
X194867Y738267D01*
X195200Y738517D01*
X195700Y738600D01*
X196200Y738433D01*
X196450Y738017D01*
G01X195450Y736600D02*
X193783D01*
G01X200800Y733600D02*
X200300Y733683D01*
X199800Y734017D01*
X199467Y734600D01*
X199300Y735267D01*
X199467Y735933D01*
X199800Y736517D01*
X200300Y736850D01*
X200800Y736933D01*
X201300Y736850D01*
X201800Y736517D01*
X202133Y735933D01*
X202217Y735267D01*
X202133Y734600D01*
X201800Y734017D01*
X201300Y733683D01*
X200800Y733600D01*
G01X205233D02*
Y736933D01*
G01Y736267D02*
X205650Y736600D01*
X206067Y736850D01*
X206650Y736933D01*
X207067Y736850D01*
X207567Y736600D01*
G01X215933Y733600D02*
Y738600D01*
X217933D01*
X218600Y738350D01*
X219100Y737767D01*
X219267Y737100D01*
X219100Y736433D01*
X218683Y735933D01*
X217933Y735683D01*
X215933D01*
G01X222033Y733600D02*
Y736933D01*
G01Y736267D02*
X222450Y736600D01*
X222867Y736850D01*
X223450Y736933D01*
X223867Y736850D01*
X224367Y736600D01*
G01X228800Y736933D02*
Y733600D01*
G01Y738267D02*
X228633Y738350D01*
Y738517D01*
X228800Y738600D01*
X228967Y738517D01*
Y738350D01*
X228800Y738267D01*
G01X232983Y733600D02*
Y736933D01*
G01Y736100D02*
X233317Y736517D01*
X233817Y736850D01*
X234483Y736933D01*
X235067Y736850D01*
X235567Y736517D01*
X235817Y735933D01*
Y733600D01*
G01X240000Y738600D02*
Y733600D01*
G01X238833Y736933D02*
X241167D01*
G01X244350Y735850D02*
X247017D01*
X246767Y736433D01*
X246350Y736767D01*
X245767Y736933D01*
X245183Y736850D01*
X244683Y736600D01*
X244350Y736017D01*
X244183Y735517D01*
Y735017D01*
X244350Y734517D01*
X244767Y734017D01*
X245267Y733683D01*
X245850Y733600D01*
X246433Y733767D01*
X247017Y734267D01*
G01X252700Y738600D02*
Y733600D01*
G01Y734350D02*
X252367Y733933D01*
X251867Y733683D01*
X251283Y733600D01*
X250617Y733767D01*
X250117Y734183D01*
X249783Y734683D01*
X249700Y735267D01*
X249783Y735850D01*
X250117Y736350D01*
X250617Y736767D01*
X251283Y736933D01*
X251867Y736850D01*
X252283Y736683D01*
X252700Y736350D01*
G01X259900Y738600D02*
X261067Y733600D01*
X262400Y738600D01*
X263733Y733600D01*
X264900Y738600D01*
G01X268000Y736933D02*
Y733600D01*
G01Y738267D02*
X267833Y738350D01*
Y738517D01*
X268000Y738600D01*
X268167Y738517D01*
Y738350D01*
X268000Y738267D01*
G01X272433Y733600D02*
Y736933D01*
G01Y736267D02*
X272850Y736600D01*
X273267Y736850D01*
X273850Y736933D01*
X274267Y736850D01*
X274767Y736600D01*
G01X279200Y736933D02*
Y733600D01*
G01Y738267D02*
X279033Y738350D01*
Y738517D01*
X279200Y738600D01*
X279367Y738517D01*
Y738350D01*
X279200Y738267D01*
G01X283383Y733600D02*
Y736933D01*
G01Y736100D02*
X283717Y736517D01*
X284217Y736850D01*
X284883Y736933D01*
X285467Y736850D01*
X285967Y736517D01*
X286217Y735933D01*
Y733600D01*
G01X289233Y732350D02*
X289817Y732017D01*
X290483Y731933D01*
X291067Y732017D01*
X291567Y732433D01*
X291900Y733017D01*
Y736933D01*
G01Y736267D02*
X291567Y736600D01*
X291067Y736850D01*
X290483Y736933D01*
X289817Y736767D01*
X289400Y736433D01*
X289067Y735850D01*
X288900Y735267D01*
X288983Y734767D01*
X289317Y734183D01*
X289817Y733767D01*
X290483Y733600D01*
X290983Y733683D01*
X291567Y734017D01*
X291900Y734350D01*
G01X299517Y733600D02*
X301600Y738600D01*
X303683Y733600D01*
G01X302933Y735350D02*
X300267D01*
G01X305700Y731933D02*
Y736933D01*
G01Y736183D02*
X306117Y736600D01*
X306533Y736850D01*
X307200Y736933D01*
X307783Y736850D01*
X308367Y736433D01*
X308617Y735850D01*
X308700Y735267D01*
X308617Y734683D01*
X308367Y734100D01*
X307867Y733767D01*
X307200Y733600D01*
X306617Y733683D01*
X306033Y733933D01*
X305700Y734267D01*
G01X311300Y731933D02*
Y736933D01*
G01Y736183D02*
X311717Y736600D01*
X312133Y736850D01*
X312800Y736933D01*
X313383Y736850D01*
X313967Y736433D01*
X314217Y735850D01*
X314300Y735267D01*
X314217Y734683D01*
X313967Y734100D01*
X313467Y733767D01*
X312800Y733600D01*
X312217Y733683D01*
X311633Y733933D01*
X311300Y734267D01*
G01X318400Y733600D02*
Y738600D01*
G01X324000Y736933D02*
Y733600D01*
G01Y738267D02*
X323833Y738350D01*
Y738517D01*
X324000Y738600D01*
X324167Y738517D01*
Y738350D01*
X324000Y738267D01*
G01X330933Y736517D02*
X330350Y736850D01*
X329850Y736933D01*
X329183Y736767D01*
X328683Y736433D01*
X328350Y735850D01*
X328267Y735267D01*
X328350Y734683D01*
X328683Y734183D01*
X329183Y733767D01*
X329850Y733600D01*
X330433Y733767D01*
X330933Y734100D01*
G01X336700Y733600D02*
Y736933D01*
G01Y736350D02*
X336367Y736683D01*
X335867Y736850D01*
X335283Y736933D01*
X334700Y736767D01*
X334200Y736433D01*
X333867Y735933D01*
X333700Y735267D01*
X333867Y734600D01*
X334200Y734100D01*
X334700Y733767D01*
X335283Y733600D01*
X335867Y733683D01*
X336367Y733933D01*
X336700Y734267D01*
G01X340800Y738600D02*
Y733600D01*
G01X339633Y736933D02*
X341967D01*
G01X346400D02*
Y733600D01*
G01Y738267D02*
X346233Y738350D01*
Y738517D01*
X346400Y738600D01*
X346567Y738517D01*
Y738350D01*
X346400Y738267D01*
G01X352000Y733600D02*
X351500Y733683D01*
X351000Y734017D01*
X350667Y734600D01*
X350500Y735267D01*
X350667Y735933D01*
X351000Y736517D01*
X351500Y736850D01*
X352000Y736933D01*
X352500Y736850D01*
X353000Y736517D01*
X353333Y735933D01*
X353417Y735267D01*
X353333Y734600D01*
X353000Y734017D01*
X352500Y733683D01*
X352000Y733600D01*
G01X356183D02*
Y736933D01*
G01Y736100D02*
X356517Y736517D01*
X357017Y736850D01*
X357683Y736933D01*
X358267Y736850D01*
X358767Y736517D01*
X359017Y735933D01*
Y733600D01*
G01X361950Y734183D02*
X362367Y733850D01*
X362950Y733600D01*
X363450D01*
X363950Y733767D01*
X364283Y734017D01*
X364450Y734350D01*
X364367Y734850D01*
X364033Y735100D01*
X362533Y735600D01*
X362200Y736183D01*
X362367Y736600D01*
X362700Y736850D01*
X363200Y736933D01*
X363700Y736850D01*
X364200Y736600D01*
G01X71000Y747600D02*
X73000D01*
G01X72000D02*
Y742600D01*
G01X71000D02*
X73000D01*
G01X75933D02*
Y747600D01*
X77933D01*
X78600Y747350D01*
X79100Y746767D01*
X79267Y746100D01*
X79100Y745433D01*
X78683Y744933D01*
X77933Y744683D01*
X75933D01*
G01X85033Y747183D02*
X84533Y747433D01*
X83950Y747600D01*
X83283D01*
X82533Y747350D01*
X81950Y746933D01*
X81533Y746433D01*
X81200Y745600D01*
X81117Y744850D01*
X81283Y744100D01*
X81533Y743600D01*
X82033Y743100D01*
X82617Y742767D01*
X83200Y742600D01*
X83783D01*
X84367Y742767D01*
X84867Y743017D01*
X85283Y743350D01*
G01X87717Y744267D02*
X89883D01*
G01X95400Y742600D02*
Y747600D01*
X92317Y744017D01*
X96483D01*
G01X100000Y742600D02*
Y747600D01*
X99000Y746600D01*
G01Y742600D02*
X101000D01*
G01X105600Y747600D02*
X104933Y747433D01*
X104433Y747017D01*
X104100Y746517D01*
X103850Y745850D01*
X103767Y745100D01*
X103850Y744350D01*
X104100Y743683D01*
X104433Y743183D01*
X104933Y742767D01*
X105600Y742600D01*
X106267Y742767D01*
X106767Y743183D01*
X107100Y743683D01*
X107350Y744350D01*
X107433Y745100D01*
X107350Y745850D01*
X107100Y746517D01*
X106767Y747017D01*
X106267Y747433D01*
X105600Y747600D01*
G01X111200Y742600D02*
Y747600D01*
X110200Y746600D01*
G01Y742600D02*
X112200D01*
G01X120650Y743267D02*
X121317Y742850D01*
X122067Y742600D01*
X122733D01*
X123400Y742850D01*
X123900Y743267D01*
X124150Y743850D01*
X123983Y744433D01*
X123567Y744933D01*
X122817Y745267D01*
X121817Y745433D01*
X121233Y745767D01*
X120983Y746350D01*
X121150Y746933D01*
X121567Y747350D01*
X122150Y747600D01*
X122733D01*
X123317Y747433D01*
X123817Y747017D01*
G01X126500Y740933D02*
Y745933D01*
G01Y745183D02*
X126917Y745600D01*
X127333Y745850D01*
X128000Y745933D01*
X128583Y745850D01*
X129167Y745433D01*
X129417Y744850D01*
X129500Y744267D01*
X129417Y743683D01*
X129167Y743100D01*
X128667Y742767D01*
X128000Y742600D01*
X127417Y742683D01*
X126833Y742933D01*
X126500Y743267D01*
G01X132350Y744850D02*
X135017D01*
X134767Y745433D01*
X134350Y745767D01*
X133767Y745933D01*
X133183Y745850D01*
X132683Y745600D01*
X132350Y745017D01*
X132183Y744517D01*
Y744017D01*
X132350Y743517D01*
X132767Y743017D01*
X133267Y742683D01*
X133850Y742600D01*
X134433Y742767D01*
X135017Y743267D01*
G01X140533Y745517D02*
X139950Y745850D01*
X139450Y745933D01*
X138783Y745767D01*
X138283Y745433D01*
X137950Y744850D01*
X137867Y744267D01*
X137950Y743683D01*
X138283Y743183D01*
X138783Y742767D01*
X139450Y742600D01*
X140033Y742767D01*
X140533Y743100D01*
G01X144800Y745933D02*
Y742600D01*
G01Y747267D02*
X144633Y747350D01*
Y747517D01*
X144800Y747600D01*
X144967Y747517D01*
Y747350D01*
X144800Y747267D01*
G01X149900Y742600D02*
Y746850D01*
X150067Y747267D01*
X150400Y747517D01*
X150900Y747600D01*
X151400Y747433D01*
X151650Y747017D01*
G01X150650Y745600D02*
X148983D01*
G01X156000Y745933D02*
Y742600D01*
G01Y747267D02*
X155833Y747350D01*
Y747517D01*
X156000Y747600D01*
X156167Y747517D01*
Y747350D01*
X156000Y747267D01*
G01X162933Y745517D02*
X162350Y745850D01*
X161850Y745933D01*
X161183Y745767D01*
X160683Y745433D01*
X160350Y744850D01*
X160267Y744267D01*
X160350Y743683D01*
X160683Y743183D01*
X161183Y742767D01*
X161850Y742600D01*
X162433Y742767D01*
X162933Y743100D01*
G01X168700Y742600D02*
Y745933D01*
G01Y745350D02*
X168367Y745683D01*
X167867Y745850D01*
X167283Y745933D01*
X166700Y745767D01*
X166200Y745433D01*
X165867Y744933D01*
X165700Y744267D01*
X165867Y743600D01*
X166200Y743100D01*
X166700Y742767D01*
X167283Y742600D01*
X167867Y742683D01*
X168367Y742933D01*
X168700Y743267D01*
G01X172800Y747600D02*
Y742600D01*
G01X171633Y745933D02*
X173967D01*
G01X178400D02*
Y742600D01*
G01Y747267D02*
X178233Y747350D01*
Y747517D01*
X178400Y747600D01*
X178567Y747517D01*
Y747350D01*
X178400Y747267D01*
G01X184000Y742600D02*
X183500Y742683D01*
X183000Y743017D01*
X182667Y743600D01*
X182500Y744267D01*
X182667Y744933D01*
X183000Y745517D01*
X183500Y745850D01*
X184000Y745933D01*
X184500Y745850D01*
X185000Y745517D01*
X185333Y744933D01*
X185417Y744267D01*
X185333Y743600D01*
X185000Y743017D01*
X184500Y742683D01*
X184000Y742600D01*
G01X188183D02*
Y745933D01*
G01Y745100D02*
X188517Y745517D01*
X189017Y745850D01*
X189683Y745933D01*
X190267Y745850D01*
X190767Y745517D01*
X191017Y744933D01*
Y742600D01*
G01X200300D02*
Y746850D01*
X200467Y747267D01*
X200800Y747517D01*
X201300Y747600D01*
X201800Y747433D01*
X202050Y747017D01*
G01X201050Y745600D02*
X199383D01*
G01X206400Y742600D02*
X205900Y742683D01*
X205400Y743017D01*
X205067Y743600D01*
X204900Y744267D01*
X205067Y744933D01*
X205400Y745517D01*
X205900Y745850D01*
X206400Y745933D01*
X206900Y745850D01*
X207400Y745517D01*
X207733Y744933D01*
X207817Y744267D01*
X207733Y743600D01*
X207400Y743017D01*
X206900Y742683D01*
X206400Y742600D01*
G01X210833D02*
Y745933D01*
G01Y745267D02*
X211250Y745600D01*
X211667Y745850D01*
X212250Y745933D01*
X212667Y745850D01*
X213167Y745600D01*
G01X223867Y745267D02*
X224200Y745517D01*
X224450Y745933D01*
X224617Y746517D01*
X224450Y747017D01*
X224117Y747350D01*
X223533Y747600D01*
X221283D01*
Y742600D01*
X224033D01*
X224617Y742933D01*
X224950Y743433D01*
X225117Y744017D01*
X224950Y744600D01*
X224450Y745100D01*
X223867Y745267D01*
X221283D01*
G01X230300Y742600D02*
Y745933D01*
G01Y745350D02*
X229967Y745683D01*
X229467Y745850D01*
X228883Y745933D01*
X228300Y745767D01*
X227800Y745433D01*
X227467Y744933D01*
X227300Y744267D01*
X227467Y743600D01*
X227800Y743100D01*
X228300Y742767D01*
X228883Y742600D01*
X229467Y742683D01*
X229967Y742933D01*
X230300Y743267D01*
G01X233150Y743183D02*
X233567Y742850D01*
X234150Y742600D01*
X234650D01*
X235150Y742767D01*
X235483Y743017D01*
X235650Y743350D01*
X235567Y743850D01*
X235233Y744100D01*
X233733Y744600D01*
X233400Y745183D01*
X233567Y745600D01*
X233900Y745850D01*
X234400Y745933D01*
X234900Y745850D01*
X235400Y745600D01*
G01X238750Y744850D02*
X241417D01*
X241167Y745433D01*
X240750Y745767D01*
X240167Y745933D01*
X239583Y745850D01*
X239083Y745600D01*
X238750Y745017D01*
X238583Y744517D01*
Y744017D01*
X238750Y743517D01*
X239167Y743017D01*
X239667Y742683D01*
X240250Y742600D01*
X240833Y742767D01*
X241417Y743267D01*
G01X249033Y742600D02*
Y747600D01*
X251200Y743433D01*
X253367Y747600D01*
Y742600D01*
G01X258300D02*
Y745933D01*
G01Y745350D02*
X257967Y745683D01*
X257467Y745850D01*
X256883Y745933D01*
X256300Y745767D01*
X255800Y745433D01*
X255467Y744933D01*
X255300Y744267D01*
X255467Y743600D01*
X255800Y743100D01*
X256300Y742767D01*
X256883Y742600D01*
X257467Y742683D01*
X257967Y742933D01*
X258300Y743267D01*
G01X262400Y747600D02*
Y742600D01*
G01X261233Y745933D02*
X263567D01*
G01X266750Y744850D02*
X269417D01*
X269167Y745433D01*
X268750Y745767D01*
X268167Y745933D01*
X267583Y745850D01*
X267083Y745600D01*
X266750Y745017D01*
X266583Y744517D01*
Y744017D01*
X266750Y743517D01*
X267167Y743017D01*
X267667Y742683D01*
X268250Y742600D01*
X268833Y742767D01*
X269417Y743267D01*
G01X272433Y742600D02*
Y745933D01*
G01Y745267D02*
X272850Y745600D01*
X273267Y745850D01*
X273850Y745933D01*
X274267Y745850D01*
X274767Y745600D01*
G01X279200Y745933D02*
Y742600D01*
G01Y747267D02*
X279033Y747350D01*
Y747517D01*
X279200Y747600D01*
X279367Y747517D01*
Y747350D01*
X279200Y747267D01*
G01X286300Y742600D02*
Y745933D01*
G01Y745350D02*
X285967Y745683D01*
X285467Y745850D01*
X284883Y745933D01*
X284300Y745767D01*
X283800Y745433D01*
X283467Y744933D01*
X283300Y744267D01*
X283467Y743600D01*
X283800Y743100D01*
X284300Y742767D01*
X284883Y742600D01*
X285467Y742683D01*
X285967Y742933D01*
X286300Y743267D01*
G01X290400Y742600D02*
Y747600D01*
G01X294750Y743183D02*
X295167Y742850D01*
X295750Y742600D01*
X296250D01*
X296750Y742767D01*
X297083Y743017D01*
X297250Y743350D01*
X297167Y743850D01*
X296833Y744100D01*
X295333Y744600D01*
X295000Y745183D01*
X295167Y745600D01*
X295500Y745850D01*
X296000Y745933D01*
X296500Y745850D01*
X297000Y745600D01*
G01X306700Y742600D02*
Y746850D01*
X306867Y747267D01*
X307200Y747517D01*
X307700Y747600D01*
X308200Y747433D01*
X308450Y747017D01*
G01X307450Y745600D02*
X305783D01*
G01X312800Y742600D02*
X312300Y742683D01*
X311800Y743017D01*
X311467Y743600D01*
X311300Y744267D01*
X311467Y744933D01*
X311800Y745517D01*
X312300Y745850D01*
X312800Y745933D01*
X313300Y745850D01*
X313800Y745517D01*
X314133Y744933D01*
X314217Y744267D01*
X314133Y743600D01*
X313800Y743017D01*
X313300Y742683D01*
X312800Y742600D01*
G01X317233D02*
Y745933D01*
G01Y745267D02*
X317650Y745600D01*
X318067Y745850D01*
X318650Y745933D01*
X319067Y745850D01*
X319567Y745600D01*
G01X327933Y742600D02*
Y747600D01*
X330017D01*
X330683Y747350D01*
X331100Y747017D01*
X331267Y746350D01*
X331100Y745683D01*
X330600Y745267D01*
X330017Y745017D01*
X327933D01*
G01X330017D02*
X331267Y742600D01*
G01X335200Y745933D02*
Y742600D01*
G01Y747267D02*
X335033Y747350D01*
Y747517D01*
X335200Y747600D01*
X335367Y747517D01*
Y747350D01*
X335200Y747267D01*
G01X339633Y741350D02*
X340217Y741017D01*
X340883Y740933D01*
X341467Y741017D01*
X341967Y741433D01*
X342300Y742017D01*
Y745933D01*
G01Y745267D02*
X341967Y745600D01*
X341467Y745850D01*
X340883Y745933D01*
X340217Y745767D01*
X339800Y745433D01*
X339467Y744850D01*
X339300Y744267D01*
X339383Y743767D01*
X339717Y743183D01*
X340217Y742767D01*
X340883Y742600D01*
X341383Y742683D01*
X341967Y743017D01*
X342300Y743350D01*
G01X346400Y745933D02*
Y742600D01*
G01Y747267D02*
X346233Y747350D01*
Y747517D01*
X346400Y747600D01*
X346567Y747517D01*
Y747350D01*
X346400Y747267D01*
G01X353500Y747600D02*
Y742600D01*
G01Y743350D02*
X353167Y742933D01*
X352667Y742683D01*
X352083Y742600D01*
X351417Y742767D01*
X350917Y743183D01*
X350583Y743683D01*
X350500Y744267D01*
X350583Y744850D01*
X350917Y745350D01*
X351417Y745767D01*
X352083Y745933D01*
X352667Y745850D01*
X353083Y745683D01*
X353500Y745350D01*
G01X364700Y742600D02*
Y745933D01*
G01Y745350D02*
X364367Y745683D01*
X363867Y745850D01*
X363283Y745933D01*
X362700Y745767D01*
X362200Y745433D01*
X361867Y744933D01*
X361700Y744267D01*
X361867Y743600D01*
X362200Y743100D01*
X362700Y742767D01*
X363283Y742600D01*
X363867Y742683D01*
X364367Y742933D01*
X364700Y743267D01*
G01X367383Y742600D02*
Y745933D01*
G01Y745100D02*
X367717Y745517D01*
X368217Y745850D01*
X368883Y745933D01*
X369467Y745850D01*
X369967Y745517D01*
X370217Y744933D01*
Y742600D01*
G01X375900Y747600D02*
Y742600D01*
G01Y743350D02*
X375567Y742933D01*
X375067Y742683D01*
X374483Y742600D01*
X373817Y742767D01*
X373317Y743183D01*
X372983Y743683D01*
X372900Y744267D01*
X372983Y744850D01*
X373317Y745350D01*
X373817Y745767D01*
X374483Y745933D01*
X375067Y745850D01*
X375483Y745683D01*
X375900Y745350D01*
G01X383433Y742600D02*
Y747600D01*
X385600Y743433D01*
X387767Y747600D01*
Y742600D01*
G01X389783Y745933D02*
Y743600D01*
X390117Y743017D01*
X390617Y742683D01*
X391200Y742600D01*
X391783Y742683D01*
X392283Y743017D01*
X392617Y743600D01*
G01Y742600D02*
Y745933D01*
G01X396800Y742600D02*
Y747600D01*
G01X402400D02*
Y742600D01*
G01X401233Y745933D02*
X403567D01*
G01X408000D02*
Y742600D01*
G01Y747267D02*
X407833Y747350D01*
Y747517D01*
X408000Y747600D01*
X408167Y747517D01*
Y747350D01*
X408000Y747267D01*
G01X413600Y742600D02*
Y747600D01*
G01X420700Y742600D02*
Y745933D01*
G01Y745350D02*
X420367Y745683D01*
X419867Y745850D01*
X419283Y745933D01*
X418700Y745767D01*
X418200Y745433D01*
X417867Y744933D01*
X417700Y744267D01*
X417867Y743600D01*
X418200Y743100D01*
X418700Y742767D01*
X419283Y742600D01*
X419867Y742683D01*
X420367Y742933D01*
X420700Y743267D01*
G01X423050Y741100D02*
X423550Y740933D01*
X424217Y741100D01*
X424633Y741433D01*
X424967Y741850D01*
X425467Y743183D01*
X426550Y745933D01*
G01X423883D02*
X425467Y743183D01*
G01X429150Y744850D02*
X431817D01*
X431567Y745433D01*
X431150Y745767D01*
X430567Y745933D01*
X429983Y745850D01*
X429483Y745600D01*
X429150Y745017D01*
X428983Y744517D01*
Y744017D01*
X429150Y743517D01*
X429567Y743017D01*
X430067Y742683D01*
X430650Y742600D01*
X431233Y742767D01*
X431817Y743267D01*
G01X434833Y742600D02*
Y745933D01*
G01Y745267D02*
X435250Y745600D01*
X435667Y745850D01*
X436250Y745933D01*
X436667Y745850D01*
X437167Y745600D01*
G01X445533Y742600D02*
Y747600D01*
X447533D01*
X448200Y747350D01*
X448700Y746767D01*
X448867Y746100D01*
X448700Y745433D01*
X448283Y744933D01*
X447533Y744683D01*
X445533D01*
G01X451633Y742600D02*
Y745933D01*
G01Y745267D02*
X452050Y745600D01*
X452467Y745850D01*
X453050Y745933D01*
X453467Y745850D01*
X453967Y745600D01*
G01X458400Y745933D02*
Y742600D01*
G01Y747267D02*
X458233Y747350D01*
Y747517D01*
X458400Y747600D01*
X458567Y747517D01*
Y747350D01*
X458400Y747267D01*
G01X462583Y742600D02*
Y745933D01*
G01Y745100D02*
X462917Y745517D01*
X463417Y745850D01*
X464083Y745933D01*
X464667Y745850D01*
X465167Y745517D01*
X465417Y744933D01*
Y742600D01*
G01X469600Y747600D02*
Y742600D01*
G01X468433Y745933D02*
X470767D01*
G01X473950Y744850D02*
X476617D01*
X476367Y745433D01*
X475950Y745767D01*
X475367Y745933D01*
X474783Y745850D01*
X474283Y745600D01*
X473950Y745017D01*
X473783Y744517D01*
Y744017D01*
X473950Y743517D01*
X474367Y743017D01*
X474867Y742683D01*
X475450Y742600D01*
X476033Y742767D01*
X476617Y743267D01*
G01X482300Y747600D02*
Y742600D01*
G01Y743350D02*
X481967Y742933D01*
X481467Y742683D01*
X480883Y742600D01*
X480217Y742767D01*
X479717Y743183D01*
X479383Y743683D01*
X479300Y744267D01*
X479383Y744850D01*
X479717Y745350D01*
X480217Y745767D01*
X480883Y745933D01*
X481467Y745850D01*
X481883Y745683D01*
X482300Y745350D01*
G01X492667Y745267D02*
X493000Y745517D01*
X493250Y745933D01*
X493417Y746517D01*
X493250Y747017D01*
X492917Y747350D01*
X492333Y747600D01*
X490083D01*
Y742600D01*
X492833D01*
X493417Y742933D01*
X493750Y743433D01*
X493917Y744017D01*
X493750Y744600D01*
X493250Y745100D01*
X492667Y745267D01*
X490083D01*
G01X497600Y742600D02*
X497100Y742683D01*
X496600Y743017D01*
X496267Y743600D01*
X496100Y744267D01*
X496267Y744933D01*
X496600Y745517D01*
X497100Y745850D01*
X497600Y745933D01*
X498100Y745850D01*
X498600Y745517D01*
X498933Y744933D01*
X499017Y744267D01*
X498933Y743600D01*
X498600Y743017D01*
X498100Y742683D01*
X497600Y742600D01*
G01X504700D02*
Y745933D01*
G01Y745350D02*
X504367Y745683D01*
X503867Y745850D01*
X503283Y745933D01*
X502700Y745767D01*
X502200Y745433D01*
X501867Y744933D01*
X501700Y744267D01*
X501867Y743600D01*
X502200Y743100D01*
X502700Y742767D01*
X503283Y742600D01*
X503867Y742683D01*
X504367Y742933D01*
X504700Y743267D01*
G01X507633Y742600D02*
Y745933D01*
G01Y745267D02*
X508050Y745600D01*
X508467Y745850D01*
X509050Y745933D01*
X509467Y745850D01*
X509967Y745600D01*
G01X515900Y747600D02*
Y742600D01*
G01Y743350D02*
X515567Y742933D01*
X515067Y742683D01*
X514483Y742600D01*
X513817Y742767D01*
X513317Y743183D01*
X512983Y743683D01*
X512900Y744267D01*
X512983Y744850D01*
X513317Y745350D01*
X513817Y745767D01*
X514483Y745933D01*
X515067Y745850D01*
X515483Y745683D01*
X515900Y745350D01*
G01X518750Y743183D02*
X519167Y742850D01*
X519750Y742600D01*
X520250D01*
X520750Y742767D01*
X521083Y743017D01*
X521250Y743350D01*
X521167Y743850D01*
X520833Y744100D01*
X519333Y744600D01*
X519000Y745183D01*
X519167Y745600D01*
X519500Y745850D01*
X520000Y745933D01*
X520500Y745850D01*
X521000Y745600D01*
G01X71000Y756600D02*
X73000D01*
G01X72000D02*
Y751600D01*
G01X71000D02*
X73000D01*
G01X75933D02*
Y756600D01*
X77933D01*
X78600Y756350D01*
X79100Y755767D01*
X79267Y755100D01*
X79100Y754433D01*
X78683Y753933D01*
X77933Y753683D01*
X75933D01*
G01X85033Y756183D02*
X84533Y756433D01*
X83950Y756600D01*
X83283D01*
X82533Y756350D01*
X81950Y755933D01*
X81533Y755433D01*
X81200Y754600D01*
X81117Y753850D01*
X81283Y753100D01*
X81533Y752600D01*
X82033Y752100D01*
X82617Y751767D01*
X83200Y751600D01*
X83783D01*
X84367Y751767D01*
X84867Y752017D01*
X85283Y752350D01*
G01X87717Y753267D02*
X89883D01*
G01X94400Y756600D02*
Y751600D01*
G01X92483Y756600D02*
X96317D01*
G01X97833Y751600D02*
Y756600D01*
X100000Y752433D01*
X102167Y756600D01*
Y751600D01*
G01X104517Y753267D02*
X106683D01*
G01X109617Y753683D02*
X110200Y754267D01*
X110700Y754600D01*
X111367Y754767D01*
X111950Y754600D01*
X112367Y754267D01*
X112700Y753767D01*
X112783Y753183D01*
X112700Y752683D01*
X112367Y752183D01*
X111867Y751767D01*
X111283Y751600D01*
X110617Y751767D01*
X110033Y752267D01*
X109700Y753017D01*
X109617Y753850D01*
X109783Y754933D01*
X110033Y755517D01*
X110450Y756100D01*
X111033Y756517D01*
X111617Y756600D01*
X112200Y756433D01*
X112617Y756017D01*
G01X114967Y752350D02*
X115467Y751933D01*
X116050Y751683D01*
X116800Y751600D01*
X117550Y751767D01*
X118133Y752100D01*
X118550Y752683D01*
X118633Y753350D01*
X118467Y754017D01*
X118050Y754433D01*
X117467Y754767D01*
X116883Y754850D01*
X116300Y754767D01*
X115550Y754433D01*
X115800Y756600D01*
X118050D01*
G01X122400D02*
X121733Y756433D01*
X121233Y756017D01*
X120900Y755517D01*
X120650Y754850D01*
X120567Y754100D01*
X120650Y753350D01*
X120900Y752683D01*
X121233Y752183D01*
X121733Y751767D01*
X122400Y751600D01*
X123067Y751767D01*
X123567Y752183D01*
X123900Y752683D01*
X124150Y753350D01*
X124233Y754100D01*
X124150Y754850D01*
X123900Y755517D01*
X123567Y756017D01*
X123067Y756433D01*
X122400Y756600D01*
G01X133600D02*
Y751600D01*
G01X131683Y756600D02*
X135517D01*
G01X137950Y753850D02*
X140617D01*
X140367Y754433D01*
X139950Y754767D01*
X139367Y754933D01*
X138783Y754850D01*
X138283Y754600D01*
X137950Y754017D01*
X137783Y753517D01*
Y753017D01*
X137950Y752517D01*
X138367Y752017D01*
X138867Y751683D01*
X139450Y751600D01*
X140033Y751767D01*
X140617Y752267D01*
G01X143550Y752183D02*
X143967Y751850D01*
X144550Y751600D01*
X145050D01*
X145550Y751767D01*
X145883Y752017D01*
X146050Y752350D01*
X145967Y752850D01*
X145633Y753100D01*
X144133Y753600D01*
X143800Y754183D01*
X143967Y754600D01*
X144300Y754850D01*
X144800Y754933D01*
X145300Y754850D01*
X145800Y754600D01*
G01X150400Y756600D02*
Y751600D01*
G01X149233Y754933D02*
X151567D01*
G01X159433Y751600D02*
Y756600D01*
X161600Y752433D01*
X163767Y756600D01*
Y751600D01*
G01X165950Y753850D02*
X168617D01*
X168367Y754433D01*
X167950Y754767D01*
X167367Y754933D01*
X166783Y754850D01*
X166283Y754600D01*
X165950Y754017D01*
X165783Y753517D01*
Y753017D01*
X165950Y752517D01*
X166367Y752017D01*
X166867Y751683D01*
X167450Y751600D01*
X168033Y751767D01*
X168617Y752267D01*
G01X172800Y756600D02*
Y751600D01*
G01X171633Y754933D02*
X173967D01*
G01X176983Y751600D02*
Y756600D01*
G01Y754183D02*
X177400Y754600D01*
X177817Y754850D01*
X178483Y754933D01*
X178983Y754850D01*
X179567Y754517D01*
X179817Y754017D01*
Y751600D01*
G01X184000D02*
X183500Y751683D01*
X183000Y752017D01*
X182667Y752600D01*
X182500Y753267D01*
X182667Y753933D01*
X183000Y754517D01*
X183500Y754850D01*
X184000Y754933D01*
X184500Y754850D01*
X185000Y754517D01*
X185333Y753933D01*
X185417Y753267D01*
X185333Y752600D01*
X185000Y752017D01*
X184500Y751683D01*
X184000Y751600D01*
G01X191100Y756600D02*
Y751600D01*
G01Y752350D02*
X190767Y751933D01*
X190267Y751683D01*
X189683Y751600D01*
X189017Y751767D01*
X188517Y752183D01*
X188183Y752683D01*
X188100Y753267D01*
X188183Y753850D01*
X188517Y754350D01*
X189017Y754767D01*
X189683Y754933D01*
X190267Y754850D01*
X190683Y754683D01*
X191100Y754350D01*
G01X193950Y752183D02*
X194367Y751850D01*
X194950Y751600D01*
X195450D01*
X195950Y751767D01*
X196283Y752017D01*
X196450Y752350D01*
X196367Y752850D01*
X196033Y753100D01*
X194533Y753600D01*
X194200Y754183D01*
X194367Y754600D01*
X194700Y754850D01*
X195200Y754933D01*
X195700Y754850D01*
X196200Y754600D01*
G01X204233Y751600D02*
Y756600D01*
X206400Y752433D01*
X208567Y756600D01*
Y751600D01*
G01X213500D02*
Y754933D01*
G01Y754350D02*
X213167Y754683D01*
X212667Y754850D01*
X212083Y754933D01*
X211500Y754767D01*
X211000Y754433D01*
X210667Y753933D01*
X210500Y753267D01*
X210667Y752600D01*
X211000Y752100D01*
X211500Y751767D01*
X212083Y751600D01*
X212667Y751683D01*
X213167Y751933D01*
X213500Y752267D01*
G01X216183Y751600D02*
Y754933D01*
G01Y754100D02*
X216517Y754517D01*
X217017Y754850D01*
X217683Y754933D01*
X218267Y754850D01*
X218767Y754517D01*
X219017Y753933D01*
Y751600D01*
G01X221783Y754933D02*
Y752600D01*
X222117Y752017D01*
X222617Y751683D01*
X223200Y751600D01*
X223783Y751683D01*
X224283Y752017D01*
X224617Y752600D01*
G01Y751600D02*
Y754933D01*
G01X230300Y751600D02*
Y754933D01*
G01Y754350D02*
X229967Y754683D01*
X229467Y754850D01*
X228883Y754933D01*
X228300Y754767D01*
X227800Y754433D01*
X227467Y753933D01*
X227300Y753267D01*
X227467Y752600D01*
X227800Y752100D01*
X228300Y751767D01*
X228883Y751600D01*
X229467Y751683D01*
X229967Y751933D01*
X230300Y752267D01*
G01X234400Y751600D02*
Y756600D01*
G01X71000Y765600D02*
X73000D01*
G01X72000D02*
Y760600D01*
G01X71000D02*
X73000D01*
G01X75933D02*
Y765600D01*
X77933D01*
X78600Y765350D01*
X79100Y764767D01*
X79267Y764100D01*
X79100Y763433D01*
X78683Y762933D01*
X77933Y762683D01*
X75933D01*
G01X85033Y765183D02*
X84533Y765433D01*
X83950Y765600D01*
X83283D01*
X82533Y765350D01*
X81950Y764933D01*
X81533Y764433D01*
X81200Y763600D01*
X81117Y762850D01*
X81283Y762100D01*
X81533Y761600D01*
X82033Y761100D01*
X82617Y760767D01*
X83200Y760600D01*
X83783D01*
X84367Y760767D01*
X84867Y761017D01*
X85283Y761350D01*
G01X87717Y762267D02*
X89883D01*
G01X92817Y762683D02*
X93400Y763267D01*
X93900Y763600D01*
X94567Y763767D01*
X95150Y763600D01*
X95567Y763267D01*
X95900Y762767D01*
X95983Y762183D01*
X95900Y761683D01*
X95567Y761183D01*
X95067Y760767D01*
X94483Y760600D01*
X93817Y760767D01*
X93233Y761267D01*
X92900Y762017D01*
X92817Y762850D01*
X92983Y763933D01*
X93233Y764517D01*
X93650Y765100D01*
X94233Y765517D01*
X94817Y765600D01*
X95400Y765433D01*
X95817Y765017D01*
G01X100000Y765600D02*
X99333Y765433D01*
X98833Y765017D01*
X98500Y764517D01*
X98250Y763850D01*
X98167Y763100D01*
X98250Y762350D01*
X98500Y761683D01*
X98833Y761183D01*
X99333Y760767D01*
X100000Y760600D01*
X100667Y760767D01*
X101167Y761183D01*
X101500Y761683D01*
X101750Y762350D01*
X101833Y763100D01*
X101750Y763850D01*
X101500Y764517D01*
X101167Y765017D01*
X100667Y765433D01*
X100000Y765600D01*
G01X105600Y760600D02*
Y765600D01*
X104600Y764600D01*
G01Y760600D02*
X106600D01*
G01X109617Y762683D02*
X110200Y763267D01*
X110700Y763600D01*
X111367Y763767D01*
X111950Y763600D01*
X112367Y763267D01*
X112700Y762767D01*
X112783Y762183D01*
X112700Y761683D01*
X112367Y761183D01*
X111867Y760767D01*
X111283Y760600D01*
X110617Y760767D01*
X110033Y761267D01*
X109700Y762017D01*
X109617Y762850D01*
X109783Y763933D01*
X110033Y764517D01*
X110450Y765100D01*
X111033Y765517D01*
X111617Y765600D01*
X112200Y765433D01*
X112617Y765017D01*
G01X122400Y760600D02*
X121733Y760683D01*
X121150Y761017D01*
X120650Y761517D01*
X120317Y762100D01*
X120150Y762767D01*
Y763433D01*
X120317Y764100D01*
X120650Y764683D01*
X121150Y765183D01*
X121733Y765517D01*
X122400Y765600D01*
X123067Y765517D01*
X123650Y765183D01*
X124150Y764683D01*
X124483Y764100D01*
X124650Y763433D01*
Y762767D01*
X124483Y762100D01*
X124150Y761517D01*
X123650Y761017D01*
X123067Y760683D01*
X122400Y760600D01*
G01X123067Y761933D02*
X124067Y760600D01*
G01X126583Y763933D02*
Y761600D01*
X126917Y761017D01*
X127417Y760683D01*
X128000Y760600D01*
X128583Y760683D01*
X129083Y761017D01*
X129417Y761600D01*
G01Y760600D02*
Y763933D01*
G01X135100Y760600D02*
Y763933D01*
G01Y763350D02*
X134767Y763683D01*
X134267Y763850D01*
X133683Y763933D01*
X133100Y763767D01*
X132600Y763433D01*
X132267Y762933D01*
X132100Y762267D01*
X132267Y761600D01*
X132600Y761100D01*
X133100Y760767D01*
X133683Y760600D01*
X134267Y760683D01*
X134767Y760933D01*
X135100Y761267D01*
G01X139200Y760600D02*
Y765600D01*
G01X144800Y763933D02*
Y760600D01*
G01Y765267D02*
X144633Y765350D01*
Y765517D01*
X144800Y765600D01*
X144967Y765517D01*
Y765350D01*
X144800Y765267D01*
G01X149900Y760600D02*
Y764850D01*
X150067Y765267D01*
X150400Y765517D01*
X150900Y765600D01*
X151400Y765433D01*
X151650Y765017D01*
G01X150650Y763600D02*
X148983D01*
G01X156000Y763933D02*
Y760600D01*
G01Y765267D02*
X155833Y765350D01*
Y765517D01*
X156000Y765600D01*
X156167Y765517D01*
Y765350D01*
X156000Y765267D01*
G01X162933Y763517D02*
X162350Y763850D01*
X161850Y763933D01*
X161183Y763767D01*
X160683Y763433D01*
X160350Y762850D01*
X160267Y762267D01*
X160350Y761683D01*
X160683Y761183D01*
X161183Y760767D01*
X161850Y760600D01*
X162433Y760767D01*
X162933Y761100D01*
G01X168700Y760600D02*
Y763933D01*
G01Y763350D02*
X168367Y763683D01*
X167867Y763850D01*
X167283Y763933D01*
X166700Y763767D01*
X166200Y763433D01*
X165867Y762933D01*
X165700Y762267D01*
X165867Y761600D01*
X166200Y761100D01*
X166700Y760767D01*
X167283Y760600D01*
X167867Y760683D01*
X168367Y760933D01*
X168700Y761267D01*
G01X172800Y765600D02*
Y760600D01*
G01X171633Y763933D02*
X173967D01*
G01X178400D02*
Y760600D01*
G01Y765267D02*
X178233Y765350D01*
Y765517D01*
X178400Y765600D01*
X178567Y765517D01*
Y765350D01*
X178400Y765267D01*
G01X184000Y760600D02*
X183500Y760683D01*
X183000Y761017D01*
X182667Y761600D01*
X182500Y762267D01*
X182667Y762933D01*
X183000Y763517D01*
X183500Y763850D01*
X184000Y763933D01*
X184500Y763850D01*
X185000Y763517D01*
X185333Y762933D01*
X185417Y762267D01*
X185333Y761600D01*
X185000Y761017D01*
X184500Y760683D01*
X184000Y760600D01*
G01X188183D02*
Y763933D01*
G01Y763100D02*
X188517Y763517D01*
X189017Y763850D01*
X189683Y763933D01*
X190267Y763850D01*
X190767Y763517D01*
X191017Y762933D01*
Y760600D01*
G01X203300Y758933D02*
X199133Y763933D01*
Y764767D01*
X199967Y765600D01*
X200800D01*
X201633Y764767D01*
Y763933D01*
X200800Y763100D01*
X199133Y762267D01*
X198300Y761433D01*
Y759767D01*
X199133Y758933D01*
X201633D01*
X203300Y760600D01*
G01X210333D02*
Y765600D01*
X212333D01*
X213000Y765350D01*
X213500Y764767D01*
X213667Y764100D01*
X213500Y763433D01*
X213083Y762933D01*
X212333Y762683D01*
X210333D01*
G01X216350Y762850D02*
X219017D01*
X218767Y763433D01*
X218350Y763767D01*
X217767Y763933D01*
X217183Y763850D01*
X216683Y763600D01*
X216350Y763017D01*
X216183Y762517D01*
Y762017D01*
X216350Y761517D01*
X216767Y761017D01*
X217267Y760683D01*
X217850Y760600D01*
X218433Y760767D01*
X219017Y761267D01*
G01X222033Y760600D02*
Y763933D01*
G01Y763267D02*
X222450Y763600D01*
X222867Y763850D01*
X223450Y763933D01*
X223867Y763850D01*
X224367Y763600D01*
G01X228300Y760600D02*
Y764850D01*
X228467Y765267D01*
X228800Y765517D01*
X229300Y765600D01*
X229800Y765433D01*
X230050Y765017D01*
G01X229050Y763600D02*
X227383D01*
G01X234400Y760600D02*
X233900Y760683D01*
X233400Y761017D01*
X233067Y761600D01*
X232900Y762267D01*
X233067Y762933D01*
X233400Y763517D01*
X233900Y763850D01*
X234400Y763933D01*
X234900Y763850D01*
X235400Y763517D01*
X235733Y762933D01*
X235817Y762267D01*
X235733Y761600D01*
X235400Y761017D01*
X234900Y760683D01*
X234400Y760600D01*
G01X238833D02*
Y763933D01*
G01Y763267D02*
X239250Y763600D01*
X239667Y763850D01*
X240250Y763933D01*
X240667Y763850D01*
X241167Y763600D01*
G01X243100Y760600D02*
Y763933D01*
G01Y763017D02*
X243350Y763433D01*
X243767Y763767D01*
X244350Y763933D01*
X244933Y763767D01*
X245350Y763433D01*
X245600Y763017D01*
Y760600D01*
G01Y763017D02*
X245850Y763433D01*
X246267Y763767D01*
X246850Y763933D01*
X247433Y763767D01*
X247850Y763433D01*
X248100Y762933D01*
Y760600D01*
G01X252700D02*
Y763933D01*
G01Y763350D02*
X252367Y763683D01*
X251867Y763850D01*
X251283Y763933D01*
X250700Y763767D01*
X250200Y763433D01*
X249867Y762933D01*
X249700Y762267D01*
X249867Y761600D01*
X250200Y761100D01*
X250700Y760767D01*
X251283Y760600D01*
X251867Y760683D01*
X252367Y760933D01*
X252700Y761267D01*
G01X255383Y760600D02*
Y763933D01*
G01Y763100D02*
X255717Y763517D01*
X256217Y763850D01*
X256883Y763933D01*
X257467Y763850D01*
X257967Y763517D01*
X258217Y762933D01*
Y760600D01*
G01X263733Y763517D02*
X263150Y763850D01*
X262650Y763933D01*
X261983Y763767D01*
X261483Y763433D01*
X261150Y762850D01*
X261067Y762267D01*
X261150Y761683D01*
X261483Y761183D01*
X261983Y760767D01*
X262650Y760600D01*
X263233Y760767D01*
X263733Y761100D01*
G01X266750Y762850D02*
X269417D01*
X269167Y763433D01*
X268750Y763767D01*
X268167Y763933D01*
X267583Y763850D01*
X267083Y763600D01*
X266750Y763017D01*
X266583Y762517D01*
Y762017D01*
X266750Y761517D01*
X267167Y761017D01*
X267667Y760683D01*
X268250Y760600D01*
X268833Y760767D01*
X269417Y761267D01*
G01X277450D02*
X278117Y760850D01*
X278867Y760600D01*
X279533D01*
X280200Y760850D01*
X280700Y761267D01*
X280950Y761850D01*
X280783Y762433D01*
X280367Y762933D01*
X279617Y763267D01*
X278617Y763433D01*
X278033Y763767D01*
X277783Y764350D01*
X277950Y764933D01*
X278367Y765350D01*
X278950Y765600D01*
X279533D01*
X280117Y765433D01*
X280617Y765017D01*
G01X283300Y758933D02*
Y763933D01*
G01Y763183D02*
X283717Y763600D01*
X284133Y763850D01*
X284800Y763933D01*
X285383Y763850D01*
X285967Y763433D01*
X286217Y762850D01*
X286300Y762267D01*
X286217Y761683D01*
X285967Y761100D01*
X285467Y760767D01*
X284800Y760600D01*
X284217Y760683D01*
X283633Y760933D01*
X283300Y761267D01*
G01X289150Y762850D02*
X291817D01*
X291567Y763433D01*
X291150Y763767D01*
X290567Y763933D01*
X289983Y763850D01*
X289483Y763600D01*
X289150Y763017D01*
X288983Y762517D01*
Y762017D01*
X289150Y761517D01*
X289567Y761017D01*
X290067Y760683D01*
X290650Y760600D01*
X291233Y760767D01*
X291817Y761267D01*
G01X297333Y763517D02*
X296750Y763850D01*
X296250Y763933D01*
X295583Y763767D01*
X295083Y763433D01*
X294750Y762850D01*
X294667Y762267D01*
X294750Y761683D01*
X295083Y761183D01*
X295583Y760767D01*
X296250Y760600D01*
X296833Y760767D01*
X297333Y761100D01*
G01X301600Y763933D02*
Y760600D01*
G01Y765267D02*
X301433Y765350D01*
Y765517D01*
X301600Y765600D01*
X301767Y765517D01*
Y765350D01*
X301600Y765267D01*
G01X306700Y760600D02*
Y764850D01*
X306867Y765267D01*
X307200Y765517D01*
X307700Y765600D01*
X308200Y765433D01*
X308450Y765017D01*
G01X307450Y763600D02*
X305783D01*
G01X312800Y763933D02*
Y760600D01*
G01Y765267D02*
X312633Y765350D01*
Y765517D01*
X312800Y765600D01*
X312967Y765517D01*
Y765350D01*
X312800Y765267D01*
G01X319733Y763517D02*
X319150Y763850D01*
X318650Y763933D01*
X317983Y763767D01*
X317483Y763433D01*
X317150Y762850D01*
X317067Y762267D01*
X317150Y761683D01*
X317483Y761183D01*
X317983Y760767D01*
X318650Y760600D01*
X319233Y760767D01*
X319733Y761100D01*
G01X325500Y760600D02*
Y763933D01*
G01Y763350D02*
X325167Y763683D01*
X324667Y763850D01*
X324083Y763933D01*
X323500Y763767D01*
X323000Y763433D01*
X322667Y762933D01*
X322500Y762267D01*
X322667Y761600D01*
X323000Y761100D01*
X323500Y760767D01*
X324083Y760600D01*
X324667Y760683D01*
X325167Y760933D01*
X325500Y761267D01*
G01X329600Y765600D02*
Y760600D01*
G01X328433Y763933D02*
X330767D01*
G01X335200D02*
Y760600D01*
G01Y765267D02*
X335033Y765350D01*
Y765517D01*
X335200Y765600D01*
X335367Y765517D01*
Y765350D01*
X335200Y765267D01*
G01X340800Y760600D02*
X340300Y760683D01*
X339800Y761017D01*
X339467Y761600D01*
X339300Y762267D01*
X339467Y762933D01*
X339800Y763517D01*
X340300Y763850D01*
X340800Y763933D01*
X341300Y763850D01*
X341800Y763517D01*
X342133Y762933D01*
X342217Y762267D01*
X342133Y761600D01*
X341800Y761017D01*
X341300Y760683D01*
X340800Y760600D01*
G01X344983D02*
Y763933D01*
G01Y763100D02*
X345317Y763517D01*
X345817Y763850D01*
X346483Y763933D01*
X347067Y763850D01*
X347567Y763517D01*
X347817Y762933D01*
Y760600D01*
G01X357100D02*
Y764850D01*
X357267Y765267D01*
X357600Y765517D01*
X358100Y765600D01*
X358600Y765433D01*
X358850Y765017D01*
G01X357850Y763600D02*
X356183D01*
G01X363200Y760600D02*
X362700Y760683D01*
X362200Y761017D01*
X361867Y761600D01*
X361700Y762267D01*
X361867Y762933D01*
X362200Y763517D01*
X362700Y763850D01*
X363200Y763933D01*
X363700Y763850D01*
X364200Y763517D01*
X364533Y762933D01*
X364617Y762267D01*
X364533Y761600D01*
X364200Y761017D01*
X363700Y760683D01*
X363200Y760600D01*
G01X367633D02*
Y763933D01*
G01Y763267D02*
X368050Y763600D01*
X368467Y763850D01*
X369050Y763933D01*
X369467Y763850D01*
X369967Y763600D01*
G01X378250Y760600D02*
Y765600D01*
G01X381750D02*
Y760600D01*
G01Y763100D02*
X378250D01*
G01X385600Y763933D02*
Y760600D01*
G01Y765267D02*
X385433Y765350D01*
Y765517D01*
X385600Y765600D01*
X385767Y765517D01*
Y765350D01*
X385600Y765267D01*
G01X390033Y759350D02*
X390617Y759017D01*
X391283Y758933D01*
X391867Y759017D01*
X392367Y759433D01*
X392700Y760017D01*
Y763933D01*
G01Y763267D02*
X392367Y763600D01*
X391867Y763850D01*
X391283Y763933D01*
X390617Y763767D01*
X390200Y763433D01*
X389867Y762850D01*
X389700Y762267D01*
X389783Y761767D01*
X390117Y761183D01*
X390617Y760767D01*
X391283Y760600D01*
X391783Y760683D01*
X392367Y761017D01*
X392700Y761350D01*
G01X395383Y760600D02*
Y765600D01*
G01Y763183D02*
X395800Y763600D01*
X396217Y763850D01*
X396883Y763933D01*
X397383Y763850D01*
X397967Y763517D01*
X398217Y763017D01*
Y760600D01*
G01X406167D02*
Y765600D01*
X407833D01*
X408500Y765350D01*
X409000Y765017D01*
X409417Y764517D01*
X409750Y763933D01*
X409833Y763100D01*
X409750Y762267D01*
X409417Y761683D01*
X409000Y761183D01*
X408500Y760850D01*
X407833Y760600D01*
X406167D01*
G01X412350Y762850D02*
X415017D01*
X414767Y763433D01*
X414350Y763767D01*
X413767Y763933D01*
X413183Y763850D01*
X412683Y763600D01*
X412350Y763017D01*
X412183Y762517D01*
Y762017D01*
X412350Y761517D01*
X412767Y761017D01*
X413267Y760683D01*
X413850Y760600D01*
X414433Y760767D01*
X415017Y761267D01*
G01X417783Y760600D02*
Y763933D01*
G01Y763100D02*
X418117Y763517D01*
X418617Y763850D01*
X419283Y763933D01*
X419867Y763850D01*
X420367Y763517D01*
X420617Y762933D01*
Y760600D01*
G01X423550Y761183D02*
X423967Y760850D01*
X424550Y760600D01*
X425050D01*
X425550Y760767D01*
X425883Y761017D01*
X426050Y761350D01*
X425967Y761850D01*
X425633Y762100D01*
X424133Y762600D01*
X423800Y763183D01*
X423967Y763600D01*
X424300Y763850D01*
X424800Y763933D01*
X425300Y763850D01*
X425800Y763600D01*
G01X430400Y763933D02*
Y760600D01*
G01Y765267D02*
X430233Y765350D01*
Y765517D01*
X430400Y765600D01*
X430567Y765517D01*
Y765350D01*
X430400Y765267D01*
G01X436000Y765600D02*
Y760600D01*
G01X434833Y763933D02*
X437167D01*
G01X439850Y759100D02*
X440350Y758933D01*
X441017Y759100D01*
X441433Y759433D01*
X441767Y759850D01*
X442267Y761183D01*
X443350Y763933D01*
G01X440683D02*
X442267Y761183D01*
G01X451800Y765600D02*
X453800D01*
G01X452800D02*
Y760600D01*
G01X451800D02*
X453800D01*
G01X456983D02*
Y763933D01*
G01Y763100D02*
X457317Y763517D01*
X457817Y763850D01*
X458483Y763933D01*
X459067Y763850D01*
X459567Y763517D01*
X459817Y762933D01*
Y760600D01*
G01X464000Y765600D02*
Y760600D01*
G01X462833Y763933D02*
X465167D01*
G01X468350Y762850D02*
X471017D01*
X470767Y763433D01*
X470350Y763767D01*
X469767Y763933D01*
X469183Y763850D01*
X468683Y763600D01*
X468350Y763017D01*
X468183Y762517D01*
Y762017D01*
X468350Y761517D01*
X468767Y761017D01*
X469267Y760683D01*
X469850Y760600D01*
X470433Y760767D01*
X471017Y761267D01*
G01X474033Y760600D02*
Y763933D01*
G01Y763267D02*
X474450Y763600D01*
X474867Y763850D01*
X475450Y763933D01*
X475867Y763850D01*
X476367Y763600D01*
G01X482133Y763517D02*
X481550Y763850D01*
X481050Y763933D01*
X480383Y763767D01*
X479883Y763433D01*
X479550Y762850D01*
X479467Y762267D01*
X479550Y761683D01*
X479883Y761183D01*
X480383Y760767D01*
X481050Y760600D01*
X481633Y760767D01*
X482133Y761100D01*
G01X486400Y760600D02*
X485900Y760683D01*
X485400Y761017D01*
X485067Y761600D01*
X484900Y762267D01*
X485067Y762933D01*
X485400Y763517D01*
X485900Y763850D01*
X486400Y763933D01*
X486900Y763850D01*
X487400Y763517D01*
X487733Y762933D01*
X487817Y762267D01*
X487733Y761600D01*
X487400Y761017D01*
X486900Y760683D01*
X486400Y760600D01*
G01X490583D02*
Y763933D01*
G01Y763100D02*
X490917Y763517D01*
X491417Y763850D01*
X492083Y763933D01*
X492667Y763850D01*
X493167Y763517D01*
X493417Y762933D01*
Y760600D01*
G01X496183D02*
Y763933D01*
G01Y763100D02*
X496517Y763517D01*
X497017Y763850D01*
X497683Y763933D01*
X498267Y763850D01*
X498767Y763517D01*
X499017Y762933D01*
Y760600D01*
G01X501950Y762850D02*
X504617D01*
X504367Y763433D01*
X503950Y763767D01*
X503367Y763933D01*
X502783Y763850D01*
X502283Y763600D01*
X501950Y763017D01*
X501783Y762517D01*
Y762017D01*
X501950Y761517D01*
X502367Y761017D01*
X502867Y760683D01*
X503450Y760600D01*
X504033Y760767D01*
X504617Y761267D01*
G01X510133Y763517D02*
X509550Y763850D01*
X509050Y763933D01*
X508383Y763767D01*
X507883Y763433D01*
X507550Y762850D01*
X507467Y762267D01*
X507550Y761683D01*
X507883Y761183D01*
X508383Y760767D01*
X509050Y760600D01*
X509633Y760767D01*
X510133Y761100D01*
G01X514400Y765600D02*
Y760600D01*
G01X513233Y763933D02*
X515567D01*
G01X519583Y758933D02*
X518750Y759767D01*
X518333Y760600D01*
Y763933D01*
X518750Y764767D01*
X519583Y765600D01*
G01X523850Y760600D02*
Y765600D01*
G01X527350D02*
Y760600D01*
G01Y763100D02*
X523850D01*
G01X529367Y760600D02*
Y765600D01*
X531033D01*
X531700Y765350D01*
X532200Y765017D01*
X532617Y764517D01*
X532950Y763933D01*
X533033Y763100D01*
X532950Y762267D01*
X532617Y761683D01*
X532200Y761183D01*
X531700Y760850D01*
X531033Y760600D01*
X529367D01*
G01X535800Y765600D02*
X537800D01*
G01X536800D02*
Y760600D01*
G01X535800D02*
X537800D01*
G01X542817Y758933D02*
X543650Y759767D01*
X544067Y760600D01*
Y763933D01*
X543650Y764767D01*
X542817Y765600D01*
G01X551933D02*
Y760600D01*
X555267D01*
G01X560700D02*
Y763933D01*
G01Y763350D02*
X560367Y763683D01*
X559867Y763850D01*
X559283Y763933D01*
X558700Y763767D01*
X558200Y763433D01*
X557867Y762933D01*
X557700Y762267D01*
X557867Y761600D01*
X558200Y761100D01*
X558700Y760767D01*
X559283Y760600D01*
X559867Y760683D01*
X560367Y760933D01*
X560700Y761267D01*
G01X563050Y759100D02*
X563550Y758933D01*
X564217Y759100D01*
X564633Y759433D01*
X564967Y759850D01*
X565467Y761183D01*
X566550Y763933D01*
G01X563883D02*
X565467Y761183D01*
G01X569150Y762850D02*
X571817D01*
X571567Y763433D01*
X571150Y763767D01*
X570567Y763933D01*
X569983Y763850D01*
X569483Y763600D01*
X569150Y763017D01*
X568983Y762517D01*
Y762017D01*
X569150Y761517D01*
X569567Y761017D01*
X570067Y760683D01*
X570650Y760600D01*
X571233Y760767D01*
X571817Y761267D01*
G01X574833Y760600D02*
Y763933D01*
G01Y763267D02*
X575250Y763600D01*
X575667Y763850D01*
X576250Y763933D01*
X576667Y763850D01*
X577167Y763600D01*
G01X580350Y761183D02*
X580767Y760850D01*
X581350Y760600D01*
X581850D01*
X582350Y760767D01*
X582683Y761017D01*
X582850Y761350D01*
X582767Y761850D01*
X582433Y762100D01*
X580933Y762600D01*
X580600Y763183D01*
X580767Y763600D01*
X581100Y763850D01*
X581600Y763933D01*
X582100Y763850D01*
X582600Y763600D01*
G01X592800Y760600D02*
X592300Y760683D01*
X591800Y761017D01*
X591467Y761600D01*
X591300Y762267D01*
X591467Y762933D01*
X591800Y763517D01*
X592300Y763850D01*
X592800Y763933D01*
X593300Y763850D01*
X593800Y763517D01*
X594133Y762933D01*
X594217Y762267D01*
X594133Y761600D01*
X593800Y761017D01*
X593300Y760683D01*
X592800Y760600D01*
G01X597233D02*
Y763933D01*
G01Y763267D02*
X597650Y763600D01*
X598067Y763850D01*
X598650Y763933D01*
X599067Y763850D01*
X599567Y763600D01*
G01X610267Y763267D02*
X610600Y763517D01*
X610850Y763933D01*
X611017Y764517D01*
X610850Y765017D01*
X610517Y765350D01*
X609933Y765600D01*
X607683D01*
Y760600D01*
X610433D01*
X611017Y760933D01*
X611350Y761433D01*
X611517Y762017D01*
X611350Y762600D01*
X610850Y763100D01*
X610267Y763267D01*
X607683D01*
G01X615200Y760600D02*
X614700Y760683D01*
X614200Y761017D01*
X613867Y761600D01*
X613700Y762267D01*
X613867Y762933D01*
X614200Y763517D01*
X614700Y763850D01*
X615200Y763933D01*
X615700Y763850D01*
X616200Y763517D01*
X616533Y762933D01*
X616617Y762267D01*
X616533Y761600D01*
X616200Y761017D01*
X615700Y760683D01*
X615200Y760600D01*
G01X622300D02*
Y763933D01*
G01Y763350D02*
X621967Y763683D01*
X621467Y763850D01*
X620883Y763933D01*
X620300Y763767D01*
X619800Y763433D01*
X619467Y762933D01*
X619300Y762267D01*
X619467Y761600D01*
X619800Y761100D01*
X620300Y760767D01*
X620883Y760600D01*
X621467Y760683D01*
X621967Y760933D01*
X622300Y761267D01*
G01X625233Y760600D02*
Y763933D01*
G01Y763267D02*
X625650Y763600D01*
X626067Y763850D01*
X626650Y763933D01*
X627067Y763850D01*
X627567Y763600D01*
G01X633500Y765600D02*
Y760600D01*
G01Y761350D02*
X633167Y760933D01*
X632667Y760683D01*
X632083Y760600D01*
X631417Y760767D01*
X630917Y761183D01*
X630583Y761683D01*
X630500Y762267D01*
X630583Y762850D01*
X630917Y763350D01*
X631417Y763767D01*
X632083Y763933D01*
X632667Y763850D01*
X633083Y763683D01*
X633500Y763350D01*
G01X636350Y761183D02*
X636767Y760850D01*
X637350Y760600D01*
X637850D01*
X638350Y760767D01*
X638683Y761017D01*
X638850Y761350D01*
X638767Y761850D01*
X638433Y762100D01*
X636933Y762600D01*
X636600Y763183D01*
X636767Y763600D01*
X637100Y763850D01*
X637600Y763933D01*
X638100Y763850D01*
X638600Y763600D01*
G01X643617Y758933D02*
X644450Y759767D01*
X644867Y760600D01*
Y763933D01*
X644450Y764767D01*
X643617Y765600D01*
G01X71000Y774600D02*
X73000D01*
G01X72000D02*
Y769600D01*
G01X71000D02*
X73000D01*
G01X75933D02*
Y774600D01*
X77933D01*
X78600Y774350D01*
X79100Y773767D01*
X79267Y773100D01*
X79100Y772433D01*
X78683Y771933D01*
X77933Y771683D01*
X75933D01*
G01X85033Y774183D02*
X84533Y774433D01*
X83950Y774600D01*
X83283D01*
X82533Y774350D01*
X81950Y773933D01*
X81533Y773433D01*
X81200Y772600D01*
X81117Y771850D01*
X81283Y771100D01*
X81533Y770600D01*
X82033Y770100D01*
X82617Y769767D01*
X83200Y769600D01*
X83783D01*
X84367Y769767D01*
X84867Y770017D01*
X85283Y770350D01*
G01X87717Y771267D02*
X89883D01*
G01X92817Y771683D02*
X93400Y772267D01*
X93900Y772600D01*
X94567Y772767D01*
X95150Y772600D01*
X95567Y772267D01*
X95900Y771767D01*
X95983Y771183D01*
X95900Y770683D01*
X95567Y770183D01*
X95067Y769767D01*
X94483Y769600D01*
X93817Y769767D01*
X93233Y770267D01*
X92900Y771017D01*
X92817Y771850D01*
X92983Y772933D01*
X93233Y773517D01*
X93650Y774100D01*
X94233Y774517D01*
X94817Y774600D01*
X95400Y774433D01*
X95817Y774017D01*
G01X100000Y774600D02*
X99333Y774433D01*
X98833Y774017D01*
X98500Y773517D01*
X98250Y772850D01*
X98167Y772100D01*
X98250Y771350D01*
X98500Y770683D01*
X98833Y770183D01*
X99333Y769767D01*
X100000Y769600D01*
X100667Y769767D01*
X101167Y770183D01*
X101500Y770683D01*
X101750Y771350D01*
X101833Y772100D01*
X101750Y772850D01*
X101500Y773517D01*
X101167Y774017D01*
X100667Y774433D01*
X100000Y774600D01*
G01X105600Y769600D02*
Y774600D01*
X104600Y773600D01*
G01Y769600D02*
X106600D01*
G01X109617Y773767D02*
X110117Y774267D01*
X110700Y774517D01*
X111367Y774600D01*
X112200Y774433D01*
X112783Y774017D01*
X112950Y773517D01*
X112867Y773017D01*
X112533Y772600D01*
X110867Y771767D01*
X110117Y771183D01*
X109617Y770350D01*
X109450Y769600D01*
X112950D01*
G01X122400D02*
X121733Y769683D01*
X121150Y770017D01*
X120650Y770517D01*
X120317Y771100D01*
X120150Y771767D01*
Y772433D01*
X120317Y773100D01*
X120650Y773683D01*
X121150Y774183D01*
X121733Y774517D01*
X122400Y774600D01*
X123067Y774517D01*
X123650Y774183D01*
X124150Y773683D01*
X124483Y773100D01*
X124650Y772433D01*
Y771767D01*
X124483Y771100D01*
X124150Y770517D01*
X123650Y770017D01*
X123067Y769683D01*
X122400Y769600D01*
G01X123067Y770933D02*
X124067Y769600D01*
G01X126583Y772933D02*
Y770600D01*
X126917Y770017D01*
X127417Y769683D01*
X128000Y769600D01*
X128583Y769683D01*
X129083Y770017D01*
X129417Y770600D01*
G01Y769600D02*
Y772933D01*
G01X135100Y769600D02*
Y772933D01*
G01Y772350D02*
X134767Y772683D01*
X134267Y772850D01*
X133683Y772933D01*
X133100Y772767D01*
X132600Y772433D01*
X132267Y771933D01*
X132100Y771267D01*
X132267Y770600D01*
X132600Y770100D01*
X133100Y769767D01*
X133683Y769600D01*
X134267Y769683D01*
X134767Y769933D01*
X135100Y770267D01*
G01X139200Y769600D02*
Y774600D01*
G01X144800Y772933D02*
Y769600D01*
G01Y774267D02*
X144633Y774350D01*
Y774517D01*
X144800Y774600D01*
X144967Y774517D01*
Y774350D01*
X144800Y774267D01*
G01X149900Y769600D02*
Y773850D01*
X150067Y774267D01*
X150400Y774517D01*
X150900Y774600D01*
X151400Y774433D01*
X151650Y774017D01*
G01X150650Y772600D02*
X148983D01*
G01X156000Y772933D02*
Y769600D01*
G01Y774267D02*
X155833Y774350D01*
Y774517D01*
X156000Y774600D01*
X156167Y774517D01*
Y774350D01*
X156000Y774267D01*
G01X162933Y772517D02*
X162350Y772850D01*
X161850Y772933D01*
X161183Y772767D01*
X160683Y772433D01*
X160350Y771850D01*
X160267Y771267D01*
X160350Y770683D01*
X160683Y770183D01*
X161183Y769767D01*
X161850Y769600D01*
X162433Y769767D01*
X162933Y770100D01*
G01X168700Y769600D02*
Y772933D01*
G01Y772350D02*
X168367Y772683D01*
X167867Y772850D01*
X167283Y772933D01*
X166700Y772767D01*
X166200Y772433D01*
X165867Y771933D01*
X165700Y771267D01*
X165867Y770600D01*
X166200Y770100D01*
X166700Y769767D01*
X167283Y769600D01*
X167867Y769683D01*
X168367Y769933D01*
X168700Y770267D01*
G01X172800Y774600D02*
Y769600D01*
G01X171633Y772933D02*
X173967D01*
G01X178400D02*
Y769600D01*
G01Y774267D02*
X178233Y774350D01*
Y774517D01*
X178400Y774600D01*
X178567Y774517D01*
Y774350D01*
X178400Y774267D01*
G01X184000Y769600D02*
X183500Y769683D01*
X183000Y770017D01*
X182667Y770600D01*
X182500Y771267D01*
X182667Y771933D01*
X183000Y772517D01*
X183500Y772850D01*
X184000Y772933D01*
X184500Y772850D01*
X185000Y772517D01*
X185333Y771933D01*
X185417Y771267D01*
X185333Y770600D01*
X185000Y770017D01*
X184500Y769683D01*
X184000Y769600D01*
G01X188183D02*
Y772933D01*
G01Y772100D02*
X188517Y772517D01*
X189017Y772850D01*
X189683Y772933D01*
X190267Y772850D01*
X190767Y772517D01*
X191017Y771933D01*
Y769600D01*
G01X202300D02*
Y772933D01*
G01Y772350D02*
X201967Y772683D01*
X201467Y772850D01*
X200883Y772933D01*
X200300Y772767D01*
X199800Y772433D01*
X199467Y771933D01*
X199300Y771267D01*
X199467Y770600D01*
X199800Y770100D01*
X200300Y769767D01*
X200883Y769600D01*
X201467Y769683D01*
X201967Y769933D01*
X202300Y770267D01*
G01X204983Y769600D02*
Y772933D01*
G01Y772100D02*
X205317Y772517D01*
X205817Y772850D01*
X206483Y772933D01*
X207067Y772850D01*
X207567Y772517D01*
X207817Y771933D01*
Y769600D01*
G01X213500Y774600D02*
Y769600D01*
G01Y770350D02*
X213167Y769933D01*
X212667Y769683D01*
X212083Y769600D01*
X211417Y769767D01*
X210917Y770183D01*
X210583Y770683D01*
X210500Y771267D01*
X210583Y771850D01*
X210917Y772350D01*
X211417Y772767D01*
X212083Y772933D01*
X212667Y772850D01*
X213083Y772683D01*
X213500Y772350D01*
G01X221533Y769600D02*
Y774600D01*
X223533D01*
X224200Y774350D01*
X224700Y773767D01*
X224867Y773100D01*
X224700Y772433D01*
X224283Y771933D01*
X223533Y771683D01*
X221533D01*
G01X227550Y771850D02*
X230217D01*
X229967Y772433D01*
X229550Y772767D01*
X228967Y772933D01*
X228383Y772850D01*
X227883Y772600D01*
X227550Y772017D01*
X227383Y771517D01*
Y771017D01*
X227550Y770517D01*
X227967Y770017D01*
X228467Y769683D01*
X229050Y769600D01*
X229633Y769767D01*
X230217Y770267D01*
G01X233233Y769600D02*
Y772933D01*
G01Y772267D02*
X233650Y772600D01*
X234067Y772850D01*
X234650Y772933D01*
X235067Y772850D01*
X235567Y772600D01*
G01X239500Y769600D02*
Y773850D01*
X239667Y774267D01*
X240000Y774517D01*
X240500Y774600D01*
X241000Y774433D01*
X241250Y774017D01*
G01X240250Y772600D02*
X238583D01*
G01X245600Y769600D02*
X245100Y769683D01*
X244600Y770017D01*
X244267Y770600D01*
X244100Y771267D01*
X244267Y771933D01*
X244600Y772517D01*
X245100Y772850D01*
X245600Y772933D01*
X246100Y772850D01*
X246600Y772517D01*
X246933Y771933D01*
X247017Y771267D01*
X246933Y770600D01*
X246600Y770017D01*
X246100Y769683D01*
X245600Y769600D01*
G01X250033D02*
Y772933D01*
G01Y772267D02*
X250450Y772600D01*
X250867Y772850D01*
X251450Y772933D01*
X251867Y772850D01*
X252367Y772600D01*
G01X254300Y769600D02*
Y772933D01*
G01Y772017D02*
X254550Y772433D01*
X254967Y772767D01*
X255550Y772933D01*
X256133Y772767D01*
X256550Y772433D01*
X256800Y772017D01*
Y769600D01*
G01Y772017D02*
X257050Y772433D01*
X257467Y772767D01*
X258050Y772933D01*
X258633Y772767D01*
X259050Y772433D01*
X259300Y771933D01*
Y769600D01*
G01X263900D02*
Y772933D01*
G01Y772350D02*
X263567Y772683D01*
X263067Y772850D01*
X262483Y772933D01*
X261900Y772767D01*
X261400Y772433D01*
X261067Y771933D01*
X260900Y771267D01*
X261067Y770600D01*
X261400Y770100D01*
X261900Y769767D01*
X262483Y769600D01*
X263067Y769683D01*
X263567Y769933D01*
X263900Y770267D01*
G01X266583Y769600D02*
Y772933D01*
G01Y772100D02*
X266917Y772517D01*
X267417Y772850D01*
X268083Y772933D01*
X268667Y772850D01*
X269167Y772517D01*
X269417Y771933D01*
Y769600D01*
G01X274933Y772517D02*
X274350Y772850D01*
X273850Y772933D01*
X273183Y772767D01*
X272683Y772433D01*
X272350Y771850D01*
X272267Y771267D01*
X272350Y770683D01*
X272683Y770183D01*
X273183Y769767D01*
X273850Y769600D01*
X274433Y769767D01*
X274933Y770100D01*
G01X277950Y771850D02*
X280617D01*
X280367Y772433D01*
X279950Y772767D01*
X279367Y772933D01*
X278783Y772850D01*
X278283Y772600D01*
X277950Y772017D01*
X277783Y771517D01*
Y771017D01*
X277950Y770517D01*
X278367Y770017D01*
X278867Y769683D01*
X279450Y769600D01*
X280033Y769767D01*
X280617Y770267D01*
G01X288650D02*
X289317Y769850D01*
X290067Y769600D01*
X290733D01*
X291400Y769850D01*
X291900Y770267D01*
X292150Y770850D01*
X291983Y771433D01*
X291567Y771933D01*
X290817Y772267D01*
X289817Y772433D01*
X289233Y772767D01*
X288983Y773350D01*
X289150Y773933D01*
X289567Y774350D01*
X290150Y774600D01*
X290733D01*
X291317Y774433D01*
X291817Y774017D01*
G01X294500Y767933D02*
Y772933D01*
G01Y772183D02*
X294917Y772600D01*
X295333Y772850D01*
X296000Y772933D01*
X296583Y772850D01*
X297167Y772433D01*
X297417Y771850D01*
X297500Y771267D01*
X297417Y770683D01*
X297167Y770100D01*
X296667Y769767D01*
X296000Y769600D01*
X295417Y769683D01*
X294833Y769933D01*
X294500Y770267D01*
G01X300350Y771850D02*
X303017D01*
X302767Y772433D01*
X302350Y772767D01*
X301767Y772933D01*
X301183Y772850D01*
X300683Y772600D01*
X300350Y772017D01*
X300183Y771517D01*
Y771017D01*
X300350Y770517D01*
X300767Y770017D01*
X301267Y769683D01*
X301850Y769600D01*
X302433Y769767D01*
X303017Y770267D01*
G01X308533Y772517D02*
X307950Y772850D01*
X307450Y772933D01*
X306783Y772767D01*
X306283Y772433D01*
X305950Y771850D01*
X305867Y771267D01*
X305950Y770683D01*
X306283Y770183D01*
X306783Y769767D01*
X307450Y769600D01*
X308033Y769767D01*
X308533Y770100D01*
G01X312800Y772933D02*
Y769600D01*
G01Y774267D02*
X312633Y774350D01*
Y774517D01*
X312800Y774600D01*
X312967Y774517D01*
Y774350D01*
X312800Y774267D01*
G01X317900Y769600D02*
Y773850D01*
X318067Y774267D01*
X318400Y774517D01*
X318900Y774600D01*
X319400Y774433D01*
X319650Y774017D01*
G01X318650Y772600D02*
X316983D01*
G01X324000Y772933D02*
Y769600D01*
G01Y774267D02*
X323833Y774350D01*
Y774517D01*
X324000Y774600D01*
X324167Y774517D01*
Y774350D01*
X324000Y774267D01*
G01X330933Y772517D02*
X330350Y772850D01*
X329850Y772933D01*
X329183Y772767D01*
X328683Y772433D01*
X328350Y771850D01*
X328267Y771267D01*
X328350Y770683D01*
X328683Y770183D01*
X329183Y769767D01*
X329850Y769600D01*
X330433Y769767D01*
X330933Y770100D01*
G01X336700Y769600D02*
Y772933D01*
G01Y772350D02*
X336367Y772683D01*
X335867Y772850D01*
X335283Y772933D01*
X334700Y772767D01*
X334200Y772433D01*
X333867Y771933D01*
X333700Y771267D01*
X333867Y770600D01*
X334200Y770100D01*
X334700Y769767D01*
X335283Y769600D01*
X335867Y769683D01*
X336367Y769933D01*
X336700Y770267D01*
G01X340800Y774600D02*
Y769600D01*
G01X339633Y772933D02*
X341967D01*
G01X346400D02*
Y769600D01*
G01Y774267D02*
X346233Y774350D01*
Y774517D01*
X346400Y774600D01*
X346567Y774517D01*
Y774350D01*
X346400Y774267D01*
G01X352000Y769600D02*
X351500Y769683D01*
X351000Y770017D01*
X350667Y770600D01*
X350500Y771267D01*
X350667Y771933D01*
X351000Y772517D01*
X351500Y772850D01*
X352000Y772933D01*
X352500Y772850D01*
X353000Y772517D01*
X353333Y771933D01*
X353417Y771267D01*
X353333Y770600D01*
X353000Y770017D01*
X352500Y769683D01*
X352000Y769600D01*
G01X356183D02*
Y772933D01*
G01Y772100D02*
X356517Y772517D01*
X357017Y772850D01*
X357683Y772933D01*
X358267Y772850D01*
X358767Y772517D01*
X359017Y771933D01*
Y769600D01*
G01X368300D02*
Y773850D01*
X368467Y774267D01*
X368800Y774517D01*
X369300Y774600D01*
X369800Y774433D01*
X370050Y774017D01*
G01X369050Y772600D02*
X367383D01*
G01X374400Y769600D02*
X373900Y769683D01*
X373400Y770017D01*
X373067Y770600D01*
X372900Y771267D01*
X373067Y771933D01*
X373400Y772517D01*
X373900Y772850D01*
X374400Y772933D01*
X374900Y772850D01*
X375400Y772517D01*
X375733Y771933D01*
X375817Y771267D01*
X375733Y770600D01*
X375400Y770017D01*
X374900Y769683D01*
X374400Y769600D01*
G01X378833D02*
Y772933D01*
G01Y772267D02*
X379250Y772600D01*
X379667Y772850D01*
X380250Y772933D01*
X380667Y772850D01*
X381167Y772600D01*
G01X389533Y769600D02*
Y774600D01*
X391617D01*
X392283Y774350D01*
X392700Y774017D01*
X392867Y773350D01*
X392700Y772683D01*
X392200Y772267D01*
X391617Y772017D01*
X389533D01*
G01X391617D02*
X392867Y769600D01*
G01X396800Y772933D02*
Y769600D01*
G01Y774267D02*
X396633Y774350D01*
Y774517D01*
X396800Y774600D01*
X396967Y774517D01*
Y774350D01*
X396800Y774267D01*
G01X401233Y768350D02*
X401817Y768017D01*
X402483Y767933D01*
X403067Y768017D01*
X403567Y768433D01*
X403900Y769017D01*
Y772933D01*
G01Y772267D02*
X403567Y772600D01*
X403067Y772850D01*
X402483Y772933D01*
X401817Y772767D01*
X401400Y772433D01*
X401067Y771850D01*
X400900Y771267D01*
X400983Y770767D01*
X401317Y770183D01*
X401817Y769767D01*
X402483Y769600D01*
X402983Y769683D01*
X403567Y770017D01*
X403900Y770350D01*
G01X408000Y772933D02*
Y769600D01*
G01Y774267D02*
X407833Y774350D01*
Y774517D01*
X408000Y774600D01*
X408167Y774517D01*
Y774350D01*
X408000Y774267D01*
G01X415100Y774600D02*
Y769600D01*
G01Y770350D02*
X414767Y769933D01*
X414267Y769683D01*
X413683Y769600D01*
X413017Y769767D01*
X412517Y770183D01*
X412183Y770683D01*
X412100Y771267D01*
X412183Y771850D01*
X412517Y772350D01*
X413017Y772767D01*
X413683Y772933D01*
X414267Y772850D01*
X414683Y772683D01*
X415100Y772350D01*
G01X423133Y769600D02*
Y774600D01*
X425133D01*
X425800Y774350D01*
X426300Y773767D01*
X426467Y773100D01*
X426300Y772433D01*
X425883Y771933D01*
X425133Y771683D01*
X423133D01*
G01X429233Y769600D02*
Y772933D01*
G01Y772267D02*
X429650Y772600D01*
X430067Y772850D01*
X430650Y772933D01*
X431067Y772850D01*
X431567Y772600D01*
G01X436000Y772933D02*
Y769600D01*
G01Y774267D02*
X435833Y774350D01*
Y774517D01*
X436000Y774600D01*
X436167Y774517D01*
Y774350D01*
X436000Y774267D01*
G01X440183Y769600D02*
Y772933D01*
G01Y772100D02*
X440517Y772517D01*
X441017Y772850D01*
X441683Y772933D01*
X442267Y772850D01*
X442767Y772517D01*
X443017Y771933D01*
Y769600D01*
G01X447200Y774600D02*
Y769600D01*
G01X446033Y772933D02*
X448367D01*
G01X451550Y771850D02*
X454217D01*
X453967Y772433D01*
X453550Y772767D01*
X452967Y772933D01*
X452383Y772850D01*
X451883Y772600D01*
X451550Y772017D01*
X451383Y771517D01*
Y771017D01*
X451550Y770517D01*
X451967Y770017D01*
X452467Y769683D01*
X453050Y769600D01*
X453633Y769767D01*
X454217Y770267D01*
G01X459900Y774600D02*
Y769600D01*
G01Y770350D02*
X459567Y769933D01*
X459067Y769683D01*
X458483Y769600D01*
X457817Y769767D01*
X457317Y770183D01*
X456983Y770683D01*
X456900Y771267D01*
X456983Y771850D01*
X457317Y772350D01*
X457817Y772767D01*
X458483Y772933D01*
X459067Y772850D01*
X459483Y772683D01*
X459900Y772350D01*
G01X470267Y772267D02*
X470600Y772517D01*
X470850Y772933D01*
X471017Y773517D01*
X470850Y774017D01*
X470517Y774350D01*
X469933Y774600D01*
X467683D01*
Y769600D01*
X470433D01*
X471017Y769933D01*
X471350Y770433D01*
X471517Y771017D01*
X471350Y771600D01*
X470850Y772100D01*
X470267Y772267D01*
X467683D01*
G01X475200Y769600D02*
X474700Y769683D01*
X474200Y770017D01*
X473867Y770600D01*
X473700Y771267D01*
X473867Y771933D01*
X474200Y772517D01*
X474700Y772850D01*
X475200Y772933D01*
X475700Y772850D01*
X476200Y772517D01*
X476533Y771933D01*
X476617Y771267D01*
X476533Y770600D01*
X476200Y770017D01*
X475700Y769683D01*
X475200Y769600D01*
G01X482300D02*
Y772933D01*
G01Y772350D02*
X481967Y772683D01*
X481467Y772850D01*
X480883Y772933D01*
X480300Y772767D01*
X479800Y772433D01*
X479467Y771933D01*
X479300Y771267D01*
X479467Y770600D01*
X479800Y770100D01*
X480300Y769767D01*
X480883Y769600D01*
X481467Y769683D01*
X481967Y769933D01*
X482300Y770267D01*
G01X485233Y769600D02*
Y772933D01*
G01Y772267D02*
X485650Y772600D01*
X486067Y772850D01*
X486650Y772933D01*
X487067Y772850D01*
X487567Y772600D01*
G01X493500Y774600D02*
Y769600D01*
G01Y770350D02*
X493167Y769933D01*
X492667Y769683D01*
X492083Y769600D01*
X491417Y769767D01*
X490917Y770183D01*
X490583Y770683D01*
X490500Y771267D01*
X490583Y771850D01*
X490917Y772350D01*
X491417Y772767D01*
X492083Y772933D01*
X492667Y772850D01*
X493083Y772683D01*
X493500Y772350D01*
G01X496350Y770183D02*
X496767Y769850D01*
X497350Y769600D01*
X497850D01*
X498350Y769767D01*
X498683Y770017D01*
X498850Y770350D01*
X498767Y770850D01*
X498433Y771100D01*
X496933Y771600D01*
X496600Y772183D01*
X496767Y772600D01*
X497100Y772850D01*
X497600Y772933D01*
X498100Y772850D01*
X498600Y772600D01*
G01X57000Y802500D02*
X59000D01*
G01X58000D02*
Y797500D01*
G01X57000D02*
X59000D01*
G01X63100D02*
Y801750D01*
X63267Y802167D01*
X63600Y802417D01*
X64100Y802500D01*
X64600Y802333D01*
X64850Y801917D01*
G01X63850Y800500D02*
X62183D01*
G01X74800Y802500D02*
Y797500D01*
G01X73633Y800833D02*
X75967D01*
G01X78983Y797500D02*
Y802500D01*
G01Y800083D02*
X79400Y800500D01*
X79817Y800750D01*
X80483Y800833D01*
X80983Y800750D01*
X81567Y800417D01*
X81817Y799917D01*
Y797500D01*
G01X84750Y799750D02*
X87417D01*
X87167Y800333D01*
X86750Y800667D01*
X86167Y800833D01*
X85583Y800750D01*
X85083Y800500D01*
X84750Y799917D01*
X84583Y799417D01*
Y798917D01*
X84750Y798417D01*
X85167Y797917D01*
X85667Y797583D01*
X86250Y797500D01*
X86833Y797667D01*
X87417Y798167D01*
G01X98533Y800417D02*
X97950Y800750D01*
X97450Y800833D01*
X96783Y800667D01*
X96283Y800333D01*
X95950Y799750D01*
X95867Y799167D01*
X95950Y798583D01*
X96283Y798083D01*
X96783Y797667D01*
X97450Y797500D01*
X98033Y797667D01*
X98533Y798000D01*
G01X101633Y797500D02*
Y800833D01*
G01Y800167D02*
X102050Y800500D01*
X102467Y800750D01*
X103050Y800833D01*
X103467Y800750D01*
X103967Y800500D01*
G01X108400Y800833D02*
Y797500D01*
G01Y802167D02*
X108233Y802250D01*
Y802417D01*
X108400Y802500D01*
X108567Y802417D01*
Y802250D01*
X108400Y802167D01*
G01X114000Y802500D02*
Y797500D01*
G01X112833Y800833D02*
X115167D01*
G01X118350Y799750D02*
X121017D01*
X120767Y800333D01*
X120350Y800667D01*
X119767Y800833D01*
X119183Y800750D01*
X118683Y800500D01*
X118350Y799917D01*
X118183Y799417D01*
Y798917D01*
X118350Y798417D01*
X118767Y797917D01*
X119267Y797583D01*
X119850Y797500D01*
X120433Y797667D01*
X121017Y798167D01*
G01X124033Y797500D02*
Y800833D01*
G01Y800167D02*
X124450Y800500D01*
X124867Y800750D01*
X125450Y800833D01*
X125867Y800750D01*
X126367Y800500D01*
G01X130800Y800833D02*
Y797500D01*
G01Y802167D02*
X130633Y802250D01*
Y802417D01*
X130800Y802500D01*
X130967Y802417D01*
Y802250D01*
X130800Y802167D01*
G01X137900Y797500D02*
Y800833D01*
G01Y800250D02*
X137567Y800583D01*
X137067Y800750D01*
X136483Y800833D01*
X135900Y800667D01*
X135400Y800333D01*
X135067Y799833D01*
X134900Y799167D01*
X135067Y798500D01*
X135400Y798000D01*
X135900Y797667D01*
X136483Y797500D01*
X137067Y797583D01*
X137567Y797833D01*
X137900Y798167D01*
G01X147600Y800833D02*
Y797500D01*
G01Y802167D02*
X147433Y802250D01*
Y802417D01*
X147600Y802500D01*
X147767Y802417D01*
Y802250D01*
X147600Y802167D01*
G01X151950Y798083D02*
X152367Y797750D01*
X152950Y797500D01*
X153450D01*
X153950Y797667D01*
X154283Y797917D01*
X154450Y798250D01*
X154367Y798750D01*
X154033Y799000D01*
X152533Y799500D01*
X152200Y800083D01*
X152367Y800500D01*
X152700Y800750D01*
X153200Y800833D01*
X153700Y800750D01*
X154200Y800500D01*
G01X162983Y797500D02*
Y800833D01*
G01Y800000D02*
X163317Y800417D01*
X163817Y800750D01*
X164483Y800833D01*
X165067Y800750D01*
X165567Y800417D01*
X165817Y799833D01*
Y797500D01*
G01X170000D02*
X169500Y797583D01*
X169000Y797917D01*
X168667Y798500D01*
X168500Y799167D01*
X168667Y799833D01*
X169000Y800417D01*
X169500Y800750D01*
X170000Y800833D01*
X170500Y800750D01*
X171000Y800417D01*
X171333Y799833D01*
X171417Y799167D01*
X171333Y798500D01*
X171000Y797917D01*
X170500Y797583D01*
X170000Y797500D01*
G01X175600Y802500D02*
Y797500D01*
G01X174433Y800833D02*
X176767D01*
G01X185550Y798083D02*
X185967Y797750D01*
X186550Y797500D01*
X187050D01*
X187550Y797667D01*
X187883Y797917D01*
X188050Y798250D01*
X187967Y798750D01*
X187633Y799000D01*
X186133Y799500D01*
X185800Y800083D01*
X185967Y800500D01*
X186300Y800750D01*
X186800Y800833D01*
X187300Y800750D01*
X187800Y800500D01*
G01X190900Y795833D02*
Y800833D01*
G01Y800083D02*
X191317Y800500D01*
X191733Y800750D01*
X192400Y800833D01*
X192983Y800750D01*
X193567Y800333D01*
X193817Y799750D01*
X193900Y799167D01*
X193817Y798583D01*
X193567Y798000D01*
X193067Y797667D01*
X192400Y797500D01*
X191817Y797583D01*
X191233Y797833D01*
X190900Y798167D01*
G01X196750Y799750D02*
X199417D01*
X199167Y800333D01*
X198750Y800667D01*
X198167Y800833D01*
X197583Y800750D01*
X197083Y800500D01*
X196750Y799917D01*
X196583Y799417D01*
Y798917D01*
X196750Y798417D01*
X197167Y797917D01*
X197667Y797583D01*
X198250Y797500D01*
X198833Y797667D01*
X199417Y798167D01*
G01X204933Y800417D02*
X204350Y800750D01*
X203850Y800833D01*
X203183Y800667D01*
X202683Y800333D01*
X202350Y799750D01*
X202267Y799167D01*
X202350Y798583D01*
X202683Y798083D01*
X203183Y797667D01*
X203850Y797500D01*
X204433Y797667D01*
X204933Y798000D01*
G01X209200Y800833D02*
Y797500D01*
G01Y802167D02*
X209033Y802250D01*
Y802417D01*
X209200Y802500D01*
X209367Y802417D01*
Y802250D01*
X209200Y802167D01*
G01X214300Y797500D02*
Y801750D01*
X214467Y802167D01*
X214800Y802417D01*
X215300Y802500D01*
X215800Y802333D01*
X216050Y801917D01*
G01X215050Y800500D02*
X213383D01*
G01X220400Y800833D02*
Y797500D01*
G01Y802167D02*
X220233Y802250D01*
Y802417D01*
X220400Y802500D01*
X220567Y802417D01*
Y802250D01*
X220400Y802167D01*
G01X224750Y799750D02*
X227417D01*
X227167Y800333D01*
X226750Y800667D01*
X226167Y800833D01*
X225583Y800750D01*
X225083Y800500D01*
X224750Y799917D01*
X224583Y799417D01*
Y798917D01*
X224750Y798417D01*
X225167Y797917D01*
X225667Y797583D01*
X226250Y797500D01*
X226833Y797667D01*
X227417Y798167D01*
G01X233100Y802500D02*
Y797500D01*
G01Y798250D02*
X232767Y797833D01*
X232267Y797583D01*
X231683Y797500D01*
X231017Y797667D01*
X230517Y798083D01*
X230183Y798583D01*
X230100Y799167D01*
X230183Y799750D01*
X230517Y800250D01*
X231017Y800667D01*
X231683Y800833D01*
X232267Y800750D01*
X232683Y800583D01*
X233100Y800250D01*
G01X242800Y800833D02*
Y797500D01*
G01Y802167D02*
X242633Y802250D01*
Y802417D01*
X242800Y802500D01*
X242967Y802417D01*
Y802250D01*
X242800Y802167D01*
G01X246983Y797500D02*
Y800833D01*
G01Y800000D02*
X247317Y800417D01*
X247817Y800750D01*
X248483Y800833D01*
X249067Y800750D01*
X249567Y800417D01*
X249817Y799833D01*
Y797500D01*
G01X259600Y802500D02*
Y797500D01*
G01X258433Y800833D02*
X260767D01*
G01X263783Y797500D02*
Y802500D01*
G01Y800083D02*
X264200Y800500D01*
X264617Y800750D01*
X265283Y800833D01*
X265783Y800750D01*
X266367Y800417D01*
X266617Y799917D01*
Y797500D01*
G01X269550Y799750D02*
X272217D01*
X271967Y800333D01*
X271550Y800667D01*
X270967Y800833D01*
X270383Y800750D01*
X269883Y800500D01*
X269550Y799917D01*
X269383Y799417D01*
Y798917D01*
X269550Y798417D01*
X269967Y797917D01*
X270467Y797583D01*
X271050Y797500D01*
X271633Y797667D01*
X272217Y798167D01*
G01X282000Y802500D02*
Y797500D01*
G01X280833Y800833D02*
X283167D01*
G01X289100Y797500D02*
Y800833D01*
G01Y800250D02*
X288767Y800583D01*
X288267Y800750D01*
X287683Y800833D01*
X287100Y800667D01*
X286600Y800333D01*
X286267Y799833D01*
X286100Y799167D01*
X286267Y798500D01*
X286600Y798000D01*
X287100Y797667D01*
X287683Y797500D01*
X288267Y797583D01*
X288767Y797833D01*
X289100Y798167D01*
G01X291700Y797500D02*
Y802500D01*
G01Y800000D02*
X292117Y800500D01*
X292617Y800750D01*
X293117Y800833D01*
X293867Y800667D01*
X294367Y800333D01*
X294700Y799750D01*
Y799083D01*
X294533Y798417D01*
X294200Y797917D01*
X293617Y797583D01*
X293117Y797500D01*
X292617Y797583D01*
X292117Y797833D01*
X291700Y798250D01*
G01X298800Y797500D02*
Y802500D01*
G01X303150Y799750D02*
X305817D01*
X305567Y800333D01*
X305150Y800667D01*
X304567Y800833D01*
X303983Y800750D01*
X303483Y800500D01*
X303150Y799917D01*
X302983Y799417D01*
Y798917D01*
X303150Y798417D01*
X303567Y797917D01*
X304067Y797583D01*
X304650Y797500D01*
X305233Y797667D01*
X305817Y798167D01*
G01X310000Y797333D02*
X309833Y797417D01*
Y797583D01*
X310000Y797667D01*
X310167Y797583D01*
Y797417D01*
X310000Y797333D01*
G01Y799583D02*
X309833Y799667D01*
Y799833D01*
X310000Y799917D01*
X310167Y799833D01*
Y799667D01*
X310000Y799583D01*
G01X67000Y779433D02*
X66833Y779517D01*
Y779683D01*
X67000Y779767D01*
X67167Y779683D01*
Y779517D01*
X67000Y779433D01*
G01Y786333D02*
X66833Y786417D01*
Y786583D01*
X67000Y786667D01*
X67167Y786583D01*
Y786417D01*
X67000Y786333D01*
G01X71000Y783600D02*
X73000D01*
G01X72000D02*
Y778600D01*
G01X71000D02*
X73000D01*
G01X75933D02*
Y783600D01*
X77933D01*
X78600Y783350D01*
X79100Y782767D01*
X79267Y782100D01*
X79100Y781433D01*
X78683Y780933D01*
X77933Y780683D01*
X75933D01*
G01X85033Y783183D02*
X84533Y783433D01*
X83950Y783600D01*
X83283D01*
X82533Y783350D01*
X81950Y782933D01*
X81533Y782433D01*
X81200Y781600D01*
X81117Y780850D01*
X81283Y780100D01*
X81533Y779600D01*
X82033Y779100D01*
X82617Y778767D01*
X83200Y778600D01*
X83783D01*
X84367Y778767D01*
X84867Y779017D01*
X85283Y779350D01*
G01X87717Y780267D02*
X89883D01*
G01X92817Y780683D02*
X93400Y781267D01*
X93900Y781600D01*
X94567Y781767D01*
X95150Y781600D01*
X95567Y781267D01*
X95900Y780767D01*
X95983Y780183D01*
X95900Y779683D01*
X95567Y779183D01*
X95067Y778767D01*
X94483Y778600D01*
X93817Y778767D01*
X93233Y779267D01*
X92900Y780017D01*
X92817Y780850D01*
X92983Y781933D01*
X93233Y782517D01*
X93650Y783100D01*
X94233Y783517D01*
X94817Y783600D01*
X95400Y783433D01*
X95817Y783017D01*
G01X100000Y783600D02*
X99333Y783433D01*
X98833Y783017D01*
X98500Y782517D01*
X98250Y781850D01*
X98167Y781100D01*
X98250Y780350D01*
X98500Y779683D01*
X98833Y779183D01*
X99333Y778767D01*
X100000Y778600D01*
X100667Y778767D01*
X101167Y779183D01*
X101500Y779683D01*
X101750Y780350D01*
X101833Y781100D01*
X101750Y781850D01*
X101500Y782517D01*
X101167Y783017D01*
X100667Y783433D01*
X100000Y783600D01*
G01X105600Y778600D02*
Y783600D01*
X104600Y782600D01*
G01Y778600D02*
X106600D01*
G01X111200D02*
Y783600D01*
X110200Y782600D01*
G01Y778600D02*
X112200D01*
G01X122900Y781100D02*
X124567D01*
Y779600D01*
X124067Y779100D01*
X123483Y778767D01*
X122650Y778600D01*
X121817Y778767D01*
X121233Y779100D01*
X120733Y779600D01*
X120400Y780183D01*
X120233Y780850D01*
Y781433D01*
X120400Y781933D01*
X120733Y782517D01*
X121233Y783017D01*
X121733Y783350D01*
X122400Y783600D01*
X122983D01*
X123650Y783433D01*
X124150Y783100D01*
G01X126750Y780850D02*
X129417D01*
X129167Y781433D01*
X128750Y781767D01*
X128167Y781933D01*
X127583Y781850D01*
X127083Y781600D01*
X126750Y781017D01*
X126583Y780517D01*
Y780017D01*
X126750Y779517D01*
X127167Y779017D01*
X127667Y778683D01*
X128250Y778600D01*
X128833Y778767D01*
X129417Y779267D01*
G01X132183Y778600D02*
Y781933D01*
G01Y781100D02*
X132517Y781517D01*
X133017Y781850D01*
X133683Y781933D01*
X134267Y781850D01*
X134767Y781517D01*
X135017Y780933D01*
Y778600D01*
G01X137950Y780850D02*
X140617D01*
X140367Y781433D01*
X139950Y781767D01*
X139367Y781933D01*
X138783Y781850D01*
X138283Y781600D01*
X137950Y781017D01*
X137783Y780517D01*
Y780017D01*
X137950Y779517D01*
X138367Y779017D01*
X138867Y778683D01*
X139450Y778600D01*
X140033Y778767D01*
X140617Y779267D01*
G01X143633Y778600D02*
Y781933D01*
G01Y781267D02*
X144050Y781600D01*
X144467Y781850D01*
X145050Y781933D01*
X145467Y781850D01*
X145967Y781600D01*
G01X150400Y781933D02*
Y778600D01*
G01Y783267D02*
X150233Y783350D01*
Y783517D01*
X150400Y783600D01*
X150567Y783517D01*
Y783350D01*
X150400Y783267D01*
G01X157333Y781517D02*
X156750Y781850D01*
X156250Y781933D01*
X155583Y781767D01*
X155083Y781433D01*
X154750Y780850D01*
X154667Y780267D01*
X154750Y779683D01*
X155083Y779183D01*
X155583Y778767D01*
X156250Y778600D01*
X156833Y778767D01*
X157333Y779100D01*
G01X165533Y778600D02*
Y783600D01*
X167533D01*
X168200Y783350D01*
X168700Y782767D01*
X168867Y782100D01*
X168700Y781433D01*
X168283Y780933D01*
X167533Y780683D01*
X165533D01*
G01X171550Y780850D02*
X174217D01*
X173967Y781433D01*
X173550Y781767D01*
X172967Y781933D01*
X172383Y781850D01*
X171883Y781600D01*
X171550Y781017D01*
X171383Y780517D01*
Y780017D01*
X171550Y779517D01*
X171967Y779017D01*
X172467Y778683D01*
X173050Y778600D01*
X173633Y778767D01*
X174217Y779267D01*
G01X177233Y778600D02*
Y781933D01*
G01Y781267D02*
X177650Y781600D01*
X178067Y781850D01*
X178650Y781933D01*
X179067Y781850D01*
X179567Y781600D01*
G01X183500Y778600D02*
Y782850D01*
X183667Y783267D01*
X184000Y783517D01*
X184500Y783600D01*
X185000Y783433D01*
X185250Y783017D01*
G01X184250Y781600D02*
X182583D01*
G01X189600Y778600D02*
X189100Y778683D01*
X188600Y779017D01*
X188267Y779600D01*
X188100Y780267D01*
X188267Y780933D01*
X188600Y781517D01*
X189100Y781850D01*
X189600Y781933D01*
X190100Y781850D01*
X190600Y781517D01*
X190933Y780933D01*
X191017Y780267D01*
X190933Y779600D01*
X190600Y779017D01*
X190100Y778683D01*
X189600Y778600D01*
G01X194033D02*
Y781933D01*
G01Y781267D02*
X194450Y781600D01*
X194867Y781850D01*
X195450Y781933D01*
X195867Y781850D01*
X196367Y781600D01*
G01X198300Y778600D02*
Y781933D01*
G01Y781017D02*
X198550Y781433D01*
X198967Y781767D01*
X199550Y781933D01*
X200133Y781767D01*
X200550Y781433D01*
X200800Y781017D01*
Y778600D01*
G01Y781017D02*
X201050Y781433D01*
X201467Y781767D01*
X202050Y781933D01*
X202633Y781767D01*
X203050Y781433D01*
X203300Y780933D01*
Y778600D01*
G01X207900D02*
Y781933D01*
G01Y781350D02*
X207567Y781683D01*
X207067Y781850D01*
X206483Y781933D01*
X205900Y781767D01*
X205400Y781433D01*
X205067Y780933D01*
X204900Y780267D01*
X205067Y779600D01*
X205400Y779100D01*
X205900Y778767D01*
X206483Y778600D01*
X207067Y778683D01*
X207567Y778933D01*
X207900Y779267D01*
G01X210583Y778600D02*
Y781933D01*
G01Y781100D02*
X210917Y781517D01*
X211417Y781850D01*
X212083Y781933D01*
X212667Y781850D01*
X213167Y781517D01*
X213417Y780933D01*
Y778600D01*
G01X218933Y781517D02*
X218350Y781850D01*
X217850Y781933D01*
X217183Y781767D01*
X216683Y781433D01*
X216350Y780850D01*
X216267Y780267D01*
X216350Y779683D01*
X216683Y779183D01*
X217183Y778767D01*
X217850Y778600D01*
X218433Y778767D01*
X218933Y779100D01*
G01X221950Y780850D02*
X224617D01*
X224367Y781433D01*
X223950Y781767D01*
X223367Y781933D01*
X222783Y781850D01*
X222283Y781600D01*
X221950Y781017D01*
X221783Y780517D01*
Y780017D01*
X221950Y779517D01*
X222367Y779017D01*
X222867Y778683D01*
X223450Y778600D01*
X224033Y778767D01*
X224617Y779267D01*
G01X232650D02*
X233317Y778850D01*
X234067Y778600D01*
X234733D01*
X235400Y778850D01*
X235900Y779267D01*
X236150Y779850D01*
X235983Y780433D01*
X235567Y780933D01*
X234817Y781267D01*
X233817Y781433D01*
X233233Y781767D01*
X232983Y782350D01*
X233150Y782933D01*
X233567Y783350D01*
X234150Y783600D01*
X234733D01*
X235317Y783433D01*
X235817Y783017D01*
G01X238500Y776933D02*
Y781933D01*
G01Y781183D02*
X238917Y781600D01*
X239333Y781850D01*
X240000Y781933D01*
X240583Y781850D01*
X241167Y781433D01*
X241417Y780850D01*
X241500Y780267D01*
X241417Y779683D01*
X241167Y779100D01*
X240667Y778767D01*
X240000Y778600D01*
X239417Y778683D01*
X238833Y778933D01*
X238500Y779267D01*
G01X244350Y780850D02*
X247017D01*
X246767Y781433D01*
X246350Y781767D01*
X245767Y781933D01*
X245183Y781850D01*
X244683Y781600D01*
X244350Y781017D01*
X244183Y780517D01*
Y780017D01*
X244350Y779517D01*
X244767Y779017D01*
X245267Y778683D01*
X245850Y778600D01*
X246433Y778767D01*
X247017Y779267D01*
G01X252533Y781517D02*
X251950Y781850D01*
X251450Y781933D01*
X250783Y781767D01*
X250283Y781433D01*
X249950Y780850D01*
X249867Y780267D01*
X249950Y779683D01*
X250283Y779183D01*
X250783Y778767D01*
X251450Y778600D01*
X252033Y778767D01*
X252533Y779100D01*
G01X256800Y781933D02*
Y778600D01*
G01Y783267D02*
X256633Y783350D01*
Y783517D01*
X256800Y783600D01*
X256967Y783517D01*
Y783350D01*
X256800Y783267D01*
G01X261900Y778600D02*
Y782850D01*
X262067Y783267D01*
X262400Y783517D01*
X262900Y783600D01*
X263400Y783433D01*
X263650Y783017D01*
G01X262650Y781600D02*
X260983D01*
G01X268000Y781933D02*
Y778600D01*
G01Y783267D02*
X267833Y783350D01*
Y783517D01*
X268000Y783600D01*
X268167Y783517D01*
Y783350D01*
X268000Y783267D01*
G01X274933Y781517D02*
X274350Y781850D01*
X273850Y781933D01*
X273183Y781767D01*
X272683Y781433D01*
X272350Y780850D01*
X272267Y780267D01*
X272350Y779683D01*
X272683Y779183D01*
X273183Y778767D01*
X273850Y778600D01*
X274433Y778767D01*
X274933Y779100D01*
G01X280700Y778600D02*
Y781933D01*
G01Y781350D02*
X280367Y781683D01*
X279867Y781850D01*
X279283Y781933D01*
X278700Y781767D01*
X278200Y781433D01*
X277867Y780933D01*
X277700Y780267D01*
X277867Y779600D01*
X278200Y779100D01*
X278700Y778767D01*
X279283Y778600D01*
X279867Y778683D01*
X280367Y778933D01*
X280700Y779267D01*
G01X284800Y783600D02*
Y778600D01*
G01X283633Y781933D02*
X285967D01*
G01X290400D02*
Y778600D01*
G01Y783267D02*
X290233Y783350D01*
Y783517D01*
X290400Y783600D01*
X290567Y783517D01*
Y783350D01*
X290400Y783267D01*
G01X296000Y778600D02*
X295500Y778683D01*
X295000Y779017D01*
X294667Y779600D01*
X294500Y780267D01*
X294667Y780933D01*
X295000Y781517D01*
X295500Y781850D01*
X296000Y781933D01*
X296500Y781850D01*
X297000Y781517D01*
X297333Y780933D01*
X297417Y780267D01*
X297333Y779600D01*
X297000Y779017D01*
X296500Y778683D01*
X296000Y778600D01*
G01X300183D02*
Y781933D01*
G01Y781100D02*
X300517Y781517D01*
X301017Y781850D01*
X301683Y781933D01*
X302267Y781850D01*
X302767Y781517D01*
X303017Y780933D01*
Y778600D01*
G01X312300D02*
Y782850D01*
X312467Y783267D01*
X312800Y783517D01*
X313300Y783600D01*
X313800Y783433D01*
X314050Y783017D01*
G01X313050Y781600D02*
X311383D01*
G01X318400Y778600D02*
X317900Y778683D01*
X317400Y779017D01*
X317067Y779600D01*
X316900Y780267D01*
X317067Y780933D01*
X317400Y781517D01*
X317900Y781850D01*
X318400Y781933D01*
X318900Y781850D01*
X319400Y781517D01*
X319733Y780933D01*
X319817Y780267D01*
X319733Y779600D01*
X319400Y779017D01*
X318900Y778683D01*
X318400Y778600D01*
G01X322833D02*
Y781933D01*
G01Y781267D02*
X323250Y781600D01*
X323667Y781850D01*
X324250Y781933D01*
X324667Y781850D01*
X325167Y781600D01*
G01X333533Y778600D02*
Y783600D01*
X335533D01*
X336200Y783350D01*
X336700Y782767D01*
X336867Y782100D01*
X336700Y781433D01*
X336283Y780933D01*
X335533Y780683D01*
X333533D01*
G01X339633Y778600D02*
Y781933D01*
G01Y781267D02*
X340050Y781600D01*
X340467Y781850D01*
X341050Y781933D01*
X341467Y781850D01*
X341967Y781600D01*
G01X346400Y781933D02*
Y778600D01*
G01Y783267D02*
X346233Y783350D01*
Y783517D01*
X346400Y783600D01*
X346567Y783517D01*
Y783350D01*
X346400Y783267D01*
G01X350583Y778600D02*
Y781933D01*
G01Y781100D02*
X350917Y781517D01*
X351417Y781850D01*
X352083Y781933D01*
X352667Y781850D01*
X353167Y781517D01*
X353417Y780933D01*
Y778600D01*
G01X357600Y783600D02*
Y778600D01*
G01X356433Y781933D02*
X358767D01*
G01X361950Y780850D02*
X364617D01*
X364367Y781433D01*
X363950Y781767D01*
X363367Y781933D01*
X362783Y781850D01*
X362283Y781600D01*
X361950Y781017D01*
X361783Y780517D01*
Y780017D01*
X361950Y779517D01*
X362367Y779017D01*
X362867Y778683D01*
X363450Y778600D01*
X364033Y778767D01*
X364617Y779267D01*
G01X370300Y783600D02*
Y778600D01*
G01Y779350D02*
X369967Y778933D01*
X369467Y778683D01*
X368883Y778600D01*
X368217Y778767D01*
X367717Y779183D01*
X367383Y779683D01*
X367300Y780267D01*
X367383Y780850D01*
X367717Y781350D01*
X368217Y781767D01*
X368883Y781933D01*
X369467Y781850D01*
X369883Y781683D01*
X370300Y781350D01*
G01X380667Y781267D02*
X381000Y781517D01*
X381250Y781933D01*
X381417Y782517D01*
X381250Y783017D01*
X380917Y783350D01*
X380333Y783600D01*
X378083D01*
Y778600D01*
X380833D01*
X381417Y778933D01*
X381750Y779433D01*
X381917Y780017D01*
X381750Y780600D01*
X381250Y781100D01*
X380667Y781267D01*
X378083D01*
G01X385600Y778600D02*
X385100Y778683D01*
X384600Y779017D01*
X384267Y779600D01*
X384100Y780267D01*
X384267Y780933D01*
X384600Y781517D01*
X385100Y781850D01*
X385600Y781933D01*
X386100Y781850D01*
X386600Y781517D01*
X386933Y780933D01*
X387017Y780267D01*
X386933Y779600D01*
X386600Y779017D01*
X386100Y778683D01*
X385600Y778600D01*
G01X392700D02*
Y781933D01*
G01Y781350D02*
X392367Y781683D01*
X391867Y781850D01*
X391283Y781933D01*
X390700Y781767D01*
X390200Y781433D01*
X389867Y780933D01*
X389700Y780267D01*
X389867Y779600D01*
X390200Y779100D01*
X390700Y778767D01*
X391283Y778600D01*
X391867Y778683D01*
X392367Y778933D01*
X392700Y779267D01*
G01X395633Y778600D02*
Y781933D01*
G01Y781267D02*
X396050Y781600D01*
X396467Y781850D01*
X397050Y781933D01*
X397467Y781850D01*
X397967Y781600D01*
G01X403900Y783600D02*
Y778600D01*
G01Y779350D02*
X403567Y778933D01*
X403067Y778683D01*
X402483Y778600D01*
X401817Y778767D01*
X401317Y779183D01*
X400983Y779683D01*
X400900Y780267D01*
X400983Y780850D01*
X401317Y781350D01*
X401817Y781767D01*
X402483Y781933D01*
X403067Y781850D01*
X403483Y781683D01*
X403900Y781350D01*
G01X406750Y779183D02*
X407167Y778850D01*
X407750Y778600D01*
X408250D01*
X408750Y778767D01*
X409083Y779017D01*
X409250Y779350D01*
X409167Y779850D01*
X408833Y780100D01*
X407333Y780600D01*
X407000Y781183D01*
X407167Y781600D01*
X407500Y781850D01*
X408000Y781933D01*
X408500Y781850D01*
X409000Y781600D01*
G01X71000Y791500D02*
X73000D01*
G01X72000D02*
Y786500D01*
G01X71000D02*
X73000D01*
G01X75933D02*
Y791500D01*
X77933D01*
X78600Y791250D01*
X79100Y790667D01*
X79267Y790000D01*
X79100Y789333D01*
X78683Y788833D01*
X77933Y788583D01*
X75933D01*
G01X85033Y791083D02*
X84533Y791333D01*
X83950Y791500D01*
X83283D01*
X82533Y791250D01*
X81950Y790833D01*
X81533Y790333D01*
X81200Y789500D01*
X81117Y788750D01*
X81283Y788000D01*
X81533Y787500D01*
X82033Y787000D01*
X82617Y786667D01*
X83200Y786500D01*
X83783D01*
X84367Y786667D01*
X84867Y786917D01*
X85283Y787250D01*
G01X87717Y788167D02*
X89883D01*
G01X92317Y786500D02*
X94400Y791500D01*
X96483Y786500D01*
G01X95733Y788250D02*
X93067D01*
G01X98917Y788167D02*
X101083D01*
G01X104017Y788583D02*
X104600Y789167D01*
X105100Y789500D01*
X105767Y789667D01*
X106350Y789500D01*
X106767Y789167D01*
X107100Y788667D01*
X107183Y788083D01*
X107100Y787583D01*
X106767Y787083D01*
X106267Y786667D01*
X105683Y786500D01*
X105017Y786667D01*
X104433Y787167D01*
X104100Y787917D01*
X104017Y788750D01*
X104183Y789833D01*
X104433Y790417D01*
X104850Y791000D01*
X105433Y791417D01*
X106017Y791500D01*
X106600Y791333D01*
X107017Y790917D01*
G01X111200Y791500D02*
X110533Y791333D01*
X110033Y790917D01*
X109700Y790417D01*
X109450Y789750D01*
X109367Y789000D01*
X109450Y788250D01*
X109700Y787583D01*
X110033Y787083D01*
X110533Y786667D01*
X111200Y786500D01*
X111867Y786667D01*
X112367Y787083D01*
X112700Y787583D01*
X112950Y788250D01*
X113033Y789000D01*
X112950Y789750D01*
X112700Y790417D01*
X112367Y790917D01*
X111867Y791333D01*
X111200Y791500D01*
G01X116800D02*
X116133Y791333D01*
X115633Y790917D01*
X115300Y790417D01*
X115050Y789750D01*
X114967Y789000D01*
X115050Y788250D01*
X115300Y787583D01*
X115633Y787083D01*
X116133Y786667D01*
X116800Y786500D01*
X117467Y786667D01*
X117967Y787083D01*
X118300Y787583D01*
X118550Y788250D01*
X118633Y789000D01*
X118550Y789750D01*
X118300Y790417D01*
X117967Y790917D01*
X117467Y791333D01*
X116800Y791500D01*
G01X125917Y786500D02*
X128000Y791500D01*
X130083Y786500D01*
G01X129333Y788250D02*
X126667D01*
G01X134933Y789417D02*
X134350Y789750D01*
X133850Y789833D01*
X133183Y789667D01*
X132683Y789333D01*
X132350Y788750D01*
X132267Y788167D01*
X132350Y787583D01*
X132683Y787083D01*
X133183Y786667D01*
X133850Y786500D01*
X134433Y786667D01*
X134933Y787000D01*
G01X140533Y789417D02*
X139950Y789750D01*
X139450Y789833D01*
X138783Y789667D01*
X138283Y789333D01*
X137950Y788750D01*
X137867Y788167D01*
X137950Y787583D01*
X138283Y787083D01*
X138783Y786667D01*
X139450Y786500D01*
X140033Y786667D01*
X140533Y787000D01*
G01X143550Y788750D02*
X146217D01*
X145967Y789333D01*
X145550Y789667D01*
X144967Y789833D01*
X144383Y789750D01*
X143883Y789500D01*
X143550Y788917D01*
X143383Y788417D01*
Y787917D01*
X143550Y787417D01*
X143967Y786917D01*
X144467Y786583D01*
X145050Y786500D01*
X145633Y786667D01*
X146217Y787167D01*
G01X148900Y784833D02*
Y789833D01*
G01Y789083D02*
X149317Y789500D01*
X149733Y789750D01*
X150400Y789833D01*
X150983Y789750D01*
X151567Y789333D01*
X151817Y788750D01*
X151900Y788167D01*
X151817Y787583D01*
X151567Y787000D01*
X151067Y786667D01*
X150400Y786500D01*
X149817Y786583D01*
X149233Y786833D01*
X148900Y787167D01*
G01X156000Y791500D02*
Y786500D01*
G01X154833Y789833D02*
X157167D01*
G01X163100Y786500D02*
Y789833D01*
G01Y789250D02*
X162767Y789583D01*
X162267Y789750D01*
X161683Y789833D01*
X161100Y789667D01*
X160600Y789333D01*
X160267Y788833D01*
X160100Y788167D01*
X160267Y787500D01*
X160600Y787000D01*
X161100Y786667D01*
X161683Y786500D01*
X162267Y786583D01*
X162767Y786833D01*
X163100Y787167D01*
G01X165700Y786500D02*
Y791500D01*
G01Y789000D02*
X166117Y789500D01*
X166617Y789750D01*
X167117Y789833D01*
X167867Y789667D01*
X168367Y789333D01*
X168700Y788750D01*
Y788083D01*
X168533Y787417D01*
X168200Y786917D01*
X167617Y786583D01*
X167117Y786500D01*
X166617Y786583D01*
X166117Y786833D01*
X165700Y787250D01*
G01X172800Y789833D02*
Y786500D01*
G01Y791167D02*
X172633Y791250D01*
Y791417D01*
X172800Y791500D01*
X172967Y791417D01*
Y791250D01*
X172800Y791167D01*
G01X178400Y786500D02*
Y791500D01*
G01X184000Y789833D02*
Y786500D01*
G01Y791167D02*
X183833Y791250D01*
Y791417D01*
X184000Y791500D01*
X184167Y791417D01*
Y791250D01*
X184000Y791167D01*
G01X189600Y791500D02*
Y786500D01*
G01X188433Y789833D02*
X190767D01*
G01X193450Y785000D02*
X193950Y784833D01*
X194617Y785000D01*
X195033Y785333D01*
X195367Y785750D01*
X195867Y787083D01*
X196950Y789833D01*
G01X194283D02*
X195867Y787083D01*
G01X206400Y786500D02*
X205900Y786583D01*
X205400Y786917D01*
X205067Y787500D01*
X204900Y788167D01*
X205067Y788833D01*
X205400Y789417D01*
X205900Y789750D01*
X206400Y789833D01*
X206900Y789750D01*
X207400Y789417D01*
X207733Y788833D01*
X207817Y788167D01*
X207733Y787500D01*
X207400Y786917D01*
X206900Y786583D01*
X206400Y786500D01*
G01X211500D02*
Y790750D01*
X211667Y791167D01*
X212000Y791417D01*
X212500Y791500D01*
X213000Y791333D01*
X213250Y790917D01*
G01X212250Y789500D02*
X210583D01*
G01X221533Y786500D02*
Y791500D01*
X223533D01*
X224200Y791250D01*
X224700Y790667D01*
X224867Y790000D01*
X224700Y789333D01*
X224283Y788833D01*
X223533Y788583D01*
X221533D01*
G01X227633Y786500D02*
Y789833D01*
G01Y789167D02*
X228050Y789500D01*
X228467Y789750D01*
X229050Y789833D01*
X229467Y789750D01*
X229967Y789500D01*
G01X234400Y789833D02*
Y786500D01*
G01Y791167D02*
X234233Y791250D01*
Y791417D01*
X234400Y791500D01*
X234567Y791417D01*
Y791250D01*
X234400Y791167D01*
G01X238583Y786500D02*
Y789833D01*
G01Y789000D02*
X238917Y789417D01*
X239417Y789750D01*
X240083Y789833D01*
X240667Y789750D01*
X241167Y789417D01*
X241417Y788833D01*
Y786500D01*
G01X245600Y791500D02*
Y786500D01*
G01X244433Y789833D02*
X246767D01*
G01X249950Y788750D02*
X252617D01*
X252367Y789333D01*
X251950Y789667D01*
X251367Y789833D01*
X250783Y789750D01*
X250283Y789500D01*
X249950Y788917D01*
X249783Y788417D01*
Y787917D01*
X249950Y787417D01*
X250367Y786917D01*
X250867Y786583D01*
X251450Y786500D01*
X252033Y786667D01*
X252617Y787167D01*
G01X258300Y791500D02*
Y786500D01*
G01Y787250D02*
X257967Y786833D01*
X257467Y786583D01*
X256883Y786500D01*
X256217Y786667D01*
X255717Y787083D01*
X255383Y787583D01*
X255300Y788167D01*
X255383Y788750D01*
X255717Y789250D01*
X256217Y789667D01*
X256883Y789833D01*
X257467Y789750D01*
X257883Y789583D01*
X258300Y789250D01*
G01X268667Y789167D02*
X269000Y789417D01*
X269250Y789833D01*
X269417Y790417D01*
X269250Y790917D01*
X268917Y791250D01*
X268333Y791500D01*
X266083D01*
Y786500D01*
X268833D01*
X269417Y786833D01*
X269750Y787333D01*
X269917Y787917D01*
X269750Y788500D01*
X269250Y789000D01*
X268667Y789167D01*
X266083D01*
G01X273600Y786500D02*
X273100Y786583D01*
X272600Y786917D01*
X272267Y787500D01*
X272100Y788167D01*
X272267Y788833D01*
X272600Y789417D01*
X273100Y789750D01*
X273600Y789833D01*
X274100Y789750D01*
X274600Y789417D01*
X274933Y788833D01*
X275017Y788167D01*
X274933Y787500D01*
X274600Y786917D01*
X274100Y786583D01*
X273600Y786500D01*
G01X280700D02*
Y789833D01*
G01Y789250D02*
X280367Y789583D01*
X279867Y789750D01*
X279283Y789833D01*
X278700Y789667D01*
X278200Y789333D01*
X277867Y788833D01*
X277700Y788167D01*
X277867Y787500D01*
X278200Y787000D01*
X278700Y786667D01*
X279283Y786500D01*
X279867Y786583D01*
X280367Y786833D01*
X280700Y787167D01*
G01X283633Y786500D02*
Y789833D01*
G01Y789167D02*
X284050Y789500D01*
X284467Y789750D01*
X285050Y789833D01*
X285467Y789750D01*
X285967Y789500D01*
G01X291900Y791500D02*
Y786500D01*
G01Y787250D02*
X291567Y786833D01*
X291067Y786583D01*
X290483Y786500D01*
X289817Y786667D01*
X289317Y787083D01*
X288983Y787583D01*
X288900Y788167D01*
X288983Y788750D01*
X289317Y789250D01*
X289817Y789667D01*
X290483Y789833D01*
X291067Y789750D01*
X291483Y789583D01*
X291900Y789250D01*
G01X294750Y787083D02*
X295167Y786750D01*
X295750Y786500D01*
X296250D01*
X296750Y786667D01*
X297083Y786917D01*
X297250Y787250D01*
X297167Y787750D01*
X296833Y788000D01*
X295333Y788500D01*
X295000Y789083D01*
X295167Y789500D01*
X295500Y789750D01*
X296000Y789833D01*
X296500Y789750D01*
X297000Y789500D01*
G01X57833Y806500D02*
Y811500D01*
X59833D01*
X60500Y811250D01*
X61000Y810667D01*
X61167Y810000D01*
X61000Y809333D01*
X60583Y808833D01*
X59833Y808583D01*
X57833D01*
G01X65100Y806500D02*
Y811500D01*
G01X69450Y808750D02*
X72117D01*
X71867Y809333D01*
X71450Y809667D01*
X70867Y809833D01*
X70283Y809750D01*
X69783Y809500D01*
X69450Y808917D01*
X69283Y808417D01*
Y807917D01*
X69450Y807417D01*
X69867Y806917D01*
X70367Y806583D01*
X70950Y806500D01*
X71533Y806667D01*
X72117Y807167D01*
G01X77800Y806500D02*
Y809833D01*
G01Y809250D02*
X77467Y809583D01*
X76967Y809750D01*
X76383Y809833D01*
X75800Y809667D01*
X75300Y809333D01*
X74967Y808833D01*
X74800Y808167D01*
X74967Y807500D01*
X75300Y807000D01*
X75800Y806667D01*
X76383Y806500D01*
X76967Y806583D01*
X77467Y806833D01*
X77800Y807167D01*
G01X80650Y807083D02*
X81067Y806750D01*
X81650Y806500D01*
X82150D01*
X82650Y806667D01*
X82983Y806917D01*
X83150Y807250D01*
X83067Y807750D01*
X82733Y808000D01*
X81233Y808500D01*
X80900Y809083D01*
X81067Y809500D01*
X81400Y809750D01*
X81900Y809833D01*
X82400Y809750D01*
X82900Y809500D01*
G01X86250Y808750D02*
X88917D01*
X88667Y809333D01*
X88250Y809667D01*
X87667Y809833D01*
X87083Y809750D01*
X86583Y809500D01*
X86250Y808917D01*
X86083Y808417D01*
Y807917D01*
X86250Y807417D01*
X86667Y806917D01*
X87167Y806583D01*
X87750Y806500D01*
X88333Y806667D01*
X88917Y807167D01*
G01X98200Y806500D02*
Y810750D01*
X98367Y811167D01*
X98700Y811417D01*
X99200Y811500D01*
X99700Y811333D01*
X99950Y810917D01*
G01X98950Y809500D02*
X97283D01*
G01X104300Y806500D02*
X103800Y806583D01*
X103300Y806917D01*
X102967Y807500D01*
X102800Y808167D01*
X102967Y808833D01*
X103300Y809417D01*
X103800Y809750D01*
X104300Y809833D01*
X104800Y809750D01*
X105300Y809417D01*
X105633Y808833D01*
X105717Y808167D01*
X105633Y807500D01*
X105300Y806917D01*
X104800Y806583D01*
X104300Y806500D01*
G01X109900D02*
Y811500D01*
G01X115500Y806500D02*
Y811500D01*
G01X121100Y806500D02*
X120600Y806583D01*
X120100Y806917D01*
X119767Y807500D01*
X119600Y808167D01*
X119767Y808833D01*
X120100Y809417D01*
X120600Y809750D01*
X121100Y809833D01*
X121600Y809750D01*
X122100Y809417D01*
X122433Y808833D01*
X122517Y808167D01*
X122433Y807500D01*
X122100Y806917D01*
X121600Y806583D01*
X121100Y806500D01*
G01X124617Y809833D02*
X125617Y806500D01*
X126700Y809833D01*
X127783Y806500D01*
X128783Y809833D01*
G01X137900Y811500D02*
Y806500D01*
G01X136733Y809833D02*
X139067D01*
G01X142083Y806500D02*
Y811500D01*
G01Y809083D02*
X142500Y809500D01*
X142917Y809750D01*
X143583Y809833D01*
X144083Y809750D01*
X144667Y809417D01*
X144917Y808917D01*
Y806500D01*
G01X147850Y808750D02*
X150517D01*
X150267Y809333D01*
X149850Y809667D01*
X149267Y809833D01*
X148683Y809750D01*
X148183Y809500D01*
X147850Y808917D01*
X147683Y808417D01*
Y807917D01*
X147850Y807417D01*
X148267Y806917D01*
X148767Y806583D01*
X149350Y806500D01*
X149933Y806667D01*
X150517Y807167D01*
G01X159050Y807083D02*
X159467Y806750D01*
X160050Y806500D01*
X160550D01*
X161050Y806667D01*
X161383Y806917D01*
X161550Y807250D01*
X161467Y807750D01*
X161133Y808000D01*
X159633Y808500D01*
X159300Y809083D01*
X159467Y809500D01*
X159800Y809750D01*
X160300Y809833D01*
X160800Y809750D01*
X161300Y809500D01*
G01X164400Y804833D02*
Y809833D01*
G01Y809083D02*
X164817Y809500D01*
X165233Y809750D01*
X165900Y809833D01*
X166483Y809750D01*
X167067Y809333D01*
X167317Y808750D01*
X167400Y808167D01*
X167317Y807583D01*
X167067Y807000D01*
X166567Y806667D01*
X165900Y806500D01*
X165317Y806583D01*
X164733Y806833D01*
X164400Y807167D01*
G01X170250Y808750D02*
X172917D01*
X172667Y809333D01*
X172250Y809667D01*
X171667Y809833D01*
X171083Y809750D01*
X170583Y809500D01*
X170250Y808917D01*
X170083Y808417D01*
Y807917D01*
X170250Y807417D01*
X170667Y806917D01*
X171167Y806583D01*
X171750Y806500D01*
X172333Y806667D01*
X172917Y807167D01*
G01X178433Y809417D02*
X177850Y809750D01*
X177350Y809833D01*
X176683Y809667D01*
X176183Y809333D01*
X175850Y808750D01*
X175767Y808167D01*
X175850Y807583D01*
X176183Y807083D01*
X176683Y806667D01*
X177350Y806500D01*
X177933Y806667D01*
X178433Y807000D01*
G01X182700Y809833D02*
Y806500D01*
G01Y811167D02*
X182533Y811250D01*
Y811417D01*
X182700Y811500D01*
X182867Y811417D01*
Y811250D01*
X182700Y811167D01*
G01X187800Y806500D02*
Y810750D01*
X187967Y811167D01*
X188300Y811417D01*
X188800Y811500D01*
X189300Y811333D01*
X189550Y810917D01*
G01X188550Y809500D02*
X186883D01*
G01X193900Y809833D02*
Y806500D01*
G01Y811167D02*
X193733Y811250D01*
Y811417D01*
X193900Y811500D01*
X194067Y811417D01*
Y811250D01*
X193900Y811167D01*
G01X200833Y809417D02*
X200250Y809750D01*
X199750Y809833D01*
X199083Y809667D01*
X198583Y809333D01*
X198250Y808750D01*
X198167Y808167D01*
X198250Y807583D01*
X198583Y807083D01*
X199083Y806667D01*
X199750Y806500D01*
X200333Y806667D01*
X200833Y807000D01*
G01X206600Y806500D02*
Y809833D01*
G01Y809250D02*
X206267Y809583D01*
X205767Y809750D01*
X205183Y809833D01*
X204600Y809667D01*
X204100Y809333D01*
X203767Y808833D01*
X203600Y808167D01*
X203767Y807500D01*
X204100Y807000D01*
X204600Y806667D01*
X205183Y806500D01*
X205767Y806583D01*
X206267Y806833D01*
X206600Y807167D01*
G01X210700Y811500D02*
Y806500D01*
G01X209533Y809833D02*
X211867D01*
G01X216300D02*
Y806500D01*
G01Y811167D02*
X216133Y811250D01*
Y811417D01*
X216300Y811500D01*
X216467Y811417D01*
Y811250D01*
X216300Y811167D01*
G01X221900Y806500D02*
X221400Y806583D01*
X220900Y806917D01*
X220567Y807500D01*
X220400Y808167D01*
X220567Y808833D01*
X220900Y809417D01*
X221400Y809750D01*
X221900Y809833D01*
X222400Y809750D01*
X222900Y809417D01*
X223233Y808833D01*
X223317Y808167D01*
X223233Y807500D01*
X222900Y806917D01*
X222400Y806583D01*
X221900Y806500D01*
G01X226083D02*
Y809833D01*
G01Y809000D02*
X226417Y809417D01*
X226917Y809750D01*
X227583Y809833D01*
X228167Y809750D01*
X228667Y809417D01*
X228917Y808833D01*
Y806500D01*
G01X240200Y811500D02*
Y806500D01*
G01Y807250D02*
X239867Y806833D01*
X239367Y806583D01*
X238783Y806500D01*
X238117Y806667D01*
X237617Y807083D01*
X237283Y807583D01*
X237200Y808167D01*
X237283Y808750D01*
X237617Y809250D01*
X238117Y809667D01*
X238783Y809833D01*
X239367Y809750D01*
X239783Y809583D01*
X240200Y809250D01*
G01X244300Y806500D02*
X243800Y806583D01*
X243300Y806917D01*
X242967Y807500D01*
X242800Y808167D01*
X242967Y808833D01*
X243300Y809417D01*
X243800Y809750D01*
X244300Y809833D01*
X244800Y809750D01*
X245300Y809417D01*
X245633Y808833D01*
X245717Y808167D01*
X245633Y807500D01*
X245300Y806917D01*
X244800Y806583D01*
X244300Y806500D01*
G01X251233Y809417D02*
X250650Y809750D01*
X250150Y809833D01*
X249483Y809667D01*
X248983Y809333D01*
X248650Y808750D01*
X248567Y808167D01*
X248650Y807583D01*
X248983Y807083D01*
X249483Y806667D01*
X250150Y806500D01*
X250733Y806667D01*
X251233Y807000D01*
G01X254083Y809833D02*
Y807500D01*
X254417Y806917D01*
X254917Y806583D01*
X255500Y806500D01*
X256083Y806583D01*
X256583Y806917D01*
X256917Y807500D01*
G01Y806500D02*
Y809833D01*
G01X258600Y806500D02*
Y809833D01*
G01Y808917D02*
X258850Y809333D01*
X259267Y809667D01*
X259850Y809833D01*
X260433Y809667D01*
X260850Y809333D01*
X261100Y808917D01*
Y806500D01*
G01Y808917D02*
X261350Y809333D01*
X261767Y809667D01*
X262350Y809833D01*
X262933Y809667D01*
X263350Y809333D01*
X263600Y808833D01*
Y806500D01*
G01X265450Y808750D02*
X268117D01*
X267867Y809333D01*
X267450Y809667D01*
X266867Y809833D01*
X266283Y809750D01*
X265783Y809500D01*
X265450Y808917D01*
X265283Y808417D01*
Y807917D01*
X265450Y807417D01*
X265867Y806917D01*
X266367Y806583D01*
X266950Y806500D01*
X267533Y806667D01*
X268117Y807167D01*
G01X270883Y806500D02*
Y809833D01*
G01Y809000D02*
X271217Y809417D01*
X271717Y809750D01*
X272383Y809833D01*
X272967Y809750D01*
X273467Y809417D01*
X273717Y808833D01*
Y806500D01*
G01X277900Y811500D02*
Y806500D01*
G01X276733Y809833D02*
X279067D01*
G01X282250Y807083D02*
X282667Y806750D01*
X283250Y806500D01*
X283750D01*
X284250Y806667D01*
X284583Y806917D01*
X284750Y807250D01*
X284667Y807750D01*
X284333Y808000D01*
X282833Y808500D01*
X282500Y809083D01*
X282667Y809500D01*
X283000Y809750D01*
X283500Y809833D01*
X284000Y809750D01*
X284500Y809500D01*
G01X294700Y809833D02*
Y806500D01*
G01Y811167D02*
X294533Y811250D01*
Y811417D01*
X294700Y811500D01*
X294867Y811417D01*
Y811250D01*
X294700Y811167D01*
G01X298883Y806500D02*
Y809833D01*
G01Y809000D02*
X299217Y809417D01*
X299717Y809750D01*
X300383Y809833D01*
X300967Y809750D01*
X301467Y809417D01*
X301717Y808833D01*
Y806500D01*
G01X312833Y809417D02*
X312250Y809750D01*
X311750Y809833D01*
X311083Y809667D01*
X310583Y809333D01*
X310250Y808750D01*
X310167Y808167D01*
X310250Y807583D01*
X310583Y807083D01*
X311083Y806667D01*
X311750Y806500D01*
X312333Y806667D01*
X312833Y807000D01*
G01X317100Y806500D02*
Y811500D01*
G01X324200Y806500D02*
Y809833D01*
G01Y809250D02*
X323867Y809583D01*
X323367Y809750D01*
X322783Y809833D01*
X322200Y809667D01*
X321700Y809333D01*
X321367Y808833D01*
X321200Y808167D01*
X321367Y807500D01*
X321700Y807000D01*
X322200Y806667D01*
X322783Y806500D01*
X323367Y806583D01*
X323867Y806833D01*
X324200Y807167D01*
G01X327050Y807083D02*
X327467Y806750D01*
X328050Y806500D01*
X328550D01*
X329050Y806667D01*
X329383Y806917D01*
X329550Y807250D01*
X329467Y807750D01*
X329133Y808000D01*
X327633Y808500D01*
X327300Y809083D01*
X327467Y809500D01*
X327800Y809750D01*
X328300Y809833D01*
X328800Y809750D01*
X329300Y809500D01*
G01X332650Y807083D02*
X333067Y806750D01*
X333650Y806500D01*
X334150D01*
X334650Y806667D01*
X334983Y806917D01*
X335150Y807250D01*
X335067Y807750D01*
X334733Y808000D01*
X333233Y808500D01*
X332900Y809083D01*
X333067Y809500D01*
X333400Y809750D01*
X333900Y809833D01*
X334400Y809750D01*
X334900Y809500D01*
G01X343517Y810667D02*
X344017Y811167D01*
X344600Y811417D01*
X345267Y811500D01*
X346100Y811333D01*
X346683Y810917D01*
X346850Y810417D01*
X346767Y809917D01*
X346433Y809500D01*
X344767Y808667D01*
X344017Y808083D01*
X343517Y807250D01*
X343350Y806500D01*
X346850D01*
G01X357800D02*
Y809833D01*
G01Y809250D02*
X357467Y809583D01*
X356967Y809750D01*
X356383Y809833D01*
X355800Y809667D01*
X355300Y809333D01*
X354967Y808833D01*
X354800Y808167D01*
X354967Y807500D01*
X355300Y807000D01*
X355800Y806667D01*
X356383Y806500D01*
X356967Y806583D01*
X357467Y806833D01*
X357800Y807167D01*
G01X360483Y806500D02*
Y809833D01*
G01Y809000D02*
X360817Y809417D01*
X361317Y809750D01*
X361983Y809833D01*
X362567Y809750D01*
X363067Y809417D01*
X363317Y808833D01*
Y806500D01*
G01X369000Y811500D02*
Y806500D01*
G01Y807250D02*
X368667Y806833D01*
X368167Y806583D01*
X367583Y806500D01*
X366917Y806667D01*
X366417Y807083D01*
X366083Y807583D01*
X366000Y808167D01*
X366083Y808750D01*
X366417Y809250D01*
X366917Y809667D01*
X367583Y809833D01*
X368167Y809750D01*
X368583Y809583D01*
X369000Y809250D01*
G01X378700Y811500D02*
Y806500D01*
G01X377533Y809833D02*
X379867D01*
G01X382883Y806500D02*
Y811500D01*
G01Y809083D02*
X383300Y809500D01*
X383717Y809750D01*
X384383Y809833D01*
X384883Y809750D01*
X385467Y809417D01*
X385717Y808917D01*
Y806500D01*
G01X388650Y808750D02*
X391317D01*
X391067Y809333D01*
X390650Y809667D01*
X390067Y809833D01*
X389483Y809750D01*
X388983Y809500D01*
X388650Y808917D01*
X388483Y808417D01*
Y807917D01*
X388650Y807417D01*
X389067Y806917D01*
X389567Y806583D01*
X390150Y806500D01*
X390733Y806667D01*
X391317Y807167D01*
G01X401100Y806500D02*
Y811500D01*
G01X408200Y806500D02*
Y809833D01*
G01Y809250D02*
X407867Y809583D01*
X407367Y809750D01*
X406783Y809833D01*
X406200Y809667D01*
X405700Y809333D01*
X405367Y808833D01*
X405200Y808167D01*
X405367Y807500D01*
X405700Y807000D01*
X406200Y806667D01*
X406783Y806500D01*
X407367Y806583D01*
X407867Y806833D01*
X408200Y807167D01*
G01X412300Y811500D02*
Y806500D01*
G01X411133Y809833D02*
X413467D01*
G01X416650Y808750D02*
X419317D01*
X419067Y809333D01*
X418650Y809667D01*
X418067Y809833D01*
X417483Y809750D01*
X416983Y809500D01*
X416650Y808917D01*
X416483Y808417D01*
Y807917D01*
X416650Y807417D01*
X417067Y806917D01*
X417567Y806583D01*
X418150Y806500D01*
X418733Y806667D01*
X419317Y807167D01*
G01X422250Y807083D02*
X422667Y806750D01*
X423250Y806500D01*
X423750D01*
X424250Y806667D01*
X424583Y806917D01*
X424750Y807250D01*
X424667Y807750D01*
X424333Y808000D01*
X422833Y808500D01*
X422500Y809083D01*
X422667Y809500D01*
X423000Y809750D01*
X423500Y809833D01*
X424000Y809750D01*
X424500Y809500D01*
G01X429100Y811500D02*
Y806500D01*
G01X427933Y809833D02*
X430267D01*
G01X438800D02*
X440300Y806500D01*
X441800Y809833D01*
G01X444650Y808750D02*
X447317D01*
X447067Y809333D01*
X446650Y809667D01*
X446067Y809833D01*
X445483Y809750D01*
X444983Y809500D01*
X444650Y808917D01*
X444483Y808417D01*
Y807917D01*
X444650Y807417D01*
X445067Y806917D01*
X445567Y806583D01*
X446150Y806500D01*
X446733Y806667D01*
X447317Y807167D01*
G01X450333Y806500D02*
Y809833D01*
G01Y809167D02*
X450750Y809500D01*
X451167Y809750D01*
X451750Y809833D01*
X452167Y809750D01*
X452667Y809500D01*
G01X455850Y807083D02*
X456267Y806750D01*
X456850Y806500D01*
X457350D01*
X457850Y806667D01*
X458183Y806917D01*
X458350Y807250D01*
X458267Y807750D01*
X457933Y808000D01*
X456433Y808500D01*
X456100Y809083D01*
X456267Y809500D01*
X456600Y809750D01*
X457100Y809833D01*
X457600Y809750D01*
X458100Y809500D01*
G01X462700Y809833D02*
Y806500D01*
G01Y811167D02*
X462533Y811250D01*
Y811417D01*
X462700Y811500D01*
X462867Y811417D01*
Y811250D01*
X462700Y811167D01*
G01X468300Y806500D02*
X467800Y806583D01*
X467300Y806917D01*
X466967Y807500D01*
X466800Y808167D01*
X466967Y808833D01*
X467300Y809417D01*
X467800Y809750D01*
X468300Y809833D01*
X468800Y809750D01*
X469300Y809417D01*
X469633Y808833D01*
X469717Y808167D01*
X469633Y807500D01*
X469300Y806917D01*
X468800Y806583D01*
X468300Y806500D01*
G01X472483D02*
Y809833D01*
G01Y809000D02*
X472817Y809417D01*
X473317Y809750D01*
X473983Y809833D01*
X474567Y809750D01*
X475067Y809417D01*
X475317Y808833D01*
Y806500D01*
G01X485100Y809833D02*
Y806500D01*
G01Y811167D02*
X484933Y811250D01*
Y811417D01*
X485100Y811500D01*
X485267Y811417D01*
Y811250D01*
X485100Y811167D01*
G01X489450Y807083D02*
X489867Y806750D01*
X490450Y806500D01*
X490950D01*
X491450Y806667D01*
X491783Y806917D01*
X491950Y807250D01*
X491867Y807750D01*
X491533Y808000D01*
X490033Y808500D01*
X489700Y809083D01*
X489867Y809500D01*
X490200Y809750D01*
X490700Y809833D01*
X491200Y809750D01*
X491700Y809500D01*
G01X500733Y806500D02*
Y809833D01*
G01Y809167D02*
X501150Y809500D01*
X501567Y809750D01*
X502150Y809833D01*
X502567Y809750D01*
X503067Y809500D01*
G01X506250Y808750D02*
X508917D01*
X508667Y809333D01*
X508250Y809667D01*
X507667Y809833D01*
X507083Y809750D01*
X506583Y809500D01*
X506250Y808917D01*
X506083Y808417D01*
Y807917D01*
X506250Y807417D01*
X506667Y806917D01*
X507167Y806583D01*
X507750Y806500D01*
X508333Y806667D01*
X508917Y807167D01*
G01X514600Y804833D02*
Y809833D01*
G01Y809083D02*
X514183Y809500D01*
X513683Y809750D01*
X513100Y809833D01*
X512600Y809750D01*
X512017Y809333D01*
X511683Y808750D01*
X511600Y808167D01*
X511683Y807583D01*
X512017Y807000D01*
X512600Y806583D01*
X513100Y806500D01*
X513683Y806583D01*
X514183Y806833D01*
X514600Y807250D01*
G01X517283Y809833D02*
Y807500D01*
X517617Y806917D01*
X518117Y806583D01*
X518700Y806500D01*
X519283Y806583D01*
X519783Y806917D01*
X520117Y807500D01*
G01Y806500D02*
Y809833D01*
G01X524300D02*
Y806500D01*
G01Y811167D02*
X524133Y811250D01*
Y811417D01*
X524300Y811500D01*
X524467Y811417D01*
Y811250D01*
X524300Y811167D01*
G01X528733Y806500D02*
Y809833D01*
G01Y809167D02*
X529150Y809500D01*
X529567Y809750D01*
X530150Y809833D01*
X530567Y809750D01*
X531067Y809500D01*
G01X534250Y808750D02*
X536917D01*
X536667Y809333D01*
X536250Y809667D01*
X535667Y809833D01*
X535083Y809750D01*
X534583Y809500D01*
X534250Y808917D01*
X534083Y808417D01*
Y807917D01*
X534250Y807417D01*
X534667Y806917D01*
X535167Y806583D01*
X535750Y806500D01*
X536333Y806667D01*
X536917Y807167D01*
G01X542600Y811500D02*
Y806500D01*
G01Y807250D02*
X542267Y806833D01*
X541767Y806583D01*
X541183Y806500D01*
X540517Y806667D01*
X540017Y807083D01*
X539683Y807583D01*
X539600Y808167D01*
X539683Y808750D01*
X540017Y809250D01*
X540517Y809667D01*
X541183Y809833D01*
X541767Y809750D01*
X542183Y809583D01*
X542600Y809250D01*
G01X546533Y805583D02*
X546867Y806667D01*
G01X112333Y-60000D02*
Y-65000D01*
X115667D01*
G01X119600D02*
X119100Y-64917D01*
X118600Y-64583D01*
X118267Y-64000D01*
X118100Y-63333D01*
X118267Y-62667D01*
X118600Y-62083D01*
X119100Y-61750D01*
X119600Y-61667D01*
X120100Y-61750D01*
X120600Y-62083D01*
X120933Y-62667D01*
X121017Y-63333D01*
X120933Y-64000D01*
X120600Y-64583D01*
X120100Y-64917D01*
X119600Y-65000D01*
G01X124033Y-66250D02*
X124617Y-66583D01*
X125283Y-66667D01*
X125867Y-66583D01*
X126367Y-66167D01*
X126700Y-65583D01*
Y-61667D01*
G01Y-62333D02*
X126367Y-62000D01*
X125867Y-61750D01*
X125283Y-61667D01*
X124617Y-61833D01*
X124200Y-62167D01*
X123867Y-62750D01*
X123700Y-63333D01*
X123783Y-63833D01*
X124117Y-64417D01*
X124617Y-64833D01*
X125283Y-65000D01*
X125783Y-64917D01*
X126367Y-64583D01*
X126700Y-64250D01*
G01X130800Y-65000D02*
X130300Y-64917D01*
X129800Y-64583D01*
X129467Y-64000D01*
X129300Y-63333D01*
X129467Y-62667D01*
X129800Y-62083D01*
X130300Y-61750D01*
X130800Y-61667D01*
X131300Y-61750D01*
X131800Y-62083D01*
X132133Y-62667D01*
X132217Y-63333D01*
X132133Y-64000D01*
X131800Y-64583D01*
X131300Y-64917D01*
X130800Y-65000D01*
G01X114000Y-36000D02*
Y-41000D01*
G01X112833Y-37667D02*
X115167D01*
G01X118183Y-41000D02*
Y-36000D01*
G01Y-38417D02*
X118600Y-38000D01*
X119017Y-37750D01*
X119683Y-37667D01*
X120183Y-37750D01*
X120767Y-38083D01*
X121017Y-38583D01*
Y-41000D01*
G01X125200Y-37667D02*
Y-41000D01*
G01Y-36333D02*
X125033Y-36250D01*
Y-36083D01*
X125200Y-36000D01*
X125367Y-36083D01*
Y-36250D01*
X125200Y-36333D01*
G01X132133Y-38083D02*
X131550Y-37750D01*
X131050Y-37667D01*
X130383Y-37833D01*
X129883Y-38167D01*
X129550Y-38750D01*
X129467Y-39333D01*
X129550Y-39917D01*
X129883Y-40417D01*
X130383Y-40833D01*
X131050Y-41000D01*
X131633Y-40833D01*
X132133Y-40500D01*
G01X134983Y-41000D02*
Y-36000D01*
G01X137650Y-37667D02*
X134983Y-39583D01*
G01X136067Y-38833D02*
X137817Y-41000D01*
G01X140583D02*
Y-37667D01*
G01Y-38500D02*
X140917Y-38083D01*
X141417Y-37750D01*
X142083Y-37667D01*
X142667Y-37750D01*
X143167Y-38083D01*
X143417Y-38667D01*
Y-41000D01*
G01X146350Y-38750D02*
X149017D01*
X148767Y-38167D01*
X148350Y-37833D01*
X147767Y-37667D01*
X147183Y-37750D01*
X146683Y-38000D01*
X146350Y-38583D01*
X146183Y-39083D01*
Y-39583D01*
X146350Y-40083D01*
X146767Y-40583D01*
X147267Y-40917D01*
X147850Y-41000D01*
X148433Y-40833D01*
X149017Y-40333D01*
G01X151950Y-40417D02*
X152367Y-40750D01*
X152950Y-41000D01*
X153450D01*
X153950Y-40833D01*
X154283Y-40583D01*
X154450Y-40250D01*
X154367Y-39750D01*
X154033Y-39500D01*
X152533Y-39000D01*
X152200Y-38417D01*
X152367Y-38000D01*
X152700Y-37750D01*
X153200Y-37667D01*
X153700Y-37750D01*
X154200Y-38000D01*
G01X157550Y-40417D02*
X157967Y-40750D01*
X158550Y-41000D01*
X159050D01*
X159550Y-40833D01*
X159883Y-40583D01*
X160050Y-40250D01*
X159967Y-39750D01*
X159633Y-39500D01*
X158133Y-39000D01*
X157800Y-38417D01*
X157967Y-38000D01*
X158300Y-37750D01*
X158800Y-37667D01*
X159300Y-37750D01*
X159800Y-38000D01*
G01X112483Y24700D02*
Y29700D01*
X114650Y25533D01*
X116817Y29700D01*
Y24700D01*
G01X121750D02*
Y28033D01*
G01Y27450D02*
X121417Y27783D01*
X120917Y27950D01*
X120333Y28033D01*
X119750Y27867D01*
X119250Y27533D01*
X118917Y27033D01*
X118750Y26367D01*
X118917Y25700D01*
X119250Y25200D01*
X119750Y24867D01*
X120333Y24700D01*
X120917Y24783D01*
X121417Y25033D01*
X121750Y25367D01*
G01X124683Y24700D02*
Y28033D01*
G01Y27367D02*
X125100Y27700D01*
X125517Y27950D01*
X126100Y28033D01*
X126517Y27950D01*
X127017Y27700D01*
G01X130033Y24700D02*
Y29700D01*
G01X132700Y28033D02*
X130033Y26117D01*
G01X131117Y26867D02*
X132867Y24700D01*
G01X137467Y23033D02*
X138300Y23867D01*
X138717Y24700D01*
Y28033D01*
X138300Y28867D01*
X137467Y29700D01*
G01X114000Y-15000D02*
Y-20000D01*
G01X112833Y-16667D02*
X115167D01*
G01X118183Y-20000D02*
Y-15000D01*
G01Y-17417D02*
X118600Y-17000D01*
X119017Y-16750D01*
X119683Y-16667D01*
X120183Y-16750D01*
X120767Y-17083D01*
X121017Y-17583D01*
Y-20000D01*
G01X125200Y-16667D02*
Y-20000D01*
G01Y-15333D02*
X125033Y-15250D01*
Y-15083D01*
X125200Y-15000D01*
X125367Y-15083D01*
Y-15250D01*
X125200Y-15333D01*
G01X132133Y-17083D02*
X131550Y-16750D01*
X131050Y-16667D01*
X130383Y-16833D01*
X129883Y-17167D01*
X129550Y-17750D01*
X129467Y-18333D01*
X129550Y-18917D01*
X129883Y-19417D01*
X130383Y-19833D01*
X131050Y-20000D01*
X131633Y-19833D01*
X132133Y-19500D01*
G01X134983Y-20000D02*
Y-15000D01*
G01X137650Y-16667D02*
X134983Y-18583D01*
G01X136067Y-17833D02*
X137817Y-20000D01*
G01X140583D02*
Y-16667D01*
G01Y-17500D02*
X140917Y-17083D01*
X141417Y-16750D01*
X142083Y-16667D01*
X142667Y-16750D01*
X143167Y-17083D01*
X143417Y-17667D01*
Y-20000D01*
G01X146350Y-17750D02*
X149017D01*
X148767Y-17167D01*
X148350Y-16833D01*
X147767Y-16667D01*
X147183Y-16750D01*
X146683Y-17000D01*
X146350Y-17583D01*
X146183Y-18083D01*
Y-18583D01*
X146350Y-19083D01*
X146767Y-19583D01*
X147267Y-19917D01*
X147850Y-20000D01*
X148433Y-19833D01*
X149017Y-19333D01*
G01X151950Y-19417D02*
X152367Y-19750D01*
X152950Y-20000D01*
X153450D01*
X153950Y-19833D01*
X154283Y-19583D01*
X154450Y-19250D01*
X154367Y-18750D01*
X154033Y-18500D01*
X152533Y-18000D01*
X152200Y-17417D01*
X152367Y-17000D01*
X152700Y-16750D01*
X153200Y-16667D01*
X153700Y-16750D01*
X154200Y-17000D01*
G01X157550Y-19417D02*
X157967Y-19750D01*
X158550Y-20000D01*
X159050D01*
X159550Y-19833D01*
X159883Y-19583D01*
X160050Y-19250D01*
X159967Y-18750D01*
X159633Y-18500D01*
X158133Y-18000D01*
X157800Y-17417D01*
X157967Y-17000D01*
X158300Y-16750D01*
X158800Y-16667D01*
X159300Y-16750D01*
X159800Y-17000D01*
G01X119183Y-2167D02*
X118350Y-1333D01*
X117933Y-500D01*
Y2833D01*
X118350Y3667D01*
X119183Y4500D01*
G01X123450Y167D02*
X124117Y-250D01*
X124867Y-500D01*
X125533D01*
X126200Y-250D01*
X126700Y167D01*
X126950Y750D01*
X126783Y1333D01*
X126367Y1833D01*
X125617Y2167D01*
X124617Y2333D01*
X124033Y2667D01*
X123783Y3250D01*
X123950Y3833D01*
X124367Y4250D01*
X124950Y4500D01*
X125533D01*
X126117Y4333D01*
X126617Y3917D01*
G01X128633Y-500D02*
Y4500D01*
X130800Y333D01*
X132967Y4500D01*
Y-500D01*
G01X134567D02*
Y4500D01*
X136233D01*
X136900Y4250D01*
X137400Y3917D01*
X137817Y3417D01*
X138150Y2833D01*
X138233Y2000D01*
X138150Y1167D01*
X137817Y583D01*
X137400Y83D01*
X136900Y-250D01*
X136233Y-500D01*
X134567D01*
G01X142417Y-2167D02*
X143250Y-1333D01*
X143667Y-500D01*
Y2833D01*
X143250Y3667D01*
X142417Y4500D01*
G01X112250Y12167D02*
X112917Y11750D01*
X113667Y11500D01*
X114333D01*
X115000Y11750D01*
X115500Y12167D01*
X115750Y12750D01*
X115583Y13333D01*
X115167Y13833D01*
X114417Y14167D01*
X113417Y14333D01*
X112833Y14667D01*
X112583Y15250D01*
X112750Y15833D01*
X113167Y16250D01*
X113750Y16500D01*
X114333D01*
X114917Y16333D01*
X115417Y15917D01*
G01X119600Y11500D02*
X119100Y11583D01*
X118600Y11917D01*
X118267Y12500D01*
X118100Y13167D01*
X118267Y13833D01*
X118600Y14417D01*
X119100Y14750D01*
X119600Y14833D01*
X120100Y14750D01*
X120600Y14417D01*
X120933Y13833D01*
X121017Y13167D01*
X120933Y12500D01*
X120600Y11917D01*
X120100Y11583D01*
X119600Y11500D01*
G01X125200D02*
Y16500D01*
G01X132300D02*
Y11500D01*
G01Y12250D02*
X131967Y11833D01*
X131467Y11583D01*
X130883Y11500D01*
X130217Y11667D01*
X129717Y12083D01*
X129383Y12583D01*
X129300Y13167D01*
X129383Y13750D01*
X129717Y14250D01*
X130217Y14667D01*
X130883Y14833D01*
X131467Y14750D01*
X131883Y14583D01*
X132300Y14250D01*
G01X135150Y13750D02*
X137817D01*
X137567Y14333D01*
X137150Y14667D01*
X136567Y14833D01*
X135983Y14750D01*
X135483Y14500D01*
X135150Y13917D01*
X134983Y13417D01*
Y12917D01*
X135150Y12417D01*
X135567Y11917D01*
X136067Y11583D01*
X136650Y11500D01*
X137233Y11667D01*
X137817Y12167D01*
G01X140833Y11500D02*
Y14833D01*
G01Y14167D02*
X141250Y14500D01*
X141667Y14750D01*
X142250Y14833D01*
X142667Y14750D01*
X143167Y14500D01*
G01X150700Y11500D02*
Y14833D01*
G01Y13917D02*
X150950Y14333D01*
X151367Y14667D01*
X151950Y14833D01*
X152533Y14667D01*
X152950Y14333D01*
X153200Y13917D01*
Y11500D01*
G01Y13917D02*
X153450Y14333D01*
X153867Y14667D01*
X154450Y14833D01*
X155033Y14667D01*
X155450Y14333D01*
X155700Y13833D01*
Y11500D01*
G01X160300D02*
Y14833D01*
G01Y14250D02*
X159967Y14583D01*
X159467Y14750D01*
X158883Y14833D01*
X158300Y14667D01*
X157800Y14333D01*
X157467Y13833D01*
X157300Y13167D01*
X157467Y12500D01*
X157800Y12000D01*
X158300Y11667D01*
X158883Y11500D01*
X159467Y11583D01*
X159967Y11833D01*
X160300Y12167D01*
G01X163150Y12083D02*
X163567Y11750D01*
X164150Y11500D01*
X164650D01*
X165150Y11667D01*
X165483Y11917D01*
X165650Y12250D01*
X165567Y12750D01*
X165233Y13000D01*
X163733Y13500D01*
X163400Y14083D01*
X163567Y14500D01*
X163900Y14750D01*
X164400Y14833D01*
X164900Y14750D01*
X165400Y14500D01*
G01X168583Y11500D02*
Y16500D01*
G01X171250Y14833D02*
X168583Y12917D01*
G01X169667Y13667D02*
X171417Y11500D01*
G01X182700Y16500D02*
Y11500D01*
G01Y12250D02*
X182367Y11833D01*
X181867Y11583D01*
X181283Y11500D01*
X180617Y11667D01*
X180117Y12083D01*
X179783Y12583D01*
X179700Y13167D01*
X179783Y13750D01*
X180117Y14250D01*
X180617Y14667D01*
X181283Y14833D01*
X181867Y14750D01*
X182283Y14583D01*
X182700Y14250D01*
G01X185550Y13750D02*
X188217D01*
X187967Y14333D01*
X187550Y14667D01*
X186967Y14833D01*
X186383Y14750D01*
X185883Y14500D01*
X185550Y13917D01*
X185383Y13417D01*
Y12917D01*
X185550Y12417D01*
X185967Y11917D01*
X186467Y11583D01*
X187050Y11500D01*
X187633Y11667D01*
X188217Y12167D01*
G01X191900Y11500D02*
Y15750D01*
X192067Y16167D01*
X192400Y16417D01*
X192900Y16500D01*
X193400Y16333D01*
X193650Y15917D01*
G01X192650Y14500D02*
X190983D01*
G01X198000Y14833D02*
Y11500D01*
G01Y16167D02*
X197833Y16250D01*
Y16417D01*
X198000Y16500D01*
X198167Y16417D01*
Y16250D01*
X198000Y16167D01*
G01X202183Y11500D02*
Y14833D01*
G01Y14000D02*
X202517Y14417D01*
X203017Y14750D01*
X203683Y14833D01*
X204267Y14750D01*
X204767Y14417D01*
X205017Y13833D01*
Y11500D01*
G01X207950Y13750D02*
X210617D01*
X210367Y14333D01*
X209950Y14667D01*
X209367Y14833D01*
X208783Y14750D01*
X208283Y14500D01*
X207950Y13917D01*
X207783Y13417D01*
Y12917D01*
X207950Y12417D01*
X208367Y11917D01*
X208867Y11583D01*
X209450Y11500D01*
X210033Y11667D01*
X210617Y12167D01*
G01X218900Y9833D02*
Y14833D01*
G01Y14083D02*
X219317Y14500D01*
X219733Y14750D01*
X220400Y14833D01*
X220983Y14750D01*
X221567Y14333D01*
X221817Y13750D01*
X221900Y13167D01*
X221817Y12583D01*
X221567Y12000D01*
X221067Y11667D01*
X220400Y11500D01*
X219817Y11583D01*
X219233Y11833D01*
X218900Y12167D01*
G01X227500Y11500D02*
Y14833D01*
G01Y14250D02*
X227167Y14583D01*
X226667Y14750D01*
X226083Y14833D01*
X225500Y14667D01*
X225000Y14333D01*
X224667Y13833D01*
X224500Y13167D01*
X224667Y12500D01*
X225000Y12000D01*
X225500Y11667D01*
X226083Y11500D01*
X226667Y11583D01*
X227167Y11833D01*
X227500Y12167D01*
G01X233100Y16500D02*
Y11500D01*
G01Y12250D02*
X232767Y11833D01*
X232267Y11583D01*
X231683Y11500D01*
X231017Y11667D01*
X230517Y12083D01*
X230183Y12583D01*
X230100Y13167D01*
X230183Y13750D01*
X230517Y14250D01*
X231017Y14667D01*
X231683Y14833D01*
X232267Y14750D01*
X232683Y14583D01*
X233100Y14250D01*
G01X112333Y51500D02*
Y56500D01*
X114333D01*
X115000Y56250D01*
X115500Y55667D01*
X115667Y55000D01*
X115500Y54333D01*
X115083Y53833D01*
X114333Y53583D01*
X112333D01*
G01X117517Y51500D02*
X119600Y56500D01*
X121683Y51500D01*
G01X120933Y53250D02*
X118267D01*
G01X123367Y51500D02*
Y56500D01*
X125033D01*
X125700Y56250D01*
X126200Y55917D01*
X126617Y55417D01*
X126950Y54833D01*
X127033Y54000D01*
X126950Y53167D01*
X126617Y52583D01*
X126200Y52083D01*
X125700Y51750D01*
X125033Y51500D01*
X123367D01*
G01X135150Y52083D02*
X135567Y51750D01*
X136150Y51500D01*
X136650D01*
X137150Y51667D01*
X137483Y51917D01*
X137650Y52250D01*
X137567Y52750D01*
X137233Y53000D01*
X135733Y53500D01*
X135400Y54083D01*
X135567Y54500D01*
X135900Y54750D01*
X136400Y54833D01*
X136900Y54750D01*
X137400Y54500D01*
G01X142000Y54833D02*
Y51500D01*
G01Y56167D02*
X141833Y56250D01*
Y56417D01*
X142000Y56500D01*
X142167Y56417D01*
Y56250D01*
X142000Y56167D01*
G01X146350Y54833D02*
X148850D01*
X146350Y51500D01*
X148850D01*
G01X151950Y53750D02*
X154617D01*
X154367Y54333D01*
X153950Y54667D01*
X153367Y54833D01*
X152783Y54750D01*
X152283Y54500D01*
X151950Y53917D01*
X151783Y53417D01*
Y52917D01*
X151950Y52417D01*
X152367Y51917D01*
X152867Y51583D01*
X153450Y51500D01*
X154033Y51667D01*
X154617Y52167D01*
G01X114000Y85000D02*
Y80000D01*
G01X112083Y85000D02*
X115917D01*
G01X118433Y80000D02*
Y83333D01*
G01Y82667D02*
X118850Y83000D01*
X119267Y83250D01*
X119850Y83333D01*
X120267Y83250D01*
X120767Y83000D01*
G01X126700Y80000D02*
Y83333D01*
G01Y82750D02*
X126367Y83083D01*
X125867Y83250D01*
X125283Y83333D01*
X124700Y83167D01*
X124200Y82833D01*
X123867Y82333D01*
X123700Y81667D01*
X123867Y81000D01*
X124200Y80500D01*
X124700Y80167D01*
X125283Y80000D01*
X125867Y80083D01*
X126367Y80333D01*
X126700Y80667D01*
G01X132133Y82917D02*
X131550Y83250D01*
X131050Y83333D01*
X130383Y83167D01*
X129883Y82833D01*
X129550Y82250D01*
X129467Y81667D01*
X129550Y81083D01*
X129883Y80583D01*
X130383Y80167D01*
X131050Y80000D01*
X131633Y80167D01*
X132133Y80500D01*
G01X135150Y82250D02*
X137817D01*
X137567Y82833D01*
X137150Y83167D01*
X136567Y83333D01*
X135983Y83250D01*
X135483Y83000D01*
X135150Y82417D01*
X134983Y81917D01*
Y81417D01*
X135150Y80917D01*
X135567Y80417D01*
X136067Y80083D01*
X136650Y80000D01*
X137233Y80167D01*
X137817Y80667D01*
G01X145517Y83333D02*
X146517Y80000D01*
X147600Y83333D01*
X148683Y80000D01*
X149683Y83333D01*
G01X153200D02*
Y80000D01*
G01Y84667D02*
X153033Y84750D01*
Y84917D01*
X153200Y85000D01*
X153367Y84917D01*
Y84750D01*
X153200Y84667D01*
G01X160300Y85000D02*
Y80000D01*
G01Y80750D02*
X159967Y80333D01*
X159467Y80083D01*
X158883Y80000D01*
X158217Y80167D01*
X157717Y80583D01*
X157383Y81083D01*
X157300Y81667D01*
X157383Y82250D01*
X157717Y82750D01*
X158217Y83167D01*
X158883Y83333D01*
X159467Y83250D01*
X159883Y83083D01*
X160300Y82750D01*
G01X164400Y85000D02*
Y80000D01*
G01X163233Y83333D02*
X165567D01*
G01X168583Y80000D02*
Y85000D01*
G01Y82583D02*
X169000Y83000D01*
X169417Y83250D01*
X170083Y83333D01*
X170583Y83250D01*
X171167Y82917D01*
X171417Y82417D01*
Y80000D01*
G01X112333Y111500D02*
Y116500D01*
X114417D01*
X115083Y116250D01*
X115500Y115917D01*
X115667Y115250D01*
X115500Y114583D01*
X115000Y114167D01*
X114417Y113917D01*
X112333D01*
G01X114417D02*
X115667Y111500D01*
G01X118350Y113750D02*
X121017D01*
X120767Y114333D01*
X120350Y114667D01*
X119767Y114833D01*
X119183Y114750D01*
X118683Y114500D01*
X118350Y113917D01*
X118183Y113417D01*
Y112917D01*
X118350Y112417D01*
X118767Y111917D01*
X119267Y111583D01*
X119850Y111500D01*
X120433Y111667D01*
X121017Y112167D01*
G01X125200Y111500D02*
Y116500D01*
G01X132300Y111500D02*
Y114833D01*
G01Y114250D02*
X131967Y114583D01*
X131467Y114750D01*
X130883Y114833D01*
X130300Y114667D01*
X129800Y114333D01*
X129467Y113833D01*
X129300Y113167D01*
X129467Y112500D01*
X129800Y112000D01*
X130300Y111667D01*
X130883Y111500D01*
X131467Y111583D01*
X131967Y111833D01*
X132300Y112167D01*
G01X136400Y116500D02*
Y111500D01*
G01X135233Y114833D02*
X137567D01*
G01X142000D02*
Y111500D01*
G01Y116167D02*
X141833Y116250D01*
Y116417D01*
X142000Y116500D01*
X142167Y116417D01*
Y116250D01*
X142000Y116167D01*
G01X146100Y114833D02*
X147600Y111500D01*
X149100Y114833D01*
G01X151950Y113750D02*
X154617D01*
X154367Y114333D01*
X153950Y114667D01*
X153367Y114833D01*
X152783Y114750D01*
X152283Y114500D01*
X151950Y113917D01*
X151783Y113417D01*
Y112917D01*
X151950Y112417D01*
X152367Y111917D01*
X152867Y111583D01*
X153450Y111500D01*
X154033Y111667D01*
X154617Y112167D01*
G01X162900Y109833D02*
Y114833D01*
G01Y114083D02*
X163317Y114500D01*
X163733Y114750D01*
X164400Y114833D01*
X164983Y114750D01*
X165567Y114333D01*
X165817Y113750D01*
X165900Y113167D01*
X165817Y112583D01*
X165567Y112000D01*
X165067Y111667D01*
X164400Y111500D01*
X163817Y111583D01*
X163233Y111833D01*
X162900Y112167D01*
G01X170000Y111500D02*
X169500Y111583D01*
X169000Y111917D01*
X168667Y112500D01*
X168500Y113167D01*
X168667Y113833D01*
X169000Y114417D01*
X169500Y114750D01*
X170000Y114833D01*
X170500Y114750D01*
X171000Y114417D01*
X171333Y113833D01*
X171417Y113167D01*
X171333Y112500D01*
X171000Y111917D01*
X170500Y111583D01*
X170000Y111500D01*
G01X174350Y112083D02*
X174767Y111750D01*
X175350Y111500D01*
X175850D01*
X176350Y111667D01*
X176683Y111917D01*
X176850Y112250D01*
X176767Y112750D01*
X176433Y113000D01*
X174933Y113500D01*
X174600Y114083D01*
X174767Y114500D01*
X175100Y114750D01*
X175600Y114833D01*
X176100Y114750D01*
X176600Y114500D01*
G01X181200Y114833D02*
Y111500D01*
G01Y116167D02*
X181033Y116250D01*
Y116417D01*
X181200Y116500D01*
X181367Y116417D01*
Y116250D01*
X181200Y116167D01*
G01X186800Y116500D02*
Y111500D01*
G01X185633Y114833D02*
X187967D01*
G01X192400D02*
Y111500D01*
G01Y116167D02*
X192233Y116250D01*
Y116417D01*
X192400Y116500D01*
X192567Y116417D01*
Y116250D01*
X192400Y116167D01*
G01X198000Y111500D02*
X197500Y111583D01*
X197000Y111917D01*
X196667Y112500D01*
X196500Y113167D01*
X196667Y113833D01*
X197000Y114417D01*
X197500Y114750D01*
X198000Y114833D01*
X198500Y114750D01*
X199000Y114417D01*
X199333Y113833D01*
X199417Y113167D01*
X199333Y112500D01*
X199000Y111917D01*
X198500Y111583D01*
X198000Y111500D01*
G01X202183D02*
Y114833D01*
G01Y114000D02*
X202517Y114417D01*
X203017Y114750D01*
X203683Y114833D01*
X204267Y114750D01*
X204767Y114417D01*
X205017Y113833D01*
Y111500D01*
G01X114000Y143500D02*
Y138500D01*
G01X112833Y141833D02*
X115167D01*
G01X118183Y138500D02*
Y143500D01*
G01Y141083D02*
X118600Y141500D01*
X119017Y141750D01*
X119683Y141833D01*
X120183Y141750D01*
X120767Y141417D01*
X121017Y140917D01*
Y138500D01*
G01X125200Y141833D02*
Y138500D01*
G01Y143167D02*
X125033Y143250D01*
Y143417D01*
X125200Y143500D01*
X125367Y143417D01*
Y143250D01*
X125200Y143167D01*
G01X132133Y141417D02*
X131550Y141750D01*
X131050Y141833D01*
X130383Y141667D01*
X129883Y141333D01*
X129550Y140750D01*
X129467Y140167D01*
X129550Y139583D01*
X129883Y139083D01*
X130383Y138667D01*
X131050Y138500D01*
X131633Y138667D01*
X132133Y139000D01*
G01X134983Y138500D02*
Y143500D01*
G01X137650Y141833D02*
X134983Y139917D01*
G01X136067Y140667D02*
X137817Y138500D01*
G01X140583D02*
Y141833D01*
G01Y141000D02*
X140917Y141417D01*
X141417Y141750D01*
X142083Y141833D01*
X142667Y141750D01*
X143167Y141417D01*
X143417Y140833D01*
Y138500D01*
G01X146350Y140750D02*
X149017D01*
X148767Y141333D01*
X148350Y141667D01*
X147767Y141833D01*
X147183Y141750D01*
X146683Y141500D01*
X146350Y140917D01*
X146183Y140417D01*
Y139917D01*
X146350Y139417D01*
X146767Y138917D01*
X147267Y138583D01*
X147850Y138500D01*
X148433Y138667D01*
X149017Y139167D01*
G01X151950Y139083D02*
X152367Y138750D01*
X152950Y138500D01*
X153450D01*
X153950Y138667D01*
X154283Y138917D01*
X154450Y139250D01*
X154367Y139750D01*
X154033Y140000D01*
X152533Y140500D01*
X152200Y141083D01*
X152367Y141500D01*
X152700Y141750D01*
X153200Y141833D01*
X153700Y141750D01*
X154200Y141500D01*
G01X157550Y139083D02*
X157967Y138750D01*
X158550Y138500D01*
X159050D01*
X159550Y138667D01*
X159883Y138917D01*
X160050Y139250D01*
X159967Y139750D01*
X159633Y140000D01*
X158133Y140500D01*
X157800Y141083D01*
X157967Y141500D01*
X158300Y141750D01*
X158800Y141833D01*
X159300Y141750D01*
X159800Y141500D01*
G01X171500Y138500D02*
Y141833D01*
G01Y141250D02*
X171167Y141583D01*
X170667Y141750D01*
X170083Y141833D01*
X169500Y141667D01*
X169000Y141333D01*
X168667Y140833D01*
X168500Y140167D01*
X168667Y139500D01*
X169000Y139000D01*
X169500Y138667D01*
X170083Y138500D01*
X170667Y138583D01*
X171167Y138833D01*
X171500Y139167D01*
G01X175100Y138500D02*
Y142750D01*
X175267Y143167D01*
X175600Y143417D01*
X176100Y143500D01*
X176600Y143333D01*
X176850Y142917D01*
G01X175850Y141500D02*
X174183D01*
G01X181200Y143500D02*
Y138500D01*
G01X180033Y141833D02*
X182367D01*
G01X185550Y140750D02*
X188217D01*
X187967Y141333D01*
X187550Y141667D01*
X186967Y141833D01*
X186383Y141750D01*
X185883Y141500D01*
X185550Y140917D01*
X185383Y140417D01*
Y139917D01*
X185550Y139417D01*
X185967Y138917D01*
X186467Y138583D01*
X187050Y138500D01*
X187633Y138667D01*
X188217Y139167D01*
G01X191233Y138500D02*
Y141833D01*
G01Y141167D02*
X191650Y141500D01*
X192067Y141750D01*
X192650Y141833D01*
X193067Y141750D01*
X193567Y141500D01*
G01X202100Y136833D02*
Y141833D01*
G01Y141083D02*
X202517Y141500D01*
X202933Y141750D01*
X203600Y141833D01*
X204183Y141750D01*
X204767Y141333D01*
X205017Y140750D01*
X205100Y140167D01*
X205017Y139583D01*
X204767Y139000D01*
X204267Y138667D01*
X203600Y138500D01*
X203017Y138583D01*
X202433Y138833D01*
X202100Y139167D01*
G01X209200Y138500D02*
Y143500D01*
G01X216300Y138500D02*
Y141833D01*
G01Y141250D02*
X215967Y141583D01*
X215467Y141750D01*
X214883Y141833D01*
X214300Y141667D01*
X213800Y141333D01*
X213467Y140833D01*
X213300Y140167D01*
X213467Y139500D01*
X213800Y139000D01*
X214300Y138667D01*
X214883Y138500D01*
X215467Y138583D01*
X215967Y138833D01*
X216300Y139167D01*
G01X220400Y143500D02*
Y138500D01*
G01X219233Y141833D02*
X221567D01*
G01X226000D02*
Y138500D01*
G01Y143167D02*
X225833Y143250D01*
Y143417D01*
X226000Y143500D01*
X226167Y143417D01*
Y143250D01*
X226000Y143167D01*
G01X230183Y138500D02*
Y141833D01*
G01Y141000D02*
X230517Y141417D01*
X231017Y141750D01*
X231683Y141833D01*
X232267Y141750D01*
X232767Y141417D01*
X233017Y140833D01*
Y138500D01*
G01X236033Y137250D02*
X236617Y136917D01*
X237283Y136833D01*
X237867Y136917D01*
X238367Y137333D01*
X238700Y137917D01*
Y141833D01*
G01Y141167D02*
X238367Y141500D01*
X237867Y141750D01*
X237283Y141833D01*
X236617Y141667D01*
X236200Y141333D01*
X235867Y140750D01*
X235700Y140167D01*
X235783Y139667D01*
X236117Y139083D01*
X236617Y138667D01*
X237283Y138500D01*
X237783Y138583D01*
X238367Y138917D01*
X238700Y139250D01*
G01X115667Y148500D02*
X112333D01*
Y153500D01*
X115667D01*
G01X114333Y151083D02*
X112333D01*
G01X118350Y151833D02*
X120850Y148500D01*
G01Y151833D02*
X118350Y148500D01*
G01X125200Y153500D02*
Y148500D01*
G01X124033Y151833D02*
X126367D01*
G01X129550Y150750D02*
X132217D01*
X131967Y151333D01*
X131550Y151667D01*
X130967Y151833D01*
X130383Y151750D01*
X129883Y151500D01*
X129550Y150917D01*
X129383Y150417D01*
Y149917D01*
X129550Y149417D01*
X129967Y148917D01*
X130467Y148583D01*
X131050Y148500D01*
X131633Y148667D01*
X132217Y149167D01*
G01X135233Y148500D02*
Y151833D01*
G01Y151167D02*
X135650Y151500D01*
X136067Y151750D01*
X136650Y151833D01*
X137067Y151750D01*
X137567Y151500D01*
G01X140583Y148500D02*
Y151833D01*
G01Y151000D02*
X140917Y151417D01*
X141417Y151750D01*
X142083Y151833D01*
X142667Y151750D01*
X143167Y151417D01*
X143417Y150833D01*
Y148500D01*
G01X149100D02*
Y151833D01*
G01Y151250D02*
X148767Y151583D01*
X148267Y151750D01*
X147683Y151833D01*
X147100Y151667D01*
X146600Y151333D01*
X146267Y150833D01*
X146100Y150167D01*
X146267Y149500D01*
X146600Y149000D01*
X147100Y148667D01*
X147683Y148500D01*
X148267Y148583D01*
X148767Y148833D01*
X149100Y149167D01*
G01X153200Y148500D02*
Y153500D01*
G01X165733Y151417D02*
X165150Y151750D01*
X164650Y151833D01*
X163983Y151667D01*
X163483Y151333D01*
X163150Y150750D01*
X163067Y150167D01*
X163150Y149583D01*
X163483Y149083D01*
X163983Y148667D01*
X164650Y148500D01*
X165233Y148667D01*
X165733Y149000D01*
G01X170000Y148500D02*
X169500Y148583D01*
X169000Y148917D01*
X168667Y149500D01*
X168500Y150167D01*
X168667Y150833D01*
X169000Y151417D01*
X169500Y151750D01*
X170000Y151833D01*
X170500Y151750D01*
X171000Y151417D01*
X171333Y150833D01*
X171417Y150167D01*
X171333Y149500D01*
X171000Y148917D01*
X170500Y148583D01*
X170000Y148500D01*
G01X174183D02*
Y151833D01*
G01Y151000D02*
X174517Y151417D01*
X175017Y151750D01*
X175683Y151833D01*
X176267Y151750D01*
X176767Y151417D01*
X177017Y150833D01*
Y148500D01*
G01X182700Y153500D02*
Y148500D01*
G01Y149250D02*
X182367Y148833D01*
X181867Y148583D01*
X181283Y148500D01*
X180617Y148667D01*
X180117Y149083D01*
X179783Y149583D01*
X179700Y150167D01*
X179783Y150750D01*
X180117Y151250D01*
X180617Y151667D01*
X181283Y151833D01*
X181867Y151750D01*
X182283Y151583D01*
X182700Y151250D01*
G01X185383Y151833D02*
Y149500D01*
X185717Y148917D01*
X186217Y148583D01*
X186800Y148500D01*
X187383Y148583D01*
X187883Y148917D01*
X188217Y149500D01*
G01Y148500D02*
Y151833D01*
G01X193733Y151417D02*
X193150Y151750D01*
X192650Y151833D01*
X191983Y151667D01*
X191483Y151333D01*
X191150Y150750D01*
X191067Y150167D01*
X191150Y149583D01*
X191483Y149083D01*
X191983Y148667D01*
X192650Y148500D01*
X193233Y148667D01*
X193733Y149000D01*
G01X198000Y153500D02*
Y148500D01*
G01X196833Y151833D02*
X199167D01*
G01X203600Y148500D02*
X203100Y148583D01*
X202600Y148917D01*
X202267Y149500D01*
X202100Y150167D01*
X202267Y150833D01*
X202600Y151417D01*
X203100Y151750D01*
X203600Y151833D01*
X204100Y151750D01*
X204600Y151417D01*
X204933Y150833D01*
X205017Y150167D01*
X204933Y149500D01*
X204600Y148917D01*
X204100Y148583D01*
X203600Y148500D01*
G01X208033D02*
Y151833D01*
G01Y151167D02*
X208450Y151500D01*
X208867Y151750D01*
X209450Y151833D01*
X209867Y151750D01*
X210367Y151500D01*
G01X112333Y356500D02*
Y351500D01*
X115667D01*
G01X121100D02*
Y354833D01*
G01Y354250D02*
X120767Y354583D01*
X120267Y354750D01*
X119683Y354833D01*
X119100Y354667D01*
X118600Y354333D01*
X118267Y353833D01*
X118100Y353167D01*
X118267Y352500D01*
X118600Y352000D01*
X119100Y351667D01*
X119683Y351500D01*
X120267Y351583D01*
X120767Y351833D01*
X121100Y352167D01*
G01X123950Y352083D02*
X124367Y351750D01*
X124950Y351500D01*
X125450D01*
X125950Y351667D01*
X126283Y351917D01*
X126450Y352250D01*
X126367Y352750D01*
X126033Y353000D01*
X124533Y353500D01*
X124200Y354083D01*
X124367Y354500D01*
X124700Y354750D01*
X125200Y354833D01*
X125700Y354750D01*
X126200Y354500D01*
G01X129550Y353750D02*
X132217D01*
X131967Y354333D01*
X131550Y354667D01*
X130967Y354833D01*
X130383Y354750D01*
X129883Y354500D01*
X129550Y353917D01*
X129383Y353417D01*
Y352917D01*
X129550Y352417D01*
X129967Y351917D01*
X130467Y351583D01*
X131050Y351500D01*
X131633Y351667D01*
X132217Y352167D01*
G01X135233Y351500D02*
Y354833D01*
G01Y354167D02*
X135650Y354500D01*
X136067Y354750D01*
X136650Y354833D01*
X137067Y354750D01*
X137567Y354500D01*
G01X146100Y354833D02*
X147600Y351500D01*
X149100Y354833D01*
G01X153200D02*
Y351500D01*
G01Y356167D02*
X153033Y356250D01*
Y356417D01*
X153200Y356500D01*
X153367Y356417D01*
Y356250D01*
X153200Y356167D01*
G01X160300Y351500D02*
Y354833D01*
G01Y354250D02*
X159967Y354583D01*
X159467Y354750D01*
X158883Y354833D01*
X158300Y354667D01*
X157800Y354333D01*
X157467Y353833D01*
X157300Y353167D01*
X157467Y352500D01*
X157800Y352000D01*
X158300Y351667D01*
X158883Y351500D01*
X159467Y351583D01*
X159967Y351833D01*
X160300Y352167D01*
G01X168167Y351333D02*
X171833Y355000D01*
G01X170000Y355667D02*
Y350667D01*
G01X171833Y351333D02*
X168167Y355000D01*
G01X167500Y353167D02*
X172500D01*
G01X175183Y349833D02*
X174350Y350667D01*
X173933Y351500D01*
Y354833D01*
X174350Y355667D01*
X175183Y356500D01*
G01X179367Y352250D02*
X179867Y351833D01*
X180450Y351583D01*
X181200Y351500D01*
X181950Y351667D01*
X182533Y352000D01*
X182950Y352583D01*
X183033Y353250D01*
X182867Y353917D01*
X182450Y354333D01*
X181867Y354667D01*
X181283Y354750D01*
X180700Y354667D01*
X179950Y354333D01*
X180200Y356500D01*
X182450D01*
G01X186800Y351333D02*
X186633Y351417D01*
Y351583D01*
X186800Y351667D01*
X186967Y351583D01*
Y351417D01*
X186800Y351333D01*
G01X192400Y351500D02*
Y356500D01*
X191400Y355500D01*
G01Y351500D02*
X193400D01*
G01X198417Y349833D02*
X199250Y350667D01*
X199667Y351500D01*
Y354833D01*
X199250Y355667D01*
X198417Y356500D01*
G01X112333Y406500D02*
Y411500D01*
X114333D01*
X115000Y411250D01*
X115500Y410667D01*
X115667Y410000D01*
X115500Y409333D01*
X115083Y408833D01*
X114333Y408583D01*
X112333D01*
G01X119600Y411500D02*
Y406500D01*
G01X117683Y411500D02*
X121517D01*
G01X123450Y406500D02*
Y411500D01*
G01X126950D02*
Y406500D01*
G01Y409000D02*
X123450D01*
G01X135233Y406500D02*
Y409833D01*
G01Y409167D02*
X135650Y409500D01*
X136067Y409750D01*
X136650Y409833D01*
X137067Y409750D01*
X137567Y409500D01*
G01X140750Y408750D02*
X143417D01*
X143167Y409333D01*
X142750Y409667D01*
X142167Y409833D01*
X141583Y409750D01*
X141083Y409500D01*
X140750Y408917D01*
X140583Y408417D01*
Y407917D01*
X140750Y407417D01*
X141167Y406917D01*
X141667Y406583D01*
X142250Y406500D01*
X142833Y406667D01*
X143417Y407167D01*
G01X146433Y405250D02*
X147017Y404917D01*
X147683Y404833D01*
X148267Y404917D01*
X148767Y405333D01*
X149100Y405917D01*
Y409833D01*
G01Y409167D02*
X148767Y409500D01*
X148267Y409750D01*
X147683Y409833D01*
X147017Y409667D01*
X146600Y409333D01*
X146267Y408750D01*
X146100Y408167D01*
X146183Y407667D01*
X146517Y407083D01*
X147017Y406667D01*
X147683Y406500D01*
X148183Y406583D01*
X148767Y406917D01*
X149100Y407250D01*
G01X153200Y409833D02*
Y406500D01*
G01Y411167D02*
X153033Y411250D01*
Y411417D01*
X153200Y411500D01*
X153367Y411417D01*
Y411250D01*
X153200Y411167D01*
G01X157550Y407083D02*
X157967Y406750D01*
X158550Y406500D01*
X159050D01*
X159550Y406667D01*
X159883Y406917D01*
X160050Y407250D01*
X159967Y407750D01*
X159633Y408000D01*
X158133Y408500D01*
X157800Y409083D01*
X157967Y409500D01*
X158300Y409750D01*
X158800Y409833D01*
X159300Y409750D01*
X159800Y409500D01*
G01X164400Y411500D02*
Y406500D01*
G01X163233Y409833D02*
X165567D01*
G01X168833Y406500D02*
Y409833D01*
G01Y409167D02*
X169250Y409500D01*
X169667Y409750D01*
X170250Y409833D01*
X170667Y409750D01*
X171167Y409500D01*
G01X177100Y406500D02*
Y409833D01*
G01Y409250D02*
X176767Y409583D01*
X176267Y409750D01*
X175683Y409833D01*
X175100Y409667D01*
X174600Y409333D01*
X174267Y408833D01*
X174100Y408167D01*
X174267Y407500D01*
X174600Y407000D01*
X175100Y406667D01*
X175683Y406500D01*
X176267Y406583D01*
X176767Y406833D01*
X177100Y407167D01*
G01X181200Y411500D02*
Y406500D01*
G01X180033Y409833D02*
X182367D01*
G01X186800D02*
Y406500D01*
G01Y411167D02*
X186633Y411250D01*
Y411417D01*
X186800Y411500D01*
X186967Y411417D01*
Y411250D01*
X186800Y411167D01*
G01X192400Y406500D02*
X191900Y406583D01*
X191400Y406917D01*
X191067Y407500D01*
X190900Y408167D01*
X191067Y408833D01*
X191400Y409417D01*
X191900Y409750D01*
X192400Y409833D01*
X192900Y409750D01*
X193400Y409417D01*
X193733Y408833D01*
X193817Y408167D01*
X193733Y407500D01*
X193400Y406917D01*
X192900Y406583D01*
X192400Y406500D01*
G01X196583D02*
Y409833D01*
G01Y409000D02*
X196917Y409417D01*
X197417Y409750D01*
X198083Y409833D01*
X198667Y409750D01*
X199167Y409417D01*
X199417Y408833D01*
Y406500D01*
G01X112167Y433000D02*
Y438000D01*
X113833D01*
X114500Y437750D01*
X115000Y437417D01*
X115417Y436917D01*
X115750Y436333D01*
X115833Y435500D01*
X115750Y434667D01*
X115417Y434083D01*
X115000Y433583D01*
X114500Y433250D01*
X113833Y433000D01*
X112167D01*
G01X118350Y435250D02*
X121017D01*
X120767Y435833D01*
X120350Y436167D01*
X119767Y436333D01*
X119183Y436250D01*
X118683Y436000D01*
X118350Y435417D01*
X118183Y434917D01*
Y434417D01*
X118350Y433917D01*
X118767Y433417D01*
X119267Y433083D01*
X119850Y433000D01*
X120433Y433167D01*
X121017Y433667D01*
G01X123700Y431333D02*
Y436333D01*
G01Y435583D02*
X124117Y436000D01*
X124533Y436250D01*
X125200Y436333D01*
X125783Y436250D01*
X126367Y435833D01*
X126617Y435250D01*
X126700Y434667D01*
X126617Y434083D01*
X126367Y433500D01*
X125867Y433167D01*
X125200Y433000D01*
X124617Y433083D01*
X124033Y433333D01*
X123700Y433667D01*
G01X130800Y438000D02*
Y433000D01*
G01X129633Y436333D02*
X131967D01*
G01X134983Y433000D02*
Y438000D01*
G01Y435583D02*
X135400Y436000D01*
X135817Y436250D01*
X136483Y436333D01*
X136983Y436250D01*
X137567Y435917D01*
X137817Y435417D01*
Y433000D01*
G01X148933Y435917D02*
X148350Y436250D01*
X147850Y436333D01*
X147183Y436167D01*
X146683Y435833D01*
X146350Y435250D01*
X146267Y434667D01*
X146350Y434083D01*
X146683Y433583D01*
X147183Y433167D01*
X147850Y433000D01*
X148433Y433167D01*
X148933Y433500D01*
G01X153200Y433000D02*
X152700Y433083D01*
X152200Y433417D01*
X151867Y434000D01*
X151700Y434667D01*
X151867Y435333D01*
X152200Y435917D01*
X152700Y436250D01*
X153200Y436333D01*
X153700Y436250D01*
X154200Y435917D01*
X154533Y435333D01*
X154617Y434667D01*
X154533Y434000D01*
X154200Y433417D01*
X153700Y433083D01*
X153200Y433000D01*
G01X157383D02*
Y436333D01*
G01Y435500D02*
X157717Y435917D01*
X158217Y436250D01*
X158883Y436333D01*
X159467Y436250D01*
X159967Y435917D01*
X160217Y435333D01*
Y433000D01*
G01X164400Y438000D02*
Y433000D01*
G01X163233Y436333D02*
X165567D01*
G01X168833Y433000D02*
Y436333D01*
G01Y435667D02*
X169250Y436000D01*
X169667Y436250D01*
X170250Y436333D01*
X170667Y436250D01*
X171167Y436000D01*
G01X175600Y433000D02*
X175100Y433083D01*
X174600Y433417D01*
X174267Y434000D01*
X174100Y434667D01*
X174267Y435333D01*
X174600Y435917D01*
X175100Y436250D01*
X175600Y436333D01*
X176100Y436250D01*
X176600Y435917D01*
X176933Y435333D01*
X177017Y434667D01*
X176933Y434000D01*
X176600Y433417D01*
X176100Y433083D01*
X175600Y433000D01*
G01X181200D02*
Y438000D01*
G01X190983Y433000D02*
Y438000D01*
G01Y435583D02*
X191400Y436000D01*
X191817Y436250D01*
X192483Y436333D01*
X192983Y436250D01*
X193567Y435917D01*
X193817Y435417D01*
Y433000D01*
G01X198000D02*
X197500Y433083D01*
X197000Y433417D01*
X196667Y434000D01*
X196500Y434667D01*
X196667Y435333D01*
X197000Y435917D01*
X197500Y436250D01*
X198000Y436333D01*
X198500Y436250D01*
X199000Y435917D01*
X199333Y435333D01*
X199417Y434667D01*
X199333Y434000D01*
X199000Y433417D01*
X198500Y433083D01*
X198000Y433000D01*
G01X203600D02*
Y438000D01*
G01X207950Y435250D02*
X210617D01*
X210367Y435833D01*
X209950Y436167D01*
X209367Y436333D01*
X208783Y436250D01*
X208283Y436000D01*
X207950Y435417D01*
X207783Y434917D01*
Y434417D01*
X207950Y433917D01*
X208367Y433417D01*
X208867Y433083D01*
X209450Y433000D01*
X210033Y433167D01*
X210617Y433667D01*
G01X112333Y455000D02*
Y460000D01*
X114417D01*
X115083Y459750D01*
X115500Y459417D01*
X115667Y458750D01*
X115500Y458083D01*
X115000Y457667D01*
X114417Y457417D01*
X112333D01*
G01X114417D02*
X115667Y455000D01*
G01X119600D02*
X119100Y455083D01*
X118600Y455417D01*
X118267Y456000D01*
X118100Y456667D01*
X118267Y457333D01*
X118600Y457917D01*
X119100Y458250D01*
X119600Y458333D01*
X120100Y458250D01*
X120600Y457917D01*
X120933Y457333D01*
X121017Y456667D01*
X120933Y456000D01*
X120600Y455417D01*
X120100Y455083D01*
X119600Y455000D01*
G01X123783Y458333D02*
Y456000D01*
X124117Y455417D01*
X124617Y455083D01*
X125200Y455000D01*
X125783Y455083D01*
X126283Y455417D01*
X126617Y456000D01*
G01Y455000D02*
Y458333D01*
G01X129633Y453750D02*
X130217Y453417D01*
X130883Y453333D01*
X131467Y453417D01*
X131967Y453833D01*
X132300Y454417D01*
Y458333D01*
G01Y457667D02*
X131967Y458000D01*
X131467Y458250D01*
X130883Y458333D01*
X130217Y458167D01*
X129800Y457833D01*
X129467Y457250D01*
X129300Y456667D01*
X129383Y456167D01*
X129717Y455583D01*
X130217Y455167D01*
X130883Y455000D01*
X131383Y455083D01*
X131967Y455417D01*
X132300Y455750D01*
G01X134983Y455000D02*
Y460000D01*
G01Y457583D02*
X135400Y458000D01*
X135817Y458250D01*
X136483Y458333D01*
X136983Y458250D01*
X137567Y457917D01*
X137817Y457417D01*
Y455000D01*
G01X140583D02*
Y458333D01*
G01Y457500D02*
X140917Y457917D01*
X141417Y458250D01*
X142083Y458333D01*
X142667Y458250D01*
X143167Y457917D01*
X143417Y457333D01*
Y455000D01*
G01X146350Y457250D02*
X149017D01*
X148767Y457833D01*
X148350Y458167D01*
X147767Y458333D01*
X147183Y458250D01*
X146683Y458000D01*
X146350Y457417D01*
X146183Y456917D01*
Y456417D01*
X146350Y455917D01*
X146767Y455417D01*
X147267Y455083D01*
X147850Y455000D01*
X148433Y455167D01*
X149017Y455667D01*
G01X151950Y455583D02*
X152367Y455250D01*
X152950Y455000D01*
X153450D01*
X153950Y455167D01*
X154283Y455417D01*
X154450Y455750D01*
X154367Y456250D01*
X154033Y456500D01*
X152533Y457000D01*
X152200Y457583D01*
X152367Y458000D01*
X152700Y458250D01*
X153200Y458333D01*
X153700Y458250D01*
X154200Y458000D01*
G01X157550Y455583D02*
X157967Y455250D01*
X158550Y455000D01*
X159050D01*
X159550Y455167D01*
X159883Y455417D01*
X160050Y455750D01*
X159967Y456250D01*
X159633Y456500D01*
X158133Y457000D01*
X157800Y457583D01*
X157967Y458000D01*
X158300Y458250D01*
X158800Y458333D01*
X159300Y458250D01*
X159800Y458000D01*
G01X112250Y513500D02*
Y518500D01*
G01X115750D02*
Y513500D01*
G01Y516000D02*
X112250D01*
G01X119600Y513500D02*
X119100Y513583D01*
X118600Y513917D01*
X118267Y514500D01*
X118100Y515167D01*
X118267Y515833D01*
X118600Y516417D01*
X119100Y516750D01*
X119600Y516833D01*
X120100Y516750D01*
X120600Y516417D01*
X120933Y515833D01*
X121017Y515167D01*
X120933Y514500D01*
X120600Y513917D01*
X120100Y513583D01*
X119600Y513500D01*
G01X125200D02*
Y518500D01*
G01X129550Y515750D02*
X132217D01*
X131967Y516333D01*
X131550Y516667D01*
X130967Y516833D01*
X130383Y516750D01*
X129883Y516500D01*
X129550Y515917D01*
X129383Y515417D01*
Y514917D01*
X129550Y514417D01*
X129967Y513917D01*
X130467Y513583D01*
X131050Y513500D01*
X131633Y513667D01*
X132217Y514167D01*
G01X140750Y514083D02*
X141167Y513750D01*
X141750Y513500D01*
X142250D01*
X142750Y513667D01*
X143083Y513917D01*
X143250Y514250D01*
X143167Y514750D01*
X142833Y515000D01*
X141333Y515500D01*
X141000Y516083D01*
X141167Y516500D01*
X141500Y516750D01*
X142000Y516833D01*
X142500Y516750D01*
X143000Y516500D01*
G01X147600Y516833D02*
Y513500D01*
G01Y518167D02*
X147433Y518250D01*
Y518417D01*
X147600Y518500D01*
X147767Y518417D01*
Y518250D01*
X147600Y518167D01*
G01X151950Y516833D02*
X154450D01*
X151950Y513500D01*
X154450D01*
G01X157550Y515750D02*
X160217D01*
X159967Y516333D01*
X159550Y516667D01*
X158967Y516833D01*
X158383Y516750D01*
X157883Y516500D01*
X157550Y515917D01*
X157383Y515417D01*
Y514917D01*
X157550Y514417D01*
X157967Y513917D01*
X158467Y513583D01*
X159050Y513500D01*
X159633Y513667D01*
X160217Y514167D01*
G01X111917Y610000D02*
X114000Y605000D01*
X116083Y610000D01*
G01X119600Y608333D02*
Y605000D01*
G01Y609667D02*
X119433Y609750D01*
Y609917D01*
X119600Y610000D01*
X119767Y609917D01*
Y609750D01*
X119600Y609667D01*
G01X126700Y605000D02*
Y608333D01*
G01Y607750D02*
X126367Y608083D01*
X125867Y608250D01*
X125283Y608333D01*
X124700Y608167D01*
X124200Y607833D01*
X123867Y607333D01*
X123700Y606667D01*
X123867Y606000D01*
X124200Y605500D01*
X124700Y605167D01*
X125283Y605000D01*
X125867Y605083D01*
X126367Y605333D01*
X126700Y605667D01*
G01X134983Y605000D02*
Y610000D01*
G01Y607583D02*
X135400Y608000D01*
X135817Y608250D01*
X136483Y608333D01*
X136983Y608250D01*
X137567Y607917D01*
X137817Y607417D01*
Y605000D01*
G01X142000D02*
X141500Y605083D01*
X141000Y605417D01*
X140667Y606000D01*
X140500Y606667D01*
X140667Y607333D01*
X141000Y607917D01*
X141500Y608250D01*
X142000Y608333D01*
X142500Y608250D01*
X143000Y607917D01*
X143333Y607333D01*
X143417Y606667D01*
X143333Y606000D01*
X143000Y605417D01*
X142500Y605083D01*
X142000Y605000D01*
G01X147600D02*
Y610000D01*
G01X151950Y607250D02*
X154617D01*
X154367Y607833D01*
X153950Y608167D01*
X153367Y608333D01*
X152783Y608250D01*
X152283Y608000D01*
X151950Y607417D01*
X151783Y606917D01*
Y606417D01*
X151950Y605917D01*
X152367Y605417D01*
X152867Y605083D01*
X153450Y605000D01*
X154033Y605167D01*
X154617Y605667D01*
G01X164400Y610000D02*
Y605000D01*
G01X163233Y608333D02*
X165567D01*
G01X168583Y605000D02*
Y610000D01*
G01Y607583D02*
X169000Y608000D01*
X169417Y608250D01*
X170083Y608333D01*
X170583Y608250D01*
X171167Y607917D01*
X171417Y607417D01*
Y605000D01*
G01X174350Y607250D02*
X177017D01*
X176767Y607833D01*
X176350Y608167D01*
X175767Y608333D01*
X175183Y608250D01*
X174683Y608000D01*
X174350Y607417D01*
X174183Y606917D01*
Y606417D01*
X174350Y605917D01*
X174767Y605417D01*
X175267Y605083D01*
X175850Y605000D01*
X176433Y605167D01*
X177017Y605667D01*
G01X180033Y605000D02*
Y608333D01*
G01Y607667D02*
X180450Y608000D01*
X180867Y608250D01*
X181450Y608333D01*
X181867Y608250D01*
X182367Y608000D01*
G01X184300Y605000D02*
Y608333D01*
G01Y607417D02*
X184550Y607833D01*
X184967Y608167D01*
X185550Y608333D01*
X186133Y608167D01*
X186550Y607833D01*
X186800Y607417D01*
Y605000D01*
G01Y607417D02*
X187050Y607833D01*
X187467Y608167D01*
X188050Y608333D01*
X188633Y608167D01*
X189050Y607833D01*
X189300Y607333D01*
Y605000D01*
G01X193900D02*
Y608333D01*
G01Y607750D02*
X193567Y608083D01*
X193067Y608250D01*
X192483Y608333D01*
X191900Y608167D01*
X191400Y607833D01*
X191067Y607333D01*
X190900Y606667D01*
X191067Y606000D01*
X191400Y605500D01*
X191900Y605167D01*
X192483Y605000D01*
X193067Y605083D01*
X193567Y605333D01*
X193900Y605667D01*
G01X198000Y605000D02*
Y610000D01*
G01X207700Y603333D02*
Y608333D01*
G01Y607583D02*
X208117Y608000D01*
X208533Y608250D01*
X209200Y608333D01*
X209783Y608250D01*
X210367Y607833D01*
X210617Y607250D01*
X210700Y606667D01*
X210617Y606083D01*
X210367Y605500D01*
X209867Y605167D01*
X209200Y605000D01*
X208617Y605083D01*
X208033Y605333D01*
X207700Y605667D01*
G01X216300Y605000D02*
Y608333D01*
G01Y607750D02*
X215967Y608083D01*
X215467Y608250D01*
X214883Y608333D01*
X214300Y608167D01*
X213800Y607833D01*
X213467Y607333D01*
X213300Y606667D01*
X213467Y606000D01*
X213800Y605500D01*
X214300Y605167D01*
X214883Y605000D01*
X215467Y605083D01*
X215967Y605333D01*
X216300Y605667D01*
G01X221900Y610000D02*
Y605000D01*
G01Y605750D02*
X221567Y605333D01*
X221067Y605083D01*
X220483Y605000D01*
X219817Y605167D01*
X219317Y605583D01*
X218983Y606083D01*
X218900Y606667D01*
X218983Y607250D01*
X219317Y607750D01*
X219817Y608167D01*
X220483Y608333D01*
X221067Y608250D01*
X221483Y608083D01*
X221900Y607750D01*
G01X112250Y588500D02*
Y593500D01*
G01X115750D02*
Y588500D01*
G01Y591000D02*
X112250D01*
G01X119600Y588500D02*
X119100Y588583D01*
X118600Y588917D01*
X118267Y589500D01*
X118100Y590167D01*
X118267Y590833D01*
X118600Y591417D01*
X119100Y591750D01*
X119600Y591833D01*
X120100Y591750D01*
X120600Y591417D01*
X120933Y590833D01*
X121017Y590167D01*
X120933Y589500D01*
X120600Y588917D01*
X120100Y588583D01*
X119600Y588500D01*
G01X125200D02*
Y593500D01*
G01X129550Y590750D02*
X132217D01*
X131967Y591333D01*
X131550Y591667D01*
X130967Y591833D01*
X130383Y591750D01*
X129883Y591500D01*
X129550Y590917D01*
X129383Y590417D01*
Y589917D01*
X129550Y589417D01*
X129967Y588917D01*
X130467Y588583D01*
X131050Y588500D01*
X131633Y588667D01*
X132217Y589167D01*
G01X140500Y586833D02*
Y591833D01*
G01Y591083D02*
X140917Y591500D01*
X141333Y591750D01*
X142000Y591833D01*
X142583Y591750D01*
X143167Y591333D01*
X143417Y590750D01*
X143500Y590167D01*
X143417Y589583D01*
X143167Y589000D01*
X142667Y588667D01*
X142000Y588500D01*
X141417Y588583D01*
X140833Y588833D01*
X140500Y589167D01*
G01X147600Y588500D02*
X147100Y588583D01*
X146600Y588917D01*
X146267Y589500D01*
X146100Y590167D01*
X146267Y590833D01*
X146600Y591417D01*
X147100Y591750D01*
X147600Y591833D01*
X148100Y591750D01*
X148600Y591417D01*
X148933Y590833D01*
X149017Y590167D01*
X148933Y589500D01*
X148600Y588917D01*
X148100Y588583D01*
X147600Y588500D01*
G01X151950Y589083D02*
X152367Y588750D01*
X152950Y588500D01*
X153450D01*
X153950Y588667D01*
X154283Y588917D01*
X154450Y589250D01*
X154367Y589750D01*
X154033Y590000D01*
X152533Y590500D01*
X152200Y591083D01*
X152367Y591500D01*
X152700Y591750D01*
X153200Y591833D01*
X153700Y591750D01*
X154200Y591500D01*
G01X158800Y591833D02*
Y588500D01*
G01Y593167D02*
X158633Y593250D01*
Y593417D01*
X158800Y593500D01*
X158967Y593417D01*
Y593250D01*
X158800Y593167D01*
G01X164400Y593500D02*
Y588500D01*
G01X163233Y591833D02*
X165567D01*
G01X170000D02*
Y588500D01*
G01Y593167D02*
X169833Y593250D01*
Y593417D01*
X170000Y593500D01*
X170167Y593417D01*
Y593250D01*
X170000Y593167D01*
G01X175600Y588500D02*
X175100Y588583D01*
X174600Y588917D01*
X174267Y589500D01*
X174100Y590167D01*
X174267Y590833D01*
X174600Y591417D01*
X175100Y591750D01*
X175600Y591833D01*
X176100Y591750D01*
X176600Y591417D01*
X176933Y590833D01*
X177017Y590167D01*
X176933Y589500D01*
X176600Y588917D01*
X176100Y588583D01*
X175600Y588500D01*
G01X179783D02*
Y591833D01*
G01Y591000D02*
X180117Y591417D01*
X180617Y591750D01*
X181283Y591833D01*
X181867Y591750D01*
X182367Y591417D01*
X182617Y590833D01*
Y588500D01*
G01X192400Y593500D02*
Y588500D01*
G01X191233Y591833D02*
X193567D01*
G01X198000Y588500D02*
X197500Y588583D01*
X197000Y588917D01*
X196667Y589500D01*
X196500Y590167D01*
X196667Y590833D01*
X197000Y591417D01*
X197500Y591750D01*
X198000Y591833D01*
X198500Y591750D01*
X199000Y591417D01*
X199333Y590833D01*
X199417Y590167D01*
X199333Y589500D01*
X199000Y588917D01*
X198500Y588583D01*
X198000Y588500D01*
G01X203600D02*
Y593500D01*
G01X207950Y590750D02*
X210617D01*
X210367Y591333D01*
X209950Y591667D01*
X209367Y591833D01*
X208783Y591750D01*
X208283Y591500D01*
X207950Y590917D01*
X207783Y590417D01*
Y589917D01*
X207950Y589417D01*
X208367Y588917D01*
X208867Y588583D01*
X209450Y588500D01*
X210033Y588667D01*
X210617Y589167D01*
G01X213633Y588500D02*
Y591833D01*
G01Y591167D02*
X214050Y591500D01*
X214467Y591750D01*
X215050Y591833D01*
X215467Y591750D01*
X215967Y591500D01*
G01X221900Y588500D02*
Y591833D01*
G01Y591250D02*
X221567Y591583D01*
X221067Y591750D01*
X220483Y591833D01*
X219900Y591667D01*
X219400Y591333D01*
X219067Y590833D01*
X218900Y590167D01*
X219067Y589500D01*
X219400Y589000D01*
X219900Y588667D01*
X220483Y588500D01*
X221067Y588583D01*
X221567Y588833D01*
X221900Y589167D01*
G01X224583Y588500D02*
Y591833D01*
G01Y591000D02*
X224917Y591417D01*
X225417Y591750D01*
X226083Y591833D01*
X226667Y591750D01*
X227167Y591417D01*
X227417Y590833D01*
Y588500D01*
G01X232933Y591417D02*
X232350Y591750D01*
X231850Y591833D01*
X231183Y591667D01*
X230683Y591333D01*
X230350Y590750D01*
X230267Y590167D01*
X230350Y589583D01*
X230683Y589083D01*
X231183Y588667D01*
X231850Y588500D01*
X232433Y588667D01*
X232933Y589000D01*
G01X235950Y590750D02*
X238617D01*
X238367Y591333D01*
X237950Y591667D01*
X237367Y591833D01*
X236783Y591750D01*
X236283Y591500D01*
X235950Y590917D01*
X235783Y590417D01*
Y589917D01*
X235950Y589417D01*
X236367Y588917D01*
X236867Y588583D01*
X237450Y588500D01*
X238033Y588667D01*
X238617Y589167D01*
G01X111917Y620000D02*
X114000Y625000D01*
X116083Y620000D01*
G01X115333Y621750D02*
X112667D01*
G01X118183Y620000D02*
Y623333D01*
G01Y622500D02*
X118517Y622917D01*
X119017Y623250D01*
X119683Y623333D01*
X120267Y623250D01*
X120767Y622917D01*
X121017Y622333D01*
Y620000D01*
G01X125200Y625000D02*
Y620000D01*
G01X124033Y623333D02*
X126367D01*
G01X130800D02*
Y620000D01*
G01Y624667D02*
X130633Y624750D01*
Y624917D01*
X130800Y625000D01*
X130967Y624917D01*
Y624750D01*
X130800Y624667D01*
G01X135317Y621667D02*
X137483D01*
G01X146100Y618333D02*
Y623333D01*
G01Y622583D02*
X146517Y623000D01*
X146933Y623250D01*
X147600Y623333D01*
X148183Y623250D01*
X148767Y622833D01*
X149017Y622250D01*
X149100Y621667D01*
X149017Y621083D01*
X148767Y620500D01*
X148267Y620167D01*
X147600Y620000D01*
X147017Y620083D01*
X146433Y620333D01*
X146100Y620667D01*
G01X154700Y620000D02*
Y623333D01*
G01Y622750D02*
X154367Y623083D01*
X153867Y623250D01*
X153283Y623333D01*
X152700Y623167D01*
X152200Y622833D01*
X151867Y622333D01*
X151700Y621667D01*
X151867Y621000D01*
X152200Y620500D01*
X152700Y620167D01*
X153283Y620000D01*
X153867Y620083D01*
X154367Y620333D01*
X154700Y620667D01*
G01X160300Y625000D02*
Y620000D01*
G01Y620750D02*
X159967Y620333D01*
X159467Y620083D01*
X158883Y620000D01*
X158217Y620167D01*
X157717Y620583D01*
X157383Y621083D01*
X157300Y621667D01*
X157383Y622250D01*
X157717Y622750D01*
X158217Y623167D01*
X158883Y623333D01*
X159467Y623250D01*
X159883Y623083D01*
X160300Y622750D01*
G01X160333Y668083D02*
X159833Y668333D01*
X159250Y668500D01*
X158583D01*
X157833Y668250D01*
X157250Y667833D01*
X156833Y667333D01*
X156500Y666500D01*
X156417Y665750D01*
X156583Y665000D01*
X156833Y664500D01*
X157333Y664000D01*
X157917Y663667D01*
X158500Y663500D01*
X159083D01*
X159667Y663667D01*
X160167Y663917D01*
X160583Y664250D01*
G01X164100Y663500D02*
Y668500D01*
G01X171200Y663500D02*
Y666833D01*
G01Y666250D02*
X170867Y666583D01*
X170367Y666750D01*
X169783Y666833D01*
X169200Y666667D01*
X168700Y666333D01*
X168367Y665833D01*
X168200Y665167D01*
X168367Y664500D01*
X168700Y664000D01*
X169200Y663667D01*
X169783Y663500D01*
X170367Y663583D01*
X170867Y663833D01*
X171200Y664167D01*
G01X174050Y664083D02*
X174467Y663750D01*
X175050Y663500D01*
X175550D01*
X176050Y663667D01*
X176383Y663917D01*
X176550Y664250D01*
X176467Y664750D01*
X176133Y665000D01*
X174633Y665500D01*
X174300Y666083D01*
X174467Y666500D01*
X174800Y666750D01*
X175300Y666833D01*
X175800Y666750D01*
X176300Y666500D01*
G01X179650Y664083D02*
X180067Y663750D01*
X180650Y663500D01*
X181150D01*
X181650Y663667D01*
X181983Y663917D01*
X182150Y664250D01*
X182067Y664750D01*
X181733Y665000D01*
X180233Y665500D01*
X179900Y666083D01*
X180067Y666500D01*
X180400Y666750D01*
X180900Y666833D01*
X181400Y666750D01*
X181900Y666500D01*
G01X186500Y666833D02*
Y663500D01*
G01Y668167D02*
X186333Y668250D01*
Y668417D01*
X186500Y668500D01*
X186667Y668417D01*
Y668250D01*
X186500Y668167D01*
G01X191600Y663500D02*
Y667750D01*
X191767Y668167D01*
X192100Y668417D01*
X192600Y668500D01*
X193100Y668333D01*
X193350Y667917D01*
G01X192350Y666500D02*
X190683D01*
G01X195950Y662000D02*
X196450Y661833D01*
X197117Y662000D01*
X197533Y662333D01*
X197867Y662750D01*
X198367Y664083D01*
X199450Y666833D01*
G01X196783D02*
X198367Y664083D01*
G01X274000Y-63500D02*
Y-60167D01*
G01Y-60750D02*
X273667Y-60417D01*
X273167Y-60250D01*
X272583Y-60167D01*
X272000Y-60333D01*
X271500Y-60667D01*
X271167Y-61167D01*
X271000Y-61833D01*
X271167Y-62500D01*
X271500Y-63000D01*
X272000Y-63333D01*
X272583Y-63500D01*
X273167Y-63417D01*
X273667Y-63167D01*
X274000Y-62833D01*
G01X279600Y-58500D02*
Y-63500D01*
G01Y-62750D02*
X279267Y-63167D01*
X278767Y-63417D01*
X278183Y-63500D01*
X277517Y-63333D01*
X277017Y-62917D01*
X276683Y-62417D01*
X276600Y-61833D01*
X276683Y-61250D01*
X277017Y-60750D01*
X277517Y-60333D01*
X278183Y-60167D01*
X278767Y-60250D01*
X279183Y-60417D01*
X279600Y-60750D01*
G01X285200Y-58500D02*
Y-63500D01*
G01Y-62750D02*
X284867Y-63167D01*
X284367Y-63417D01*
X283783Y-63500D01*
X283117Y-63333D01*
X282617Y-62917D01*
X282283Y-62417D01*
X282200Y-61833D01*
X282283Y-61250D01*
X282617Y-60750D01*
X283117Y-60333D01*
X283783Y-60167D01*
X284367Y-60250D01*
X284783Y-60417D01*
X285200Y-60750D01*
G01X293650Y-62917D02*
X294067Y-63250D01*
X294650Y-63500D01*
X295150D01*
X295650Y-63333D01*
X295983Y-63083D01*
X296150Y-62750D01*
X296067Y-62250D01*
X295733Y-62000D01*
X294233Y-61500D01*
X293900Y-60917D01*
X294067Y-60500D01*
X294400Y-60250D01*
X294900Y-60167D01*
X295400Y-60250D01*
X295900Y-60500D01*
G01X299083Y-60167D02*
Y-62500D01*
X299417Y-63083D01*
X299917Y-63417D01*
X300500Y-63500D01*
X301083Y-63417D01*
X301583Y-63083D01*
X301917Y-62500D01*
G01Y-63500D02*
Y-60167D01*
G01X304600Y-65167D02*
Y-60167D01*
G01Y-60917D02*
X305017Y-60500D01*
X305433Y-60250D01*
X306100Y-60167D01*
X306683Y-60250D01*
X307267Y-60667D01*
X307517Y-61250D01*
X307600Y-61833D01*
X307517Y-62417D01*
X307267Y-63000D01*
X306767Y-63333D01*
X306100Y-63500D01*
X305517Y-63417D01*
X304933Y-63167D01*
X304600Y-62833D01*
G01X310200Y-65167D02*
Y-60167D01*
G01Y-60917D02*
X310617Y-60500D01*
X311033Y-60250D01*
X311700Y-60167D01*
X312283Y-60250D01*
X312867Y-60667D01*
X313117Y-61250D01*
X313200Y-61833D01*
X313117Y-62417D01*
X312867Y-63000D01*
X312367Y-63333D01*
X311700Y-63500D01*
X311117Y-63417D01*
X310533Y-63167D01*
X310200Y-62833D01*
G01X317300Y-63500D02*
Y-58500D01*
G01X322900Y-60167D02*
Y-63500D01*
G01Y-58833D02*
X322733Y-58750D01*
Y-58583D01*
X322900Y-58500D01*
X323067Y-58583D01*
Y-58750D01*
X322900Y-58833D01*
G01X327250Y-61250D02*
X329917D01*
X329667Y-60667D01*
X329250Y-60333D01*
X328667Y-60167D01*
X328083Y-60250D01*
X327583Y-60500D01*
X327250Y-61083D01*
X327083Y-61583D01*
Y-62083D01*
X327250Y-62583D01*
X327667Y-63083D01*
X328167Y-63417D01*
X328750Y-63500D01*
X329333Y-63333D01*
X329917Y-62833D01*
G01X332933Y-63500D02*
Y-60167D01*
G01Y-60833D02*
X333350Y-60500D01*
X333767Y-60250D01*
X334350Y-60167D01*
X334767Y-60250D01*
X335267Y-60500D01*
G01X339700Y-60167D02*
X340533Y-59125D01*
Y-58500D01*
X339908D01*
Y-59125D01*
X340533D01*
G01X344050Y-62917D02*
X344467Y-63250D01*
X345050Y-63500D01*
X345550D01*
X346050Y-63333D01*
X346383Y-63083D01*
X346550Y-62750D01*
X346467Y-62250D01*
X346133Y-62000D01*
X344633Y-61500D01*
X344300Y-60917D01*
X344467Y-60500D01*
X344800Y-60250D01*
X345300Y-60167D01*
X345800Y-60250D01*
X346300Y-60500D01*
G01X354833Y-58500D02*
Y-63500D01*
X358167D01*
G01X362100D02*
X361600Y-63417D01*
X361100Y-63083D01*
X360767Y-62500D01*
X360600Y-61833D01*
X360767Y-61167D01*
X361100Y-60583D01*
X361600Y-60250D01*
X362100Y-60167D01*
X362600Y-60250D01*
X363100Y-60583D01*
X363433Y-61167D01*
X363517Y-61833D01*
X363433Y-62500D01*
X363100Y-63083D01*
X362600Y-63417D01*
X362100Y-63500D01*
G01X366533Y-64750D02*
X367117Y-65083D01*
X367783Y-65167D01*
X368367Y-65083D01*
X368867Y-64667D01*
X369200Y-64083D01*
Y-60167D01*
G01Y-60833D02*
X368867Y-60500D01*
X368367Y-60250D01*
X367783Y-60167D01*
X367117Y-60333D01*
X366700Y-60667D01*
X366367Y-61250D01*
X366200Y-61833D01*
X366283Y-62333D01*
X366617Y-62917D01*
X367117Y-63333D01*
X367783Y-63500D01*
X368283Y-63417D01*
X368867Y-63083D01*
X369200Y-62750D01*
G01X373300Y-63500D02*
X372800Y-63417D01*
X372300Y-63083D01*
X371967Y-62500D01*
X371800Y-61833D01*
X371967Y-61167D01*
X372300Y-60583D01*
X372800Y-60250D01*
X373300Y-60167D01*
X373800Y-60250D01*
X374300Y-60583D01*
X374633Y-61167D01*
X374717Y-61833D01*
X374633Y-62500D01*
X374300Y-63083D01*
X373800Y-63417D01*
X373300Y-63500D01*
G01X386000D02*
Y-60167D01*
G01Y-60750D02*
X385667Y-60417D01*
X385167Y-60250D01*
X384583Y-60167D01*
X384000Y-60333D01*
X383500Y-60667D01*
X383167Y-61167D01*
X383000Y-61833D01*
X383167Y-62500D01*
X383500Y-63000D01*
X384000Y-63333D01*
X384583Y-63500D01*
X385167Y-63417D01*
X385667Y-63167D01*
X386000Y-62833D01*
G01X388683Y-63500D02*
Y-60167D01*
G01Y-61000D02*
X389017Y-60583D01*
X389517Y-60250D01*
X390183Y-60167D01*
X390767Y-60250D01*
X391267Y-60583D01*
X391517Y-61167D01*
Y-63500D01*
G01X397200Y-58500D02*
Y-63500D01*
G01Y-62750D02*
X396867Y-63167D01*
X396367Y-63417D01*
X395783Y-63500D01*
X395117Y-63333D01*
X394617Y-62917D01*
X394283Y-62417D01*
X394200Y-61833D01*
X394283Y-61250D01*
X394617Y-60750D01*
X395117Y-60333D01*
X395783Y-60167D01*
X396367Y-60250D01*
X396783Y-60417D01*
X397200Y-60750D01*
G01X405067Y-58500D02*
Y-62083D01*
X405400Y-62833D01*
X406067Y-63333D01*
X406900Y-63500D01*
X407733Y-63333D01*
X408400Y-62833D01*
X408733Y-62083D01*
Y-58500D01*
G01X410833D02*
Y-63500D01*
X414167D01*
G01X423200D02*
Y-59250D01*
X423367Y-58833D01*
X423700Y-58583D01*
X424200Y-58500D01*
X424700Y-58667D01*
X424950Y-59083D01*
G01X423950Y-60500D02*
X422283D01*
G01X429300Y-60167D02*
Y-63500D01*
G01Y-58833D02*
X429133Y-58750D01*
Y-58583D01*
X429300Y-58500D01*
X429467Y-58583D01*
Y-58750D01*
X429300Y-58833D01*
G01X434900Y-63500D02*
Y-58500D01*
G01X439250Y-61250D02*
X441917D01*
X441667Y-60667D01*
X441250Y-60333D01*
X440667Y-60167D01*
X440083Y-60250D01*
X439583Y-60500D01*
X439250Y-61083D01*
X439083Y-61583D01*
Y-62083D01*
X439250Y-62583D01*
X439667Y-63083D01*
X440167Y-63417D01*
X440750Y-63500D01*
X441333Y-63333D01*
X441917Y-62833D01*
G01X449783Y-63500D02*
Y-58500D01*
X453617Y-63500D01*
Y-58500D01*
G01X455883Y-60167D02*
Y-62500D01*
X456217Y-63083D01*
X456717Y-63417D01*
X457300Y-63500D01*
X457883Y-63417D01*
X458383Y-63083D01*
X458717Y-62500D01*
G01Y-63500D02*
Y-60167D01*
G01X460400Y-63500D02*
Y-60167D01*
G01Y-61083D02*
X460650Y-60667D01*
X461067Y-60333D01*
X461650Y-60167D01*
X462233Y-60333D01*
X462650Y-60667D01*
X462900Y-61083D01*
Y-63500D01*
G01Y-61083D02*
X463150Y-60667D01*
X463567Y-60333D01*
X464150Y-60167D01*
X464733Y-60333D01*
X465150Y-60667D01*
X465400Y-61167D01*
Y-63500D01*
G01X467000D02*
Y-58500D01*
G01Y-61000D02*
X467417Y-60500D01*
X467917Y-60250D01*
X468417Y-60167D01*
X469167Y-60333D01*
X469667Y-60667D01*
X470000Y-61250D01*
Y-61917D01*
X469833Y-62583D01*
X469500Y-63083D01*
X468917Y-63417D01*
X468417Y-63500D01*
X467917Y-63417D01*
X467417Y-63167D01*
X467000Y-62750D01*
G01X472850Y-61250D02*
X475517D01*
X475267Y-60667D01*
X474850Y-60333D01*
X474267Y-60167D01*
X473683Y-60250D01*
X473183Y-60500D01*
X472850Y-61083D01*
X472683Y-61583D01*
Y-62083D01*
X472850Y-62583D01*
X473267Y-63083D01*
X473767Y-63417D01*
X474350Y-63500D01*
X474933Y-63333D01*
X475517Y-62833D01*
G01X478533Y-63500D02*
Y-60167D01*
G01Y-60833D02*
X478950Y-60500D01*
X479367Y-60250D01*
X479950Y-60167D01*
X480367Y-60250D01*
X480867Y-60500D01*
G01X490900Y-60167D02*
Y-63500D01*
G01Y-58833D02*
X490733Y-58750D01*
Y-58583D01*
X490900Y-58500D01*
X491067Y-58583D01*
Y-58750D01*
X490900Y-58833D01*
G01X495083Y-63500D02*
Y-60167D01*
G01Y-61000D02*
X495417Y-60583D01*
X495917Y-60250D01*
X496583Y-60167D01*
X497167Y-60250D01*
X497667Y-60583D01*
X497917Y-61167D01*
Y-63500D01*
G01X506450Y-62917D02*
X506867Y-63250D01*
X507450Y-63500D01*
X507950D01*
X508450Y-63333D01*
X508783Y-63083D01*
X508950Y-62750D01*
X508867Y-62250D01*
X508533Y-62000D01*
X507033Y-61500D01*
X506700Y-60917D01*
X506867Y-60500D01*
X507200Y-60250D01*
X507700Y-60167D01*
X508200Y-60250D01*
X508700Y-60500D01*
G01X513300Y-60167D02*
Y-63500D01*
G01Y-58833D02*
X513133Y-58750D01*
Y-58583D01*
X513300Y-58500D01*
X513467Y-58583D01*
Y-58750D01*
X513300Y-58833D01*
G01X518900Y-63500D02*
Y-58500D01*
G01X523083Y-63500D02*
Y-58500D01*
G01X525750Y-60167D02*
X523083Y-62083D01*
G01X524167Y-61333D02*
X525917Y-63500D01*
G01X528850Y-62917D02*
X529267Y-63250D01*
X529850Y-63500D01*
X530350D01*
X530850Y-63333D01*
X531183Y-63083D01*
X531350Y-62750D01*
X531267Y-62250D01*
X530933Y-62000D01*
X529433Y-61500D01*
X529100Y-60917D01*
X529267Y-60500D01*
X529600Y-60250D01*
X530100Y-60167D01*
X530600Y-60250D01*
X531100Y-60500D01*
G01X537033Y-60583D02*
X536450Y-60250D01*
X535950Y-60167D01*
X535283Y-60333D01*
X534783Y-60667D01*
X534450Y-61250D01*
X534367Y-61833D01*
X534450Y-62417D01*
X534783Y-62917D01*
X535283Y-63333D01*
X535950Y-63500D01*
X536533Y-63333D01*
X537033Y-63000D01*
G01X540133Y-63500D02*
Y-60167D01*
G01Y-60833D02*
X540550Y-60500D01*
X540967Y-60250D01*
X541550Y-60167D01*
X541967Y-60250D01*
X542467Y-60500D01*
G01X545650Y-61250D02*
X548317D01*
X548067Y-60667D01*
X547650Y-60333D01*
X547067Y-60167D01*
X546483Y-60250D01*
X545983Y-60500D01*
X545650Y-61083D01*
X545483Y-61583D01*
Y-62083D01*
X545650Y-62583D01*
X546067Y-63083D01*
X546567Y-63417D01*
X547150Y-63500D01*
X547733Y-63333D01*
X548317Y-62833D01*
G01X551250Y-61250D02*
X553917D01*
X553667Y-60667D01*
X553250Y-60333D01*
X552667Y-60167D01*
X552083Y-60250D01*
X551583Y-60500D01*
X551250Y-61083D01*
X551083Y-61583D01*
Y-62083D01*
X551250Y-62583D01*
X551667Y-63083D01*
X552167Y-63417D01*
X552750Y-63500D01*
X553333Y-63333D01*
X553917Y-62833D01*
G01X556683Y-63500D02*
Y-60167D01*
G01Y-61000D02*
X557017Y-60583D01*
X557517Y-60250D01*
X558183Y-60167D01*
X558767Y-60250D01*
X559267Y-60583D01*
X559517Y-61167D01*
Y-63500D01*
G01X270750Y-47833D02*
X271417Y-48250D01*
X272167Y-48500D01*
X272833D01*
X273500Y-48250D01*
X274000Y-47833D01*
X274250Y-47250D01*
X274083Y-46667D01*
X273667Y-46167D01*
X272917Y-45833D01*
X271917Y-45667D01*
X271333Y-45333D01*
X271083Y-44750D01*
X271250Y-44167D01*
X271667Y-43750D01*
X272250Y-43500D01*
X272833D01*
X273417Y-43667D01*
X273917Y-44083D01*
G01X278100Y-48500D02*
X277600Y-48417D01*
X277100Y-48083D01*
X276767Y-47500D01*
X276600Y-46833D01*
X276767Y-46167D01*
X277100Y-45583D01*
X277600Y-45250D01*
X278100Y-45167D01*
X278600Y-45250D01*
X279100Y-45583D01*
X279433Y-46167D01*
X279517Y-46833D01*
X279433Y-47500D01*
X279100Y-48083D01*
X278600Y-48417D01*
X278100Y-48500D01*
G01X283700D02*
Y-43500D01*
G01X290800D02*
Y-48500D01*
G01Y-47750D02*
X290467Y-48167D01*
X289967Y-48417D01*
X289383Y-48500D01*
X288717Y-48333D01*
X288217Y-47917D01*
X287883Y-47417D01*
X287800Y-46833D01*
X287883Y-46250D01*
X288217Y-45750D01*
X288717Y-45333D01*
X289383Y-45167D01*
X289967Y-45250D01*
X290383Y-45417D01*
X290800Y-45750D01*
G01X293650Y-46250D02*
X296317D01*
X296067Y-45667D01*
X295650Y-45333D01*
X295067Y-45167D01*
X294483Y-45250D01*
X293983Y-45500D01*
X293650Y-46083D01*
X293483Y-46583D01*
Y-47083D01*
X293650Y-47583D01*
X294067Y-48083D01*
X294567Y-48417D01*
X295150Y-48500D01*
X295733Y-48333D01*
X296317Y-47833D01*
G01X299333Y-48500D02*
Y-45167D01*
G01Y-45833D02*
X299750Y-45500D01*
X300167Y-45250D01*
X300750Y-45167D01*
X301167Y-45250D01*
X301667Y-45500D01*
G01X309200Y-48500D02*
Y-45167D01*
G01Y-46083D02*
X309450Y-45667D01*
X309867Y-45333D01*
X310450Y-45167D01*
X311033Y-45333D01*
X311450Y-45667D01*
X311700Y-46083D01*
Y-48500D01*
G01Y-46083D02*
X311950Y-45667D01*
X312367Y-45333D01*
X312950Y-45167D01*
X313533Y-45333D01*
X313950Y-45667D01*
X314200Y-46167D01*
Y-48500D01*
G01X318800D02*
Y-45167D01*
G01Y-45750D02*
X318467Y-45417D01*
X317967Y-45250D01*
X317383Y-45167D01*
X316800Y-45333D01*
X316300Y-45667D01*
X315967Y-46167D01*
X315800Y-46833D01*
X315967Y-47500D01*
X316300Y-48000D01*
X316800Y-48333D01*
X317383Y-48500D01*
X317967Y-48417D01*
X318467Y-48167D01*
X318800Y-47833D01*
G01X321650Y-47917D02*
X322067Y-48250D01*
X322650Y-48500D01*
X323150D01*
X323650Y-48333D01*
X323983Y-48083D01*
X324150Y-47750D01*
X324067Y-47250D01*
X323733Y-47000D01*
X322233Y-46500D01*
X321900Y-45917D01*
X322067Y-45500D01*
X322400Y-45250D01*
X322900Y-45167D01*
X323400Y-45250D01*
X323900Y-45500D01*
G01X327083Y-48500D02*
Y-43500D01*
G01X329750Y-45167D02*
X327083Y-47083D01*
G01X328167Y-46333D02*
X329917Y-48500D01*
G01X339700Y-43500D02*
Y-48500D01*
G01X338533Y-45167D02*
X340867D01*
G01X343883Y-48500D02*
Y-43500D01*
G01Y-45917D02*
X344300Y-45500D01*
X344717Y-45250D01*
X345383Y-45167D01*
X345883Y-45250D01*
X346467Y-45583D01*
X346717Y-46083D01*
Y-48500D01*
G01X350900Y-45167D02*
Y-48500D01*
G01Y-43833D02*
X350733Y-43750D01*
Y-43583D01*
X350900Y-43500D01*
X351067Y-43583D01*
Y-43750D01*
X350900Y-43833D01*
G01X357833Y-45583D02*
X357250Y-45250D01*
X356750Y-45167D01*
X356083Y-45333D01*
X355583Y-45667D01*
X355250Y-46250D01*
X355167Y-46833D01*
X355250Y-47417D01*
X355583Y-47917D01*
X356083Y-48333D01*
X356750Y-48500D01*
X357333Y-48333D01*
X357833Y-48000D01*
G01X360683Y-48500D02*
Y-43500D01*
G01X363350Y-45167D02*
X360683Y-47083D01*
G01X361767Y-46333D02*
X363517Y-48500D01*
G01X366283D02*
Y-45167D01*
G01Y-46000D02*
X366617Y-45583D01*
X367117Y-45250D01*
X367783Y-45167D01*
X368367Y-45250D01*
X368867Y-45583D01*
X369117Y-46167D01*
Y-48500D01*
G01X372050Y-46250D02*
X374717D01*
X374467Y-45667D01*
X374050Y-45333D01*
X373467Y-45167D01*
X372883Y-45250D01*
X372383Y-45500D01*
X372050Y-46083D01*
X371883Y-46583D01*
Y-47083D01*
X372050Y-47583D01*
X372467Y-48083D01*
X372967Y-48417D01*
X373550Y-48500D01*
X374133Y-48333D01*
X374717Y-47833D01*
G01X377650Y-47917D02*
X378067Y-48250D01*
X378650Y-48500D01*
X379150D01*
X379650Y-48333D01*
X379983Y-48083D01*
X380150Y-47750D01*
X380067Y-47250D01*
X379733Y-47000D01*
X378233Y-46500D01*
X377900Y-45917D01*
X378067Y-45500D01*
X378400Y-45250D01*
X378900Y-45167D01*
X379400Y-45250D01*
X379900Y-45500D01*
G01X383250Y-47917D02*
X383667Y-48250D01*
X384250Y-48500D01*
X384750D01*
X385250Y-48333D01*
X385583Y-48083D01*
X385750Y-47750D01*
X385667Y-47250D01*
X385333Y-47000D01*
X383833Y-46500D01*
X383500Y-45917D01*
X383667Y-45500D01*
X384000Y-45250D01*
X384500Y-45167D01*
X385000Y-45250D01*
X385500Y-45500D01*
G01X394200Y-50167D02*
Y-45167D01*
G01Y-45917D02*
X394617Y-45500D01*
X395033Y-45250D01*
X395700Y-45167D01*
X396283Y-45250D01*
X396867Y-45667D01*
X397117Y-46250D01*
X397200Y-46833D01*
X397117Y-47417D01*
X396867Y-48000D01*
X396367Y-48333D01*
X395700Y-48500D01*
X395117Y-48417D01*
X394533Y-48167D01*
X394200Y-47833D01*
G01X401300Y-48500D02*
Y-43500D01*
G01X405483Y-45167D02*
Y-47500D01*
X405817Y-48083D01*
X406317Y-48417D01*
X406900Y-48500D01*
X407483Y-48417D01*
X407983Y-48083D01*
X408317Y-47500D01*
G01Y-48500D02*
Y-45167D01*
G01X411250Y-47917D02*
X411667Y-48250D01*
X412250Y-48500D01*
X412750D01*
X413250Y-48333D01*
X413583Y-48083D01*
X413750Y-47750D01*
X413667Y-47250D01*
X413333Y-47000D01*
X411833Y-46500D01*
X411500Y-45917D01*
X411667Y-45500D01*
X412000Y-45250D01*
X412500Y-45167D01*
X413000Y-45250D01*
X413500Y-45500D01*
G01X423700Y-48500D02*
Y-43500D01*
G01X428050Y-46250D02*
X430717D01*
X430467Y-45667D01*
X430050Y-45333D01*
X429467Y-45167D01*
X428883Y-45250D01*
X428383Y-45500D01*
X428050Y-46083D01*
X427883Y-46583D01*
Y-47083D01*
X428050Y-47583D01*
X428467Y-48083D01*
X428967Y-48417D01*
X429550Y-48500D01*
X430133Y-48333D01*
X430717Y-47833D01*
G01X433733Y-49750D02*
X434317Y-50083D01*
X434983Y-50167D01*
X435567Y-50083D01*
X436067Y-49667D01*
X436400Y-49083D01*
Y-45167D01*
G01Y-45833D02*
X436067Y-45500D01*
X435567Y-45250D01*
X434983Y-45167D01*
X434317Y-45333D01*
X433900Y-45667D01*
X433567Y-46250D01*
X433400Y-46833D01*
X433483Y-47333D01*
X433817Y-47917D01*
X434317Y-48333D01*
X434983Y-48500D01*
X435483Y-48417D01*
X436067Y-48083D01*
X436400Y-47750D01*
G01X439250Y-46250D02*
X441917D01*
X441667Y-45667D01*
X441250Y-45333D01*
X440667Y-45167D01*
X440083Y-45250D01*
X439583Y-45500D01*
X439250Y-46083D01*
X439083Y-46583D01*
Y-47083D01*
X439250Y-47583D01*
X439667Y-48083D01*
X440167Y-48417D01*
X440750Y-48500D01*
X441333Y-48333D01*
X441917Y-47833D01*
G01X444683Y-48500D02*
Y-45167D01*
G01Y-46000D02*
X445017Y-45583D01*
X445517Y-45250D01*
X446183Y-45167D01*
X446767Y-45250D01*
X447267Y-45583D01*
X447517Y-46167D01*
Y-48500D01*
G01X453200Y-43500D02*
Y-48500D01*
G01Y-47750D02*
X452867Y-48167D01*
X452367Y-48417D01*
X451783Y-48500D01*
X451117Y-48333D01*
X450617Y-47917D01*
X450283Y-47417D01*
X450200Y-46833D01*
X450283Y-46250D01*
X450617Y-45750D01*
X451117Y-45333D01*
X451783Y-45167D01*
X452367Y-45250D01*
X452783Y-45417D01*
X453200Y-45750D01*
G01X462900Y-43500D02*
Y-48500D01*
G01X461733Y-45167D02*
X464067D01*
G01X467083Y-48500D02*
Y-43500D01*
G01Y-45917D02*
X467500Y-45500D01*
X467917Y-45250D01*
X468583Y-45167D01*
X469083Y-45250D01*
X469667Y-45583D01*
X469917Y-46083D01*
Y-48500D01*
G01X474100Y-45167D02*
Y-48500D01*
G01Y-43833D02*
X473933Y-43750D01*
Y-43583D01*
X474100Y-43500D01*
X474267Y-43583D01*
Y-43750D01*
X474100Y-43833D01*
G01X481033Y-45583D02*
X480450Y-45250D01*
X479950Y-45167D01*
X479283Y-45333D01*
X478783Y-45667D01*
X478450Y-46250D01*
X478367Y-46833D01*
X478450Y-47417D01*
X478783Y-47917D01*
X479283Y-48333D01*
X479950Y-48500D01*
X480533Y-48333D01*
X481033Y-48000D01*
G01X483883Y-48500D02*
Y-43500D01*
G01X486550Y-45167D02*
X483883Y-47083D01*
G01X484967Y-46333D02*
X486717Y-48500D01*
G01X489483D02*
Y-45167D01*
G01Y-46000D02*
X489817Y-45583D01*
X490317Y-45250D01*
X490983Y-45167D01*
X491567Y-45250D01*
X492067Y-45583D01*
X492317Y-46167D01*
Y-48500D01*
G01X495250Y-46250D02*
X497917D01*
X497667Y-45667D01*
X497250Y-45333D01*
X496667Y-45167D01*
X496083Y-45250D01*
X495583Y-45500D01*
X495250Y-46083D01*
X495083Y-46583D01*
Y-47083D01*
X495250Y-47583D01*
X495667Y-48083D01*
X496167Y-48417D01*
X496750Y-48500D01*
X497333Y-48333D01*
X497917Y-47833D01*
G01X500850Y-47917D02*
X501267Y-48250D01*
X501850Y-48500D01*
X502350D01*
X502850Y-48333D01*
X503183Y-48083D01*
X503350Y-47750D01*
X503267Y-47250D01*
X502933Y-47000D01*
X501433Y-46500D01*
X501100Y-45917D01*
X501267Y-45500D01*
X501600Y-45250D01*
X502100Y-45167D01*
X502600Y-45250D01*
X503100Y-45500D01*
G01X506450Y-47917D02*
X506867Y-48250D01*
X507450Y-48500D01*
X507950D01*
X508450Y-48333D01*
X508783Y-48083D01*
X508950Y-47750D01*
X508867Y-47250D01*
X508533Y-47000D01*
X507033Y-46500D01*
X506700Y-45917D01*
X506867Y-45500D01*
X507200Y-45250D01*
X507700Y-45167D01*
X508200Y-45250D01*
X508700Y-45500D01*
G01X518900Y-48500D02*
X518400Y-48417D01*
X517900Y-48083D01*
X517567Y-47500D01*
X517400Y-46833D01*
X517567Y-46167D01*
X517900Y-45583D01*
X518400Y-45250D01*
X518900Y-45167D01*
X519400Y-45250D01*
X519900Y-45583D01*
X520233Y-46167D01*
X520317Y-46833D01*
X520233Y-47500D01*
X519900Y-48083D01*
X519400Y-48417D01*
X518900Y-48500D01*
G01X523083D02*
Y-45167D01*
G01Y-46000D02*
X523417Y-45583D01*
X523917Y-45250D01*
X524583Y-45167D01*
X525167Y-45250D01*
X525667Y-45583D01*
X525917Y-46167D01*
Y-48500D01*
G01X535700Y-43500D02*
Y-48500D01*
G01X534533Y-45167D02*
X536867D01*
G01X540133Y-48500D02*
Y-45167D01*
G01Y-45833D02*
X540550Y-45500D01*
X540967Y-45250D01*
X541550Y-45167D01*
X541967Y-45250D01*
X542467Y-45500D01*
G01X548400Y-48500D02*
Y-45167D01*
G01Y-45750D02*
X548067Y-45417D01*
X547567Y-45250D01*
X546983Y-45167D01*
X546400Y-45333D01*
X545900Y-45667D01*
X545567Y-46167D01*
X545400Y-46833D01*
X545567Y-47500D01*
X545900Y-48000D01*
X546400Y-48333D01*
X546983Y-48500D01*
X547567Y-48417D01*
X548067Y-48167D01*
X548400Y-47833D01*
G01X553833Y-45583D02*
X553250Y-45250D01*
X552750Y-45167D01*
X552083Y-45333D01*
X551583Y-45667D01*
X551250Y-46250D01*
X551167Y-46833D01*
X551250Y-47417D01*
X551583Y-47917D01*
X552083Y-48333D01*
X552750Y-48500D01*
X553333Y-48333D01*
X553833Y-48000D01*
G01X556850Y-46250D02*
X559517D01*
X559267Y-45667D01*
X558850Y-45333D01*
X558267Y-45167D01*
X557683Y-45250D01*
X557183Y-45500D01*
X556850Y-46083D01*
X556683Y-46583D01*
Y-47083D01*
X556850Y-47583D01*
X557267Y-48083D01*
X557767Y-48417D01*
X558350Y-48500D01*
X558933Y-48333D01*
X559517Y-47833D01*
G01X563700Y-48667D02*
X563533Y-48583D01*
Y-48417D01*
X563700Y-48333D01*
X563867Y-48417D01*
Y-48583D01*
X563700Y-48667D01*
G01X272500Y-33500D02*
Y-28500D01*
G01X276850Y-31250D02*
X279517D01*
X279267Y-30667D01*
X278850Y-30333D01*
X278267Y-30167D01*
X277683Y-30250D01*
X277183Y-30500D01*
X276850Y-31083D01*
X276683Y-31583D01*
Y-32083D01*
X276850Y-32583D01*
X277267Y-33083D01*
X277767Y-33417D01*
X278350Y-33500D01*
X278933Y-33333D01*
X279517Y-32833D01*
G01X282533Y-34750D02*
X283117Y-35083D01*
X283783Y-35167D01*
X284367Y-35083D01*
X284867Y-34667D01*
X285200Y-34083D01*
Y-30167D01*
G01Y-30833D02*
X284867Y-30500D01*
X284367Y-30250D01*
X283783Y-30167D01*
X283117Y-30333D01*
X282700Y-30667D01*
X282367Y-31250D01*
X282200Y-31833D01*
X282283Y-32333D01*
X282617Y-32917D01*
X283117Y-33333D01*
X283783Y-33500D01*
X284283Y-33417D01*
X284867Y-33083D01*
X285200Y-32750D01*
G01X288050Y-31250D02*
X290717D01*
X290467Y-30667D01*
X290050Y-30333D01*
X289467Y-30167D01*
X288883Y-30250D01*
X288383Y-30500D01*
X288050Y-31083D01*
X287883Y-31583D01*
Y-32083D01*
X288050Y-32583D01*
X288467Y-33083D01*
X288967Y-33417D01*
X289550Y-33500D01*
X290133Y-33333D01*
X290717Y-32833D01*
G01X293483Y-33500D02*
Y-30167D01*
G01Y-31000D02*
X293817Y-30583D01*
X294317Y-30250D01*
X294983Y-30167D01*
X295567Y-30250D01*
X296067Y-30583D01*
X296317Y-31167D01*
Y-33500D01*
G01X302000Y-28500D02*
Y-33500D01*
G01Y-32750D02*
X301667Y-33167D01*
X301167Y-33417D01*
X300583Y-33500D01*
X299917Y-33333D01*
X299417Y-32917D01*
X299083Y-32417D01*
X299000Y-31833D01*
X299083Y-31250D01*
X299417Y-30750D01*
X299917Y-30333D01*
X300583Y-30167D01*
X301167Y-30250D01*
X301583Y-30417D01*
X302000Y-30750D01*
G01X311700Y-28500D02*
Y-33500D01*
G01X310533Y-30167D02*
X312867D01*
G01X315883Y-33500D02*
Y-28500D01*
G01Y-30917D02*
X316300Y-30500D01*
X316717Y-30250D01*
X317383Y-30167D01*
X317883Y-30250D01*
X318467Y-30583D01*
X318717Y-31083D01*
Y-33500D01*
G01X322900Y-30167D02*
Y-33500D01*
G01Y-28833D02*
X322733Y-28750D01*
Y-28583D01*
X322900Y-28500D01*
X323067Y-28583D01*
Y-28750D01*
X322900Y-28833D01*
G01X329833Y-30583D02*
X329250Y-30250D01*
X328750Y-30167D01*
X328083Y-30333D01*
X327583Y-30667D01*
X327250Y-31250D01*
X327167Y-31833D01*
X327250Y-32417D01*
X327583Y-32917D01*
X328083Y-33333D01*
X328750Y-33500D01*
X329333Y-33333D01*
X329833Y-33000D01*
G01X332683Y-33500D02*
Y-28500D01*
G01X335350Y-30167D02*
X332683Y-32083D01*
G01X333767Y-31333D02*
X335517Y-33500D01*
G01X338283D02*
Y-30167D01*
G01Y-31000D02*
X338617Y-30583D01*
X339117Y-30250D01*
X339783Y-30167D01*
X340367Y-30250D01*
X340867Y-30583D01*
X341117Y-31167D01*
Y-33500D01*
G01X344050Y-31250D02*
X346717D01*
X346467Y-30667D01*
X346050Y-30333D01*
X345467Y-30167D01*
X344883Y-30250D01*
X344383Y-30500D01*
X344050Y-31083D01*
X343883Y-31583D01*
Y-32083D01*
X344050Y-32583D01*
X344467Y-33083D01*
X344967Y-33417D01*
X345550Y-33500D01*
X346133Y-33333D01*
X346717Y-32833D01*
G01X349650Y-32917D02*
X350067Y-33250D01*
X350650Y-33500D01*
X351150D01*
X351650Y-33333D01*
X351983Y-33083D01*
X352150Y-32750D01*
X352067Y-32250D01*
X351733Y-32000D01*
X350233Y-31500D01*
X349900Y-30917D01*
X350067Y-30500D01*
X350400Y-30250D01*
X350900Y-30167D01*
X351400Y-30250D01*
X351900Y-30500D01*
G01X355250Y-32917D02*
X355667Y-33250D01*
X356250Y-33500D01*
X356750D01*
X357250Y-33333D01*
X357583Y-33083D01*
X357750Y-32750D01*
X357667Y-32250D01*
X357333Y-32000D01*
X355833Y-31500D01*
X355500Y-30917D01*
X355667Y-30500D01*
X356000Y-30250D01*
X356500Y-30167D01*
X357000Y-30250D01*
X357500Y-30500D01*
G01X367700Y-33500D02*
X367200Y-33417D01*
X366700Y-33083D01*
X366367Y-32500D01*
X366200Y-31833D01*
X366367Y-31167D01*
X366700Y-30583D01*
X367200Y-30250D01*
X367700Y-30167D01*
X368200Y-30250D01*
X368700Y-30583D01*
X369033Y-31167D01*
X369117Y-31833D01*
X369033Y-32500D01*
X368700Y-33083D01*
X368200Y-33417D01*
X367700Y-33500D01*
G01X371883D02*
Y-30167D01*
G01Y-31000D02*
X372217Y-30583D01*
X372717Y-30250D01*
X373383Y-30167D01*
X373967Y-30250D01*
X374467Y-30583D01*
X374717Y-31167D01*
Y-33500D01*
G01X385833Y-30583D02*
X385250Y-30250D01*
X384750Y-30167D01*
X384083Y-30333D01*
X383583Y-30667D01*
X383250Y-31250D01*
X383167Y-31833D01*
X383250Y-32417D01*
X383583Y-32917D01*
X384083Y-33333D01*
X384750Y-33500D01*
X385333Y-33333D01*
X385833Y-33000D01*
G01X390100Y-33500D02*
X389600Y-33417D01*
X389100Y-33083D01*
X388767Y-32500D01*
X388600Y-31833D01*
X388767Y-31167D01*
X389100Y-30583D01*
X389600Y-30250D01*
X390100Y-30167D01*
X390600Y-30250D01*
X391100Y-30583D01*
X391433Y-31167D01*
X391517Y-31833D01*
X391433Y-32500D01*
X391100Y-33083D01*
X390600Y-33417D01*
X390100Y-33500D01*
G01X394200Y-35167D02*
Y-30167D01*
G01Y-30917D02*
X394617Y-30500D01*
X395033Y-30250D01*
X395700Y-30167D01*
X396283Y-30250D01*
X396867Y-30667D01*
X397117Y-31250D01*
X397200Y-31833D01*
X397117Y-32417D01*
X396867Y-33000D01*
X396367Y-33333D01*
X395700Y-33500D01*
X395117Y-33417D01*
X394533Y-33167D01*
X394200Y-32833D01*
G01X399800Y-35167D02*
Y-30167D01*
G01Y-30917D02*
X400217Y-30500D01*
X400633Y-30250D01*
X401300Y-30167D01*
X401883Y-30250D01*
X402467Y-30667D01*
X402717Y-31250D01*
X402800Y-31833D01*
X402717Y-32417D01*
X402467Y-33000D01*
X401967Y-33333D01*
X401300Y-33500D01*
X400717Y-33417D01*
X400133Y-33167D01*
X399800Y-32833D01*
G01X405650Y-31250D02*
X408317D01*
X408067Y-30667D01*
X407650Y-30333D01*
X407067Y-30167D01*
X406483Y-30250D01*
X405983Y-30500D01*
X405650Y-31083D01*
X405483Y-31583D01*
Y-32083D01*
X405650Y-32583D01*
X406067Y-33083D01*
X406567Y-33417D01*
X407150Y-33500D01*
X407733Y-33333D01*
X408317Y-32833D01*
G01X411333Y-33500D02*
Y-30167D01*
G01Y-30833D02*
X411750Y-30500D01*
X412167Y-30250D01*
X412750Y-30167D01*
X413167Y-30250D01*
X413667Y-30500D01*
G01X423283Y-35167D02*
X422450Y-34333D01*
X422033Y-33500D01*
Y-30167D01*
X422450Y-29333D01*
X423283Y-28500D01*
G01X427217Y-30167D02*
X428217Y-33500D01*
X429300Y-30167D01*
X430383Y-33500D01*
X431383Y-30167D01*
G01X433483Y-33500D02*
Y-28500D01*
G01Y-30917D02*
X433900Y-30500D01*
X434317Y-30250D01*
X434983Y-30167D01*
X435483Y-30250D01*
X436067Y-30583D01*
X436317Y-31083D01*
Y-33500D01*
G01X440500Y-30167D02*
Y-33500D01*
G01Y-28833D02*
X440333Y-28750D01*
Y-28583D01*
X440500Y-28500D01*
X440667Y-28583D01*
Y-28750D01*
X440500Y-28833D01*
G01X447433Y-30583D02*
X446850Y-30250D01*
X446350Y-30167D01*
X445683Y-30333D01*
X445183Y-30667D01*
X444850Y-31250D01*
X444767Y-31833D01*
X444850Y-32417D01*
X445183Y-32917D01*
X445683Y-33333D01*
X446350Y-33500D01*
X446933Y-33333D01*
X447433Y-33000D01*
G01X450283Y-33500D02*
Y-28500D01*
G01Y-30917D02*
X450700Y-30500D01*
X451117Y-30250D01*
X451783Y-30167D01*
X452283Y-30250D01*
X452867Y-30583D01*
X453117Y-31083D01*
Y-33500D01*
G01X462900Y-30167D02*
Y-33500D01*
G01Y-28833D02*
X462733Y-28750D01*
Y-28583D01*
X462900Y-28500D01*
X463067Y-28583D01*
Y-28750D01*
X462900Y-28833D01*
G01X467250Y-32917D02*
X467667Y-33250D01*
X468250Y-33500D01*
X468750D01*
X469250Y-33333D01*
X469583Y-33083D01*
X469750Y-32750D01*
X469667Y-32250D01*
X469333Y-32000D01*
X467833Y-31500D01*
X467500Y-30917D01*
X467667Y-30500D01*
X468000Y-30250D01*
X468500Y-30167D01*
X469000Y-30250D01*
X469500Y-30500D01*
G01X478200Y-33500D02*
Y-28500D01*
G01Y-31000D02*
X478617Y-30500D01*
X479117Y-30250D01*
X479617Y-30167D01*
X480367Y-30333D01*
X480867Y-30667D01*
X481200Y-31250D01*
Y-31917D01*
X481033Y-32583D01*
X480700Y-33083D01*
X480117Y-33417D01*
X479617Y-33500D01*
X479117Y-33417D01*
X478617Y-33167D01*
X478200Y-32750D01*
G01X484050Y-31250D02*
X486717D01*
X486467Y-30667D01*
X486050Y-30333D01*
X485467Y-30167D01*
X484883Y-30250D01*
X484383Y-30500D01*
X484050Y-31083D01*
X483883Y-31583D01*
Y-32083D01*
X484050Y-32583D01*
X484467Y-33083D01*
X484967Y-33417D01*
X485550Y-33500D01*
X486133Y-33333D01*
X486717Y-32833D01*
G01X490900Y-28500D02*
Y-33500D01*
G01X489733Y-30167D02*
X492067D01*
G01X496500Y-28500D02*
Y-33500D01*
G01X495333Y-30167D02*
X497667D01*
G01X500850Y-31250D02*
X503517D01*
X503267Y-30667D01*
X502850Y-30333D01*
X502267Y-30167D01*
X501683Y-30250D01*
X501183Y-30500D01*
X500850Y-31083D01*
X500683Y-31583D01*
Y-32083D01*
X500850Y-32583D01*
X501267Y-33083D01*
X501767Y-33417D01*
X502350Y-33500D01*
X502933Y-33333D01*
X503517Y-32833D01*
G01X506533Y-33500D02*
Y-30167D01*
G01Y-30833D02*
X506950Y-30500D01*
X507367Y-30250D01*
X507950Y-30167D01*
X508367Y-30250D01*
X508867Y-30500D01*
G01X513717Y-35167D02*
X514550Y-34333D01*
X514967Y-33500D01*
Y-30167D01*
X514550Y-29333D01*
X513717Y-28500D01*
G01X264000Y-39500D02*
X694500D01*
G01X262500Y-69500D02*
Y439000D01*
G01X272500Y0D02*
Y-5000D01*
G01X270583Y0D02*
X274417D01*
G01X276683Y-5000D02*
Y0D01*
G01Y-2417D02*
X277100Y-2000D01*
X277517Y-1750D01*
X278183Y-1667D01*
X278683Y-1750D01*
X279267Y-2083D01*
X279517Y-2583D01*
Y-5000D01*
G01X282450Y-2750D02*
X285117D01*
X284867Y-2167D01*
X284450Y-1833D01*
X283867Y-1667D01*
X283283Y-1750D01*
X282783Y-2000D01*
X282450Y-2583D01*
X282283Y-3083D01*
Y-3583D01*
X282450Y-4083D01*
X282867Y-4583D01*
X283367Y-4917D01*
X283950Y-5000D01*
X284533Y-4833D01*
X285117Y-4333D01*
G01X294900Y-5000D02*
Y0D01*
G01X302000Y-5000D02*
Y-1667D01*
G01Y-2250D02*
X301667Y-1917D01*
X301167Y-1750D01*
X300583Y-1667D01*
X300000Y-1833D01*
X299500Y-2167D01*
X299167Y-2667D01*
X299000Y-3333D01*
X299167Y-4000D01*
X299500Y-4500D01*
X300000Y-4833D01*
X300583Y-5000D01*
X301167Y-4917D01*
X301667Y-4667D01*
X302000Y-4333D01*
G01X304933Y-5000D02*
Y-1667D01*
G01Y-2333D02*
X305350Y-2000D01*
X305767Y-1750D01*
X306350Y-1667D01*
X306767Y-1750D01*
X307267Y-2000D01*
G01X310533Y-6250D02*
X311117Y-6583D01*
X311783Y-6667D01*
X312367Y-6583D01*
X312867Y-6167D01*
X313200Y-5583D01*
Y-1667D01*
G01Y-2333D02*
X312867Y-2000D01*
X312367Y-1750D01*
X311783Y-1667D01*
X311117Y-1833D01*
X310700Y-2167D01*
X310367Y-2750D01*
X310200Y-3333D01*
X310283Y-3833D01*
X310617Y-4417D01*
X311117Y-4833D01*
X311783Y-5000D01*
X312283Y-4917D01*
X312867Y-4583D01*
X313200Y-4250D01*
G01X316050Y-2750D02*
X318717D01*
X318467Y-2167D01*
X318050Y-1833D01*
X317467Y-1667D01*
X316883Y-1750D01*
X316383Y-2000D01*
X316050Y-2583D01*
X315883Y-3083D01*
Y-3583D01*
X316050Y-4083D01*
X316467Y-4583D01*
X316967Y-4917D01*
X317550Y-5000D01*
X318133Y-4833D01*
X318717Y-4333D01*
G01X321650Y-4417D02*
X322067Y-4750D01*
X322650Y-5000D01*
X323150D01*
X323650Y-4833D01*
X323983Y-4583D01*
X324150Y-4250D01*
X324067Y-3750D01*
X323733Y-3500D01*
X322233Y-3000D01*
X321900Y-2417D01*
X322067Y-2000D01*
X322400Y-1750D01*
X322900Y-1667D01*
X323400Y-1750D01*
X323900Y-2000D01*
G01X328500Y0D02*
Y-5000D01*
G01X327333Y-1667D02*
X329667D01*
G01X341200Y0D02*
Y-5000D01*
G01Y-4250D02*
X340867Y-4667D01*
X340367Y-4917D01*
X339783Y-5000D01*
X339117Y-4833D01*
X338617Y-4417D01*
X338283Y-3917D01*
X338200Y-3333D01*
X338283Y-2750D01*
X338617Y-2250D01*
X339117Y-1833D01*
X339783Y-1667D01*
X340367Y-1750D01*
X340783Y-1917D01*
X341200Y-2250D01*
G01X345300Y-1667D02*
Y-5000D01*
G01Y-333D02*
X345133Y-250D01*
Y-83D01*
X345300Y0D01*
X345467Y-83D01*
Y-250D01*
X345300Y-333D01*
G01X348400Y-5000D02*
Y-1667D01*
G01Y-2583D02*
X348650Y-2167D01*
X349067Y-1833D01*
X349650Y-1667D01*
X350233Y-1833D01*
X350650Y-2167D01*
X350900Y-2583D01*
Y-5000D01*
G01Y-2583D02*
X351150Y-2167D01*
X351567Y-1833D01*
X352150Y-1667D01*
X352733Y-1833D01*
X353150Y-2167D01*
X353400Y-2667D01*
Y-5000D01*
G01X355250Y-2750D02*
X357917D01*
X357667Y-2167D01*
X357250Y-1833D01*
X356667Y-1667D01*
X356083Y-1750D01*
X355583Y-2000D01*
X355250Y-2583D01*
X355083Y-3083D01*
Y-3583D01*
X355250Y-4083D01*
X355667Y-4583D01*
X356167Y-4917D01*
X356750Y-5000D01*
X357333Y-4833D01*
X357917Y-4333D01*
G01X360683Y-5000D02*
Y-1667D01*
G01Y-2500D02*
X361017Y-2083D01*
X361517Y-1750D01*
X362183Y-1667D01*
X362767Y-1750D01*
X363267Y-2083D01*
X363517Y-2667D01*
Y-5000D01*
G01X366450Y-4417D02*
X366867Y-4750D01*
X367450Y-5000D01*
X367950D01*
X368450Y-4833D01*
X368783Y-4583D01*
X368950Y-4250D01*
X368867Y-3750D01*
X368533Y-3500D01*
X367033Y-3000D01*
X366700Y-2417D01*
X366867Y-2000D01*
X367200Y-1750D01*
X367700Y-1667D01*
X368200Y-1750D01*
X368700Y-2000D01*
G01X373300Y-1667D02*
Y-5000D01*
G01Y-333D02*
X373133Y-250D01*
Y-83D01*
X373300Y0D01*
X373467Y-83D01*
Y-250D01*
X373300Y-333D01*
G01X378900Y-5000D02*
X378400Y-4917D01*
X377900Y-4583D01*
X377567Y-4000D01*
X377400Y-3333D01*
X377567Y-2667D01*
X377900Y-2083D01*
X378400Y-1750D01*
X378900Y-1667D01*
X379400Y-1750D01*
X379900Y-2083D01*
X380233Y-2667D01*
X380317Y-3333D01*
X380233Y-4000D01*
X379900Y-4583D01*
X379400Y-4917D01*
X378900Y-5000D01*
G01X383083D02*
Y-1667D01*
G01Y-2500D02*
X383417Y-2083D01*
X383917Y-1750D01*
X384583Y-1667D01*
X385167Y-1750D01*
X385667Y-2083D01*
X385917Y-2667D01*
Y-5000D01*
G01X395700D02*
X395200Y-4917D01*
X394700Y-4583D01*
X394367Y-4000D01*
X394200Y-3333D01*
X394367Y-2667D01*
X394700Y-2083D01*
X395200Y-1750D01*
X395700Y-1667D01*
X396200Y-1750D01*
X396700Y-2083D01*
X397033Y-2667D01*
X397117Y-3333D01*
X397033Y-4000D01*
X396700Y-4583D01*
X396200Y-4917D01*
X395700Y-5000D01*
G01X400800D02*
Y-750D01*
X400967Y-333D01*
X401300Y-83D01*
X401800Y0D01*
X402300Y-167D01*
X402550Y-583D01*
G01X401550Y-2000D02*
X399883D01*
G01X411000Y-6667D02*
Y-1667D01*
G01Y-2417D02*
X411417Y-2000D01*
X411833Y-1750D01*
X412500Y-1667D01*
X413083Y-1750D01*
X413667Y-2167D01*
X413917Y-2750D01*
X414000Y-3333D01*
X413917Y-3917D01*
X413667Y-4500D01*
X413167Y-4833D01*
X412500Y-5000D01*
X411917Y-4917D01*
X411333Y-4667D01*
X411000Y-4333D01*
G01X419600Y-5000D02*
Y-1667D01*
G01Y-2250D02*
X419267Y-1917D01*
X418767Y-1750D01*
X418183Y-1667D01*
X417600Y-1833D01*
X417100Y-2167D01*
X416767Y-2667D01*
X416600Y-3333D01*
X416767Y-4000D01*
X417100Y-4500D01*
X417600Y-4833D01*
X418183Y-5000D01*
X418767Y-4917D01*
X419267Y-4667D01*
X419600Y-4333D01*
G01X425200Y0D02*
Y-5000D01*
G01Y-4250D02*
X424867Y-4667D01*
X424367Y-4917D01*
X423783Y-5000D01*
X423117Y-4833D01*
X422617Y-4417D01*
X422283Y-3917D01*
X422200Y-3333D01*
X422283Y-2750D01*
X422617Y-2250D01*
X423117Y-1833D01*
X423783Y-1667D01*
X424367Y-1750D01*
X424783Y-1917D01*
X425200Y-2250D01*
G01X434900Y-5000D02*
X434400Y-4917D01*
X433900Y-4583D01*
X433567Y-4000D01*
X433400Y-3333D01*
X433567Y-2667D01*
X433900Y-2083D01*
X434400Y-1750D01*
X434900Y-1667D01*
X435400Y-1750D01*
X435900Y-2083D01*
X436233Y-2667D01*
X436317Y-3333D01*
X436233Y-4000D01*
X435900Y-4583D01*
X435400Y-4917D01*
X434900Y-5000D01*
G01X439333D02*
Y-1667D01*
G01Y-2333D02*
X439750Y-2000D01*
X440167Y-1750D01*
X440750Y-1667D01*
X441167Y-1750D01*
X441667Y-2000D01*
G01X453200Y0D02*
Y-5000D01*
G01Y-4250D02*
X452867Y-4667D01*
X452367Y-4917D01*
X451783Y-5000D01*
X451117Y-4833D01*
X450617Y-4417D01*
X450283Y-3917D01*
X450200Y-3333D01*
X450283Y-2750D01*
X450617Y-2250D01*
X451117Y-1833D01*
X451783Y-1667D01*
X452367Y-1750D01*
X452783Y-1917D01*
X453200Y-2250D01*
G01X457300Y-1667D02*
Y-5000D01*
G01Y-333D02*
X457133Y-250D01*
Y-83D01*
X457300Y0D01*
X457467Y-83D01*
Y-250D01*
X457300Y-333D01*
G01X464400Y-5000D02*
Y-1667D01*
G01Y-2250D02*
X464067Y-1917D01*
X463567Y-1750D01*
X462983Y-1667D01*
X462400Y-1833D01*
X461900Y-2167D01*
X461567Y-2667D01*
X461400Y-3333D01*
X461567Y-4000D01*
X461900Y-4500D01*
X462400Y-4833D01*
X462983Y-5000D01*
X463567Y-4917D01*
X464067Y-4667D01*
X464400Y-4333D01*
G01X466000Y-5000D02*
Y-1667D01*
G01Y-2583D02*
X466250Y-2167D01*
X466667Y-1833D01*
X467250Y-1667D01*
X467833Y-1833D01*
X468250Y-2167D01*
X468500Y-2583D01*
Y-5000D01*
G01Y-2583D02*
X468750Y-2167D01*
X469167Y-1833D01*
X469750Y-1667D01*
X470333Y-1833D01*
X470750Y-2167D01*
X471000Y-2667D01*
Y-5000D01*
G01X472850Y-2750D02*
X475517D01*
X475267Y-2167D01*
X474850Y-1833D01*
X474267Y-1667D01*
X473683Y-1750D01*
X473183Y-2000D01*
X472850Y-2583D01*
X472683Y-3083D01*
Y-3583D01*
X472850Y-4083D01*
X473267Y-4583D01*
X473767Y-4917D01*
X474350Y-5000D01*
X474933Y-4833D01*
X475517Y-4333D01*
G01X479700Y0D02*
Y-5000D01*
G01X478533Y-1667D02*
X480867D01*
G01X484050Y-2750D02*
X486717D01*
X486467Y-2167D01*
X486050Y-1833D01*
X485467Y-1667D01*
X484883Y-1750D01*
X484383Y-2000D01*
X484050Y-2583D01*
X483883Y-3083D01*
Y-3583D01*
X484050Y-4083D01*
X484467Y-4583D01*
X484967Y-4917D01*
X485550Y-5000D01*
X486133Y-4833D01*
X486717Y-4333D01*
G01X489733Y-5000D02*
Y-1667D01*
G01Y-2333D02*
X490150Y-2000D01*
X490567Y-1750D01*
X491150Y-1667D01*
X491567Y-1750D01*
X492067Y-2000D01*
G01X503767Y-5000D02*
X500433Y-3333D01*
X503767Y-1667D01*
G01X506617Y-4083D02*
X508783D01*
G01Y-2583D02*
X506617D01*
G01X518900Y-5000D02*
Y0D01*
X517900Y-1000D01*
G01Y-5000D02*
X519900D01*
G01X525500D02*
Y0D01*
X522417Y-3583D01*
X526583D01*
G01X533200Y-5000D02*
Y-1667D01*
G01Y-2583D02*
X533450Y-2167D01*
X533867Y-1833D01*
X534450Y-1667D01*
X535033Y-1833D01*
X535450Y-2167D01*
X535700Y-2583D01*
Y-5000D01*
G01Y-2583D02*
X535950Y-2167D01*
X536367Y-1833D01*
X536950Y-1667D01*
X537533Y-1833D01*
X537950Y-2167D01*
X538200Y-2667D01*
Y-5000D01*
G01X541300Y-1667D02*
Y-5000D01*
G01Y-333D02*
X541133Y-250D01*
Y-83D01*
X541300Y0D01*
X541467Y-83D01*
Y-250D01*
X541300Y-333D01*
G01X546900Y-5000D02*
Y0D01*
G01X271250Y-19417D02*
X271667Y-19750D01*
X272250Y-20000D01*
X272750D01*
X273250Y-19833D01*
X273583Y-19583D01*
X273750Y-19250D01*
X273667Y-18750D01*
X273333Y-18500D01*
X271833Y-18000D01*
X271500Y-17417D01*
X271667Y-17000D01*
X272000Y-16750D01*
X272500Y-16667D01*
X273000Y-16750D01*
X273500Y-17000D01*
G01X278100Y-20000D02*
X277600Y-19917D01*
X277100Y-19583D01*
X276767Y-19000D01*
X276600Y-18333D01*
X276767Y-17667D01*
X277100Y-17083D01*
X277600Y-16750D01*
X278100Y-16667D01*
X278600Y-16750D01*
X279100Y-17083D01*
X279433Y-17667D01*
X279517Y-18333D01*
X279433Y-19000D01*
X279100Y-19583D01*
X278600Y-19917D01*
X278100Y-20000D01*
G01X283700D02*
Y-15000D01*
G01X290800D02*
Y-20000D01*
G01Y-19250D02*
X290467Y-19667D01*
X289967Y-19917D01*
X289383Y-20000D01*
X288717Y-19833D01*
X288217Y-19417D01*
X287883Y-18917D01*
X287800Y-18333D01*
X287883Y-17750D01*
X288217Y-17250D01*
X288717Y-16833D01*
X289383Y-16667D01*
X289967Y-16750D01*
X290383Y-16917D01*
X290800Y-17250D01*
G01X293650Y-17750D02*
X296317D01*
X296067Y-17167D01*
X295650Y-16833D01*
X295067Y-16667D01*
X294483Y-16750D01*
X293983Y-17000D01*
X293650Y-17583D01*
X293483Y-18083D01*
Y-18583D01*
X293650Y-19083D01*
X294067Y-19583D01*
X294567Y-19917D01*
X295150Y-20000D01*
X295733Y-19833D01*
X296317Y-19333D01*
G01X299333Y-20000D02*
Y-16667D01*
G01Y-17333D02*
X299750Y-17000D01*
X300167Y-16750D01*
X300750Y-16667D01*
X301167Y-16750D01*
X301667Y-17000D01*
G01X309200Y-20000D02*
Y-16667D01*
G01Y-17583D02*
X309450Y-17167D01*
X309867Y-16833D01*
X310450Y-16667D01*
X311033Y-16833D01*
X311450Y-17167D01*
X311700Y-17583D01*
Y-20000D01*
G01Y-17583D02*
X311950Y-17167D01*
X312367Y-16833D01*
X312950Y-16667D01*
X313533Y-16833D01*
X313950Y-17167D01*
X314200Y-17667D01*
Y-20000D01*
G01X318800D02*
Y-16667D01*
G01Y-17250D02*
X318467Y-16917D01*
X317967Y-16750D01*
X317383Y-16667D01*
X316800Y-16833D01*
X316300Y-17167D01*
X315967Y-17667D01*
X315800Y-18333D01*
X315967Y-19000D01*
X316300Y-19500D01*
X316800Y-19833D01*
X317383Y-20000D01*
X317967Y-19917D01*
X318467Y-19667D01*
X318800Y-19333D01*
G01X321650Y-19417D02*
X322067Y-19750D01*
X322650Y-20000D01*
X323150D01*
X323650Y-19833D01*
X323983Y-19583D01*
X324150Y-19250D01*
X324067Y-18750D01*
X323733Y-18500D01*
X322233Y-18000D01*
X321900Y-17417D01*
X322067Y-17000D01*
X322400Y-16750D01*
X322900Y-16667D01*
X323400Y-16750D01*
X323900Y-17000D01*
G01X327083Y-20000D02*
Y-15000D01*
G01X329750Y-16667D02*
X327083Y-18583D01*
G01X328167Y-17833D02*
X329917Y-20000D01*
G01X339700Y-15000D02*
Y-20000D01*
G01X338533Y-16667D02*
X340867D01*
G01X343883Y-20000D02*
Y-15000D01*
G01Y-17417D02*
X344300Y-17000D01*
X344717Y-16750D01*
X345383Y-16667D01*
X345883Y-16750D01*
X346467Y-17083D01*
X346717Y-17583D01*
Y-20000D01*
G01X350900Y-16667D02*
Y-20000D01*
G01Y-15333D02*
X350733Y-15250D01*
Y-15083D01*
X350900Y-15000D01*
X351067Y-15083D01*
Y-15250D01*
X350900Y-15333D01*
G01X357833Y-17083D02*
X357250Y-16750D01*
X356750Y-16667D01*
X356083Y-16833D01*
X355583Y-17167D01*
X355250Y-17750D01*
X355167Y-18333D01*
X355250Y-18917D01*
X355583Y-19417D01*
X356083Y-19833D01*
X356750Y-20000D01*
X357333Y-19833D01*
X357833Y-19500D01*
G01X360683Y-20000D02*
Y-15000D01*
G01X363350Y-16667D02*
X360683Y-18583D01*
G01X361767Y-17833D02*
X363517Y-20000D01*
G01X366283D02*
Y-16667D01*
G01Y-17500D02*
X366617Y-17083D01*
X367117Y-16750D01*
X367783Y-16667D01*
X368367Y-16750D01*
X368867Y-17083D01*
X369117Y-17667D01*
Y-20000D01*
G01X372050Y-17750D02*
X374717D01*
X374467Y-17167D01*
X374050Y-16833D01*
X373467Y-16667D01*
X372883Y-16750D01*
X372383Y-17000D01*
X372050Y-17583D01*
X371883Y-18083D01*
Y-18583D01*
X372050Y-19083D01*
X372467Y-19583D01*
X372967Y-19917D01*
X373550Y-20000D01*
X374133Y-19833D01*
X374717Y-19333D01*
G01X377650Y-19417D02*
X378067Y-19750D01*
X378650Y-20000D01*
X379150D01*
X379650Y-19833D01*
X379983Y-19583D01*
X380150Y-19250D01*
X380067Y-18750D01*
X379733Y-18500D01*
X378233Y-18000D01*
X377900Y-17417D01*
X378067Y-17000D01*
X378400Y-16750D01*
X378900Y-16667D01*
X379400Y-16750D01*
X379900Y-17000D01*
G01X383250Y-19417D02*
X383667Y-19750D01*
X384250Y-20000D01*
X384750D01*
X385250Y-19833D01*
X385583Y-19583D01*
X385750Y-19250D01*
X385667Y-18750D01*
X385333Y-18500D01*
X383833Y-18000D01*
X383500Y-17417D01*
X383667Y-17000D01*
X384000Y-16750D01*
X384500Y-16667D01*
X385000Y-16750D01*
X385500Y-17000D01*
G01X272500Y52000D02*
Y47000D01*
G01X270583Y52000D02*
X274417D01*
G01X276683Y47000D02*
Y52000D01*
G01Y49583D02*
X277100Y50000D01*
X277517Y50250D01*
X278183Y50333D01*
X278683Y50250D01*
X279267Y49917D01*
X279517Y49417D01*
Y47000D01*
G01X282450Y49250D02*
X285117D01*
X284867Y49833D01*
X284450Y50167D01*
X283867Y50333D01*
X283283Y50250D01*
X282783Y50000D01*
X282450Y49417D01*
X282283Y48917D01*
Y48417D01*
X282450Y47917D01*
X282867Y47417D01*
X283367Y47083D01*
X283950Y47000D01*
X284533Y47167D01*
X285117Y47667D01*
G01X294900Y47000D02*
Y52000D01*
G01X302000Y47000D02*
Y50333D01*
G01Y49750D02*
X301667Y50083D01*
X301167Y50250D01*
X300583Y50333D01*
X300000Y50167D01*
X299500Y49833D01*
X299167Y49333D01*
X299000Y48667D01*
X299167Y48000D01*
X299500Y47500D01*
X300000Y47167D01*
X300583Y47000D01*
X301167Y47083D01*
X301667Y47333D01*
X302000Y47667D01*
G01X304933Y47000D02*
Y50333D01*
G01Y49667D02*
X305350Y50000D01*
X305767Y50250D01*
X306350Y50333D01*
X306767Y50250D01*
X307267Y50000D01*
G01X310533Y45750D02*
X311117Y45417D01*
X311783Y45333D01*
X312367Y45417D01*
X312867Y45833D01*
X313200Y46417D01*
Y50333D01*
G01Y49667D02*
X312867Y50000D01*
X312367Y50250D01*
X311783Y50333D01*
X311117Y50167D01*
X310700Y49833D01*
X310367Y49250D01*
X310200Y48667D01*
X310283Y48167D01*
X310617Y47583D01*
X311117Y47167D01*
X311783Y47000D01*
X312283Y47083D01*
X312867Y47417D01*
X313200Y47750D01*
G01X316050Y49250D02*
X318717D01*
X318467Y49833D01*
X318050Y50167D01*
X317467Y50333D01*
X316883Y50250D01*
X316383Y50000D01*
X316050Y49417D01*
X315883Y48917D01*
Y48417D01*
X316050Y47917D01*
X316467Y47417D01*
X316967Y47083D01*
X317550Y47000D01*
X318133Y47167D01*
X318717Y47667D01*
G01X321650Y47583D02*
X322067Y47250D01*
X322650Y47000D01*
X323150D01*
X323650Y47167D01*
X323983Y47417D01*
X324150Y47750D01*
X324067Y48250D01*
X323733Y48500D01*
X322233Y49000D01*
X321900Y49583D01*
X322067Y50000D01*
X322400Y50250D01*
X322900Y50333D01*
X323400Y50250D01*
X323900Y50000D01*
G01X328500Y52000D02*
Y47000D01*
G01X327333Y50333D02*
X329667D01*
G01X341200Y52000D02*
Y47000D01*
G01Y47750D02*
X340867Y47333D01*
X340367Y47083D01*
X339783Y47000D01*
X339117Y47167D01*
X338617Y47583D01*
X338283Y48083D01*
X338200Y48667D01*
X338283Y49250D01*
X338617Y49750D01*
X339117Y50167D01*
X339783Y50333D01*
X340367Y50250D01*
X340783Y50083D01*
X341200Y49750D01*
G01X345300Y50333D02*
Y47000D01*
G01Y51667D02*
X345133Y51750D01*
Y51917D01*
X345300Y52000D01*
X345467Y51917D01*
Y51750D01*
X345300Y51667D01*
G01X348400Y47000D02*
Y50333D01*
G01Y49417D02*
X348650Y49833D01*
X349067Y50167D01*
X349650Y50333D01*
X350233Y50167D01*
X350650Y49833D01*
X350900Y49417D01*
Y47000D01*
G01Y49417D02*
X351150Y49833D01*
X351567Y50167D01*
X352150Y50333D01*
X352733Y50167D01*
X353150Y49833D01*
X353400Y49333D01*
Y47000D01*
G01X355250Y49250D02*
X357917D01*
X357667Y49833D01*
X357250Y50167D01*
X356667Y50333D01*
X356083Y50250D01*
X355583Y50000D01*
X355250Y49417D01*
X355083Y48917D01*
Y48417D01*
X355250Y47917D01*
X355667Y47417D01*
X356167Y47083D01*
X356750Y47000D01*
X357333Y47167D01*
X357917Y47667D01*
G01X360683Y47000D02*
Y50333D01*
G01Y49500D02*
X361017Y49917D01*
X361517Y50250D01*
X362183Y50333D01*
X362767Y50250D01*
X363267Y49917D01*
X363517Y49333D01*
Y47000D01*
G01X366450Y47583D02*
X366867Y47250D01*
X367450Y47000D01*
X367950D01*
X368450Y47167D01*
X368783Y47417D01*
X368950Y47750D01*
X368867Y48250D01*
X368533Y48500D01*
X367033Y49000D01*
X366700Y49583D01*
X366867Y50000D01*
X367200Y50250D01*
X367700Y50333D01*
X368200Y50250D01*
X368700Y50000D01*
G01X373300Y50333D02*
Y47000D01*
G01Y51667D02*
X373133Y51750D01*
Y51917D01*
X373300Y52000D01*
X373467Y51917D01*
Y51750D01*
X373300Y51667D01*
G01X378900Y47000D02*
X378400Y47083D01*
X377900Y47417D01*
X377567Y48000D01*
X377400Y48667D01*
X377567Y49333D01*
X377900Y49917D01*
X378400Y50250D01*
X378900Y50333D01*
X379400Y50250D01*
X379900Y49917D01*
X380233Y49333D01*
X380317Y48667D01*
X380233Y48000D01*
X379900Y47417D01*
X379400Y47083D01*
X378900Y47000D01*
G01X383083D02*
Y50333D01*
G01Y49500D02*
X383417Y49917D01*
X383917Y50250D01*
X384583Y50333D01*
X385167Y50250D01*
X385667Y49917D01*
X385917Y49333D01*
Y47000D01*
G01X395700D02*
X395200Y47083D01*
X394700Y47417D01*
X394367Y48000D01*
X394200Y48667D01*
X394367Y49333D01*
X394700Y49917D01*
X395200Y50250D01*
X395700Y50333D01*
X396200Y50250D01*
X396700Y49917D01*
X397033Y49333D01*
X397117Y48667D01*
X397033Y48000D01*
X396700Y47417D01*
X396200Y47083D01*
X395700Y47000D01*
G01X400800D02*
Y51250D01*
X400967Y51667D01*
X401300Y51917D01*
X401800Y52000D01*
X402300Y51833D01*
X402550Y51417D01*
G01X401550Y50000D02*
X399883D01*
G01X411000Y45333D02*
Y50333D01*
G01Y49583D02*
X411417Y50000D01*
X411833Y50250D01*
X412500Y50333D01*
X413083Y50250D01*
X413667Y49833D01*
X413917Y49250D01*
X414000Y48667D01*
X413917Y48083D01*
X413667Y47500D01*
X413167Y47167D01*
X412500Y47000D01*
X411917Y47083D01*
X411333Y47333D01*
X411000Y47667D01*
G01X419600Y47000D02*
Y50333D01*
G01Y49750D02*
X419267Y50083D01*
X418767Y50250D01*
X418183Y50333D01*
X417600Y50167D01*
X417100Y49833D01*
X416767Y49333D01*
X416600Y48667D01*
X416767Y48000D01*
X417100Y47500D01*
X417600Y47167D01*
X418183Y47000D01*
X418767Y47083D01*
X419267Y47333D01*
X419600Y47667D01*
G01X425200Y52000D02*
Y47000D01*
G01Y47750D02*
X424867Y47333D01*
X424367Y47083D01*
X423783Y47000D01*
X423117Y47167D01*
X422617Y47583D01*
X422283Y48083D01*
X422200Y48667D01*
X422283Y49250D01*
X422617Y49750D01*
X423117Y50167D01*
X423783Y50333D01*
X424367Y50250D01*
X424783Y50083D01*
X425200Y49750D01*
G01X434900Y47000D02*
X434400Y47083D01*
X433900Y47417D01*
X433567Y48000D01*
X433400Y48667D01*
X433567Y49333D01*
X433900Y49917D01*
X434400Y50250D01*
X434900Y50333D01*
X435400Y50250D01*
X435900Y49917D01*
X436233Y49333D01*
X436317Y48667D01*
X436233Y48000D01*
X435900Y47417D01*
X435400Y47083D01*
X434900Y47000D01*
G01X439333D02*
Y50333D01*
G01Y49667D02*
X439750Y50000D01*
X440167Y50250D01*
X440750Y50333D01*
X441167Y50250D01*
X441667Y50000D01*
G01X453200Y52000D02*
Y47000D01*
G01Y47750D02*
X452867Y47333D01*
X452367Y47083D01*
X451783Y47000D01*
X451117Y47167D01*
X450617Y47583D01*
X450283Y48083D01*
X450200Y48667D01*
X450283Y49250D01*
X450617Y49750D01*
X451117Y50167D01*
X451783Y50333D01*
X452367Y50250D01*
X452783Y50083D01*
X453200Y49750D01*
G01X457300Y50333D02*
Y47000D01*
G01Y51667D02*
X457133Y51750D01*
Y51917D01*
X457300Y52000D01*
X457467Y51917D01*
Y51750D01*
X457300Y51667D01*
G01X464400Y47000D02*
Y50333D01*
G01Y49750D02*
X464067Y50083D01*
X463567Y50250D01*
X462983Y50333D01*
X462400Y50167D01*
X461900Y49833D01*
X461567Y49333D01*
X461400Y48667D01*
X461567Y48000D01*
X461900Y47500D01*
X462400Y47167D01*
X462983Y47000D01*
X463567Y47083D01*
X464067Y47333D01*
X464400Y47667D01*
G01X466000Y47000D02*
Y50333D01*
G01Y49417D02*
X466250Y49833D01*
X466667Y50167D01*
X467250Y50333D01*
X467833Y50167D01*
X468250Y49833D01*
X468500Y49417D01*
Y47000D01*
G01Y49417D02*
X468750Y49833D01*
X469167Y50167D01*
X469750Y50333D01*
X470333Y50167D01*
X470750Y49833D01*
X471000Y49333D01*
Y47000D01*
G01X472850Y49250D02*
X475517D01*
X475267Y49833D01*
X474850Y50167D01*
X474267Y50333D01*
X473683Y50250D01*
X473183Y50000D01*
X472850Y49417D01*
X472683Y48917D01*
Y48417D01*
X472850Y47917D01*
X473267Y47417D01*
X473767Y47083D01*
X474350Y47000D01*
X474933Y47167D01*
X475517Y47667D01*
G01X479700Y52000D02*
Y47000D01*
G01X478533Y50333D02*
X480867D01*
G01X484050Y49250D02*
X486717D01*
X486467Y49833D01*
X486050Y50167D01*
X485467Y50333D01*
X484883Y50250D01*
X484383Y50000D01*
X484050Y49417D01*
X483883Y48917D01*
Y48417D01*
X484050Y47917D01*
X484467Y47417D01*
X484967Y47083D01*
X485550Y47000D01*
X486133Y47167D01*
X486717Y47667D01*
G01X489733Y47000D02*
Y50333D01*
G01Y49667D02*
X490150Y50000D01*
X490567Y50250D01*
X491150Y50333D01*
X491567Y50250D01*
X492067Y50000D01*
G01X500433Y47000D02*
X503767Y48667D01*
X500433Y50333D01*
G01X513300Y47000D02*
Y52000D01*
X512300Y51000D01*
G01Y47000D02*
X514300D01*
G01X519900D02*
Y52000D01*
X516817Y48417D01*
X520983D01*
G01X527600Y47000D02*
Y50333D01*
G01Y49417D02*
X527850Y49833D01*
X528267Y50167D01*
X528850Y50333D01*
X529433Y50167D01*
X529850Y49833D01*
X530100Y49417D01*
Y47000D01*
G01Y49417D02*
X530350Y49833D01*
X530767Y50167D01*
X531350Y50333D01*
X531933Y50167D01*
X532350Y49833D01*
X532600Y49333D01*
Y47000D01*
G01X535700Y50333D02*
Y47000D01*
G01Y51667D02*
X535533Y51750D01*
Y51917D01*
X535700Y52000D01*
X535867Y51917D01*
Y51750D01*
X535700Y51667D01*
G01X541300Y47000D02*
Y52000D01*
G01X273580Y32670D02*
Y27670D01*
G01X271663Y32670D02*
X275497D01*
G01X277763Y27670D02*
Y32670D01*
G01Y30253D02*
X278180Y30670D01*
X278597Y30920D01*
X279263Y31003D01*
X279763Y30920D01*
X280347Y30587D01*
X280597Y30087D01*
Y27670D01*
G01X283530Y29920D02*
X286197D01*
X285947Y30503D01*
X285530Y30837D01*
X284947Y31003D01*
X284363Y30920D01*
X283863Y30670D01*
X283530Y30087D01*
X283363Y29587D01*
Y29087D01*
X283530Y28587D01*
X283947Y28087D01*
X284447Y27753D01*
X285030Y27670D01*
X285613Y27837D01*
X286197Y28337D01*
G01X295980Y27670D02*
Y32670D01*
G01X303080Y27670D02*
Y31003D01*
G01Y30420D02*
X302747Y30753D01*
X302247Y30920D01*
X301663Y31003D01*
X301080Y30837D01*
X300580Y30503D01*
X300247Y30003D01*
X300080Y29337D01*
X300247Y28670D01*
X300580Y28170D01*
X301080Y27837D01*
X301663Y27670D01*
X302247Y27753D01*
X302747Y28003D01*
X303080Y28337D01*
G01X306013Y27670D02*
Y31003D01*
G01Y30337D02*
X306430Y30670D01*
X306847Y30920D01*
X307430Y31003D01*
X307847Y30920D01*
X308347Y30670D01*
G01X311613Y26420D02*
X312197Y26087D01*
X312863Y26003D01*
X313447Y26087D01*
X313947Y26503D01*
X314280Y27087D01*
Y31003D01*
G01Y30337D02*
X313947Y30670D01*
X313447Y30920D01*
X312863Y31003D01*
X312197Y30837D01*
X311780Y30503D01*
X311447Y29920D01*
X311280Y29337D01*
X311363Y28837D01*
X311697Y28253D01*
X312197Y27837D01*
X312863Y27670D01*
X313363Y27753D01*
X313947Y28087D01*
X314280Y28420D01*
G01X317130Y29920D02*
X319797D01*
X319547Y30503D01*
X319130Y30837D01*
X318547Y31003D01*
X317963Y30920D01*
X317463Y30670D01*
X317130Y30087D01*
X316963Y29587D01*
Y29087D01*
X317130Y28587D01*
X317547Y28087D01*
X318047Y27753D01*
X318630Y27670D01*
X319213Y27837D01*
X319797Y28337D01*
G01X322730Y28253D02*
X323147Y27920D01*
X323730Y27670D01*
X324230D01*
X324730Y27837D01*
X325063Y28087D01*
X325230Y28420D01*
X325147Y28920D01*
X324813Y29170D01*
X323313Y29670D01*
X322980Y30253D01*
X323147Y30670D01*
X323480Y30920D01*
X323980Y31003D01*
X324480Y30920D01*
X324980Y30670D01*
G01X329580Y32670D02*
Y27670D01*
G01X328413Y31003D02*
X330747D01*
G01X342280Y32670D02*
Y27670D01*
G01Y28420D02*
X341947Y28003D01*
X341447Y27753D01*
X340863Y27670D01*
X340197Y27837D01*
X339697Y28253D01*
X339363Y28753D01*
X339280Y29337D01*
X339363Y29920D01*
X339697Y30420D01*
X340197Y30837D01*
X340863Y31003D01*
X341447Y30920D01*
X341863Y30753D01*
X342280Y30420D01*
G01X346380Y31003D02*
Y27670D01*
G01Y32337D02*
X346213Y32420D01*
Y32587D01*
X346380Y32670D01*
X346547Y32587D01*
Y32420D01*
X346380Y32337D01*
G01X349480Y27670D02*
Y31003D01*
G01Y30087D02*
X349730Y30503D01*
X350147Y30837D01*
X350730Y31003D01*
X351313Y30837D01*
X351730Y30503D01*
X351980Y30087D01*
Y27670D01*
G01Y30087D02*
X352230Y30503D01*
X352647Y30837D01*
X353230Y31003D01*
X353813Y30837D01*
X354230Y30503D01*
X354480Y30003D01*
Y27670D01*
G01X356330Y29920D02*
X358997D01*
X358747Y30503D01*
X358330Y30837D01*
X357747Y31003D01*
X357163Y30920D01*
X356663Y30670D01*
X356330Y30087D01*
X356163Y29587D01*
Y29087D01*
X356330Y28587D01*
X356747Y28087D01*
X357247Y27753D01*
X357830Y27670D01*
X358413Y27837D01*
X358997Y28337D01*
G01X361763Y27670D02*
Y31003D01*
G01Y30170D02*
X362097Y30587D01*
X362597Y30920D01*
X363263Y31003D01*
X363847Y30920D01*
X364347Y30587D01*
X364597Y30003D01*
Y27670D01*
G01X367530Y28253D02*
X367947Y27920D01*
X368530Y27670D01*
X369030D01*
X369530Y27837D01*
X369863Y28087D01*
X370030Y28420D01*
X369947Y28920D01*
X369613Y29170D01*
X368113Y29670D01*
X367780Y30253D01*
X367947Y30670D01*
X368280Y30920D01*
X368780Y31003D01*
X369280Y30920D01*
X369780Y30670D01*
G01X374380Y31003D02*
Y27670D01*
G01Y32337D02*
X374213Y32420D01*
Y32587D01*
X374380Y32670D01*
X374547Y32587D01*
Y32420D01*
X374380Y32337D01*
G01X379980Y27670D02*
X379480Y27753D01*
X378980Y28087D01*
X378647Y28670D01*
X378480Y29337D01*
X378647Y30003D01*
X378980Y30587D01*
X379480Y30920D01*
X379980Y31003D01*
X380480Y30920D01*
X380980Y30587D01*
X381313Y30003D01*
X381397Y29337D01*
X381313Y28670D01*
X380980Y28087D01*
X380480Y27753D01*
X379980Y27670D01*
G01X384163D02*
Y31003D01*
G01Y30170D02*
X384497Y30587D01*
X384997Y30920D01*
X385663Y31003D01*
X386247Y30920D01*
X386747Y30587D01*
X386997Y30003D01*
Y27670D01*
G01X396780D02*
X396280Y27753D01*
X395780Y28087D01*
X395447Y28670D01*
X395280Y29337D01*
X395447Y30003D01*
X395780Y30587D01*
X396280Y30920D01*
X396780Y31003D01*
X397280Y30920D01*
X397780Y30587D01*
X398113Y30003D01*
X398197Y29337D01*
X398113Y28670D01*
X397780Y28087D01*
X397280Y27753D01*
X396780Y27670D01*
G01X401880D02*
Y31920D01*
X402047Y32337D01*
X402380Y32587D01*
X402880Y32670D01*
X403380Y32503D01*
X403630Y32087D01*
G01X402630Y30670D02*
X400963D01*
G01X412080Y26003D02*
Y31003D01*
G01Y30253D02*
X412497Y30670D01*
X412913Y30920D01*
X413580Y31003D01*
X414163Y30920D01*
X414747Y30503D01*
X414997Y29920D01*
X415080Y29337D01*
X414997Y28753D01*
X414747Y28170D01*
X414247Y27837D01*
X413580Y27670D01*
X412997Y27753D01*
X412413Y28003D01*
X412080Y28337D01*
G01X420680Y27670D02*
Y31003D01*
G01Y30420D02*
X420347Y30753D01*
X419847Y30920D01*
X419263Y31003D01*
X418680Y30837D01*
X418180Y30503D01*
X417847Y30003D01*
X417680Y29337D01*
X417847Y28670D01*
X418180Y28170D01*
X418680Y27837D01*
X419263Y27670D01*
X419847Y27753D01*
X420347Y28003D01*
X420680Y28337D01*
G01X426280Y32670D02*
Y27670D01*
G01Y28420D02*
X425947Y28003D01*
X425447Y27753D01*
X424863Y27670D01*
X424197Y27837D01*
X423697Y28253D01*
X423363Y28753D01*
X423280Y29337D01*
X423363Y29920D01*
X423697Y30420D01*
X424197Y30837D01*
X424863Y31003D01*
X425447Y30920D01*
X425863Y30753D01*
X426280Y30420D01*
G01X435980Y27670D02*
X435480Y27753D01*
X434980Y28087D01*
X434647Y28670D01*
X434480Y29337D01*
X434647Y30003D01*
X434980Y30587D01*
X435480Y30920D01*
X435980Y31003D01*
X436480Y30920D01*
X436980Y30587D01*
X437313Y30003D01*
X437397Y29337D01*
X437313Y28670D01*
X436980Y28087D01*
X436480Y27753D01*
X435980Y27670D01*
G01X440413D02*
Y31003D01*
G01Y30337D02*
X440830Y30670D01*
X441247Y30920D01*
X441830Y31003D01*
X442247Y30920D01*
X442747Y30670D01*
G01X454280Y32670D02*
Y27670D01*
G01Y28420D02*
X453947Y28003D01*
X453447Y27753D01*
X452863Y27670D01*
X452197Y27837D01*
X451697Y28253D01*
X451363Y28753D01*
X451280Y29337D01*
X451363Y29920D01*
X451697Y30420D01*
X452197Y30837D01*
X452863Y31003D01*
X453447Y30920D01*
X453863Y30753D01*
X454280Y30420D01*
G01X458380Y31003D02*
Y27670D01*
G01Y32337D02*
X458213Y32420D01*
Y32587D01*
X458380Y32670D01*
X458547Y32587D01*
Y32420D01*
X458380Y32337D01*
G01X465480Y27670D02*
Y31003D01*
G01Y30420D02*
X465147Y30753D01*
X464647Y30920D01*
X464063Y31003D01*
X463480Y30837D01*
X462980Y30503D01*
X462647Y30003D01*
X462480Y29337D01*
X462647Y28670D01*
X462980Y28170D01*
X463480Y27837D01*
X464063Y27670D01*
X464647Y27753D01*
X465147Y28003D01*
X465480Y28337D01*
G01X467080Y27670D02*
Y31003D01*
G01Y30087D02*
X467330Y30503D01*
X467747Y30837D01*
X468330Y31003D01*
X468913Y30837D01*
X469330Y30503D01*
X469580Y30087D01*
Y27670D01*
G01Y30087D02*
X469830Y30503D01*
X470247Y30837D01*
X470830Y31003D01*
X471413Y30837D01*
X471830Y30503D01*
X472080Y30003D01*
Y27670D01*
G01X473930Y29920D02*
X476597D01*
X476347Y30503D01*
X475930Y30837D01*
X475347Y31003D01*
X474763Y30920D01*
X474263Y30670D01*
X473930Y30087D01*
X473763Y29587D01*
Y29087D01*
X473930Y28587D01*
X474347Y28087D01*
X474847Y27753D01*
X475430Y27670D01*
X476013Y27837D01*
X476597Y28337D01*
G01X480780Y32670D02*
Y27670D01*
G01X479613Y31003D02*
X481947D01*
G01X485130Y29920D02*
X487797D01*
X487547Y30503D01*
X487130Y30837D01*
X486547Y31003D01*
X485963Y30920D01*
X485463Y30670D01*
X485130Y30087D01*
X484963Y29587D01*
Y29087D01*
X485130Y28587D01*
X485547Y28087D01*
X486047Y27753D01*
X486630Y27670D01*
X487213Y27837D01*
X487797Y28337D01*
G01X490813Y27670D02*
Y31003D01*
G01Y30337D02*
X491230Y30670D01*
X491647Y30920D01*
X492230Y31003D01*
X492647Y30920D01*
X493147Y30670D01*
G01X504847Y27670D02*
X501513Y29337D01*
X504847Y31003D01*
G01X507697Y28587D02*
X509863D01*
G01Y30087D02*
X507697D01*
G01X519980Y27670D02*
Y32670D01*
X518980Y31670D01*
G01Y27670D02*
X520980D01*
G01X526580D02*
Y32670D01*
X523497Y29087D01*
X527663D01*
G01X534280Y27670D02*
Y31003D01*
G01Y30087D02*
X534530Y30503D01*
X534947Y30837D01*
X535530Y31003D01*
X536113Y30837D01*
X536530Y30503D01*
X536780Y30087D01*
Y27670D01*
G01Y30087D02*
X537030Y30503D01*
X537447Y30837D01*
X538030Y31003D01*
X538613Y30837D01*
X539030Y30503D01*
X539280Y30003D01*
Y27670D01*
G01X542380Y31003D02*
Y27670D01*
G01Y32337D02*
X542213Y32420D01*
Y32587D01*
X542380Y32670D01*
X542547Y32587D01*
Y32420D01*
X542380Y32337D01*
G01X547980Y27670D02*
Y32670D01*
G01X272500Y15000D02*
Y10000D01*
G01X270583Y15000D02*
X274417D01*
G01X276683Y10000D02*
Y15000D01*
G01Y12583D02*
X277100Y13000D01*
X277517Y13250D01*
X278183Y13333D01*
X278683Y13250D01*
X279267Y12917D01*
X279517Y12417D01*
Y10000D01*
G01X282450Y12250D02*
X285117D01*
X284867Y12833D01*
X284450Y13167D01*
X283867Y13333D01*
X283283Y13250D01*
X282783Y13000D01*
X282450Y12417D01*
X282283Y11917D01*
Y11417D01*
X282450Y10917D01*
X282867Y10417D01*
X283367Y10083D01*
X283950Y10000D01*
X284533Y10167D01*
X285117Y10667D01*
G01X294900Y10000D02*
Y15000D01*
G01X302000Y10000D02*
Y13333D01*
G01Y12750D02*
X301667Y13083D01*
X301167Y13250D01*
X300583Y13333D01*
X300000Y13167D01*
X299500Y12833D01*
X299167Y12333D01*
X299000Y11667D01*
X299167Y11000D01*
X299500Y10500D01*
X300000Y10167D01*
X300583Y10000D01*
X301167Y10083D01*
X301667Y10333D01*
X302000Y10667D01*
G01X304933Y10000D02*
Y13333D01*
G01Y12667D02*
X305350Y13000D01*
X305767Y13250D01*
X306350Y13333D01*
X306767Y13250D01*
X307267Y13000D01*
G01X310533Y8750D02*
X311117Y8417D01*
X311783Y8333D01*
X312367Y8417D01*
X312867Y8833D01*
X313200Y9417D01*
Y13333D01*
G01Y12667D02*
X312867Y13000D01*
X312367Y13250D01*
X311783Y13333D01*
X311117Y13167D01*
X310700Y12833D01*
X310367Y12250D01*
X310200Y11667D01*
X310283Y11167D01*
X310617Y10583D01*
X311117Y10167D01*
X311783Y10000D01*
X312283Y10083D01*
X312867Y10417D01*
X313200Y10750D01*
G01X316050Y12250D02*
X318717D01*
X318467Y12833D01*
X318050Y13167D01*
X317467Y13333D01*
X316883Y13250D01*
X316383Y13000D01*
X316050Y12417D01*
X315883Y11917D01*
Y11417D01*
X316050Y10917D01*
X316467Y10417D01*
X316967Y10083D01*
X317550Y10000D01*
X318133Y10167D01*
X318717Y10667D01*
G01X321650Y10583D02*
X322067Y10250D01*
X322650Y10000D01*
X323150D01*
X323650Y10167D01*
X323983Y10417D01*
X324150Y10750D01*
X324067Y11250D01*
X323733Y11500D01*
X322233Y12000D01*
X321900Y12583D01*
X322067Y13000D01*
X322400Y13250D01*
X322900Y13333D01*
X323400Y13250D01*
X323900Y13000D01*
G01X328500Y15000D02*
Y10000D01*
G01X327333Y13333D02*
X329667D01*
G01X341200Y15000D02*
Y10000D01*
G01Y10750D02*
X340867Y10333D01*
X340367Y10083D01*
X339783Y10000D01*
X339117Y10167D01*
X338617Y10583D01*
X338283Y11083D01*
X338200Y11667D01*
X338283Y12250D01*
X338617Y12750D01*
X339117Y13167D01*
X339783Y13333D01*
X340367Y13250D01*
X340783Y13083D01*
X341200Y12750D01*
G01X345300Y13333D02*
Y10000D01*
G01Y14667D02*
X345133Y14750D01*
Y14917D01*
X345300Y15000D01*
X345467Y14917D01*
Y14750D01*
X345300Y14667D01*
G01X348400Y10000D02*
Y13333D01*
G01Y12417D02*
X348650Y12833D01*
X349067Y13167D01*
X349650Y13333D01*
X350233Y13167D01*
X350650Y12833D01*
X350900Y12417D01*
Y10000D01*
G01Y12417D02*
X351150Y12833D01*
X351567Y13167D01*
X352150Y13333D01*
X352733Y13167D01*
X353150Y12833D01*
X353400Y12333D01*
Y10000D01*
G01X355250Y12250D02*
X357917D01*
X357667Y12833D01*
X357250Y13167D01*
X356667Y13333D01*
X356083Y13250D01*
X355583Y13000D01*
X355250Y12417D01*
X355083Y11917D01*
Y11417D01*
X355250Y10917D01*
X355667Y10417D01*
X356167Y10083D01*
X356750Y10000D01*
X357333Y10167D01*
X357917Y10667D01*
G01X360683Y10000D02*
Y13333D01*
G01Y12500D02*
X361017Y12917D01*
X361517Y13250D01*
X362183Y13333D01*
X362767Y13250D01*
X363267Y12917D01*
X363517Y12333D01*
Y10000D01*
G01X366450Y10583D02*
X366867Y10250D01*
X367450Y10000D01*
X367950D01*
X368450Y10167D01*
X368783Y10417D01*
X368950Y10750D01*
X368867Y11250D01*
X368533Y11500D01*
X367033Y12000D01*
X366700Y12583D01*
X366867Y13000D01*
X367200Y13250D01*
X367700Y13333D01*
X368200Y13250D01*
X368700Y13000D01*
G01X373300Y13333D02*
Y10000D01*
G01Y14667D02*
X373133Y14750D01*
Y14917D01*
X373300Y15000D01*
X373467Y14917D01*
Y14750D01*
X373300Y14667D01*
G01X378900Y10000D02*
X378400Y10083D01*
X377900Y10417D01*
X377567Y11000D01*
X377400Y11667D01*
X377567Y12333D01*
X377900Y12917D01*
X378400Y13250D01*
X378900Y13333D01*
X379400Y13250D01*
X379900Y12917D01*
X380233Y12333D01*
X380317Y11667D01*
X380233Y11000D01*
X379900Y10417D01*
X379400Y10083D01*
X378900Y10000D01*
G01X383083D02*
Y13333D01*
G01Y12500D02*
X383417Y12917D01*
X383917Y13250D01*
X384583Y13333D01*
X385167Y13250D01*
X385667Y12917D01*
X385917Y12333D01*
Y10000D01*
G01X395700D02*
X395200Y10083D01*
X394700Y10417D01*
X394367Y11000D01*
X394200Y11667D01*
X394367Y12333D01*
X394700Y12917D01*
X395200Y13250D01*
X395700Y13333D01*
X396200Y13250D01*
X396700Y12917D01*
X397033Y12333D01*
X397117Y11667D01*
X397033Y11000D01*
X396700Y10417D01*
X396200Y10083D01*
X395700Y10000D01*
G01X400800D02*
Y14250D01*
X400967Y14667D01*
X401300Y14917D01*
X401800Y15000D01*
X402300Y14833D01*
X402550Y14417D01*
G01X401550Y13000D02*
X399883D01*
G01X411000Y8333D02*
Y13333D01*
G01Y12583D02*
X411417Y13000D01*
X411833Y13250D01*
X412500Y13333D01*
X413083Y13250D01*
X413667Y12833D01*
X413917Y12250D01*
X414000Y11667D01*
X413917Y11083D01*
X413667Y10500D01*
X413167Y10167D01*
X412500Y10000D01*
X411917Y10083D01*
X411333Y10333D01*
X411000Y10667D01*
G01X419600Y10000D02*
Y13333D01*
G01Y12750D02*
X419267Y13083D01*
X418767Y13250D01*
X418183Y13333D01*
X417600Y13167D01*
X417100Y12833D01*
X416767Y12333D01*
X416600Y11667D01*
X416767Y11000D01*
X417100Y10500D01*
X417600Y10167D01*
X418183Y10000D01*
X418767Y10083D01*
X419267Y10333D01*
X419600Y10667D01*
G01X425200Y15000D02*
Y10000D01*
G01Y10750D02*
X424867Y10333D01*
X424367Y10083D01*
X423783Y10000D01*
X423117Y10167D01*
X422617Y10583D01*
X422283Y11083D01*
X422200Y11667D01*
X422283Y12250D01*
X422617Y12750D01*
X423117Y13167D01*
X423783Y13333D01*
X424367Y13250D01*
X424783Y13083D01*
X425200Y12750D01*
G01X434900Y10000D02*
X434400Y10083D01*
X433900Y10417D01*
X433567Y11000D01*
X433400Y11667D01*
X433567Y12333D01*
X433900Y12917D01*
X434400Y13250D01*
X434900Y13333D01*
X435400Y13250D01*
X435900Y12917D01*
X436233Y12333D01*
X436317Y11667D01*
X436233Y11000D01*
X435900Y10417D01*
X435400Y10083D01*
X434900Y10000D01*
G01X439333D02*
Y13333D01*
G01Y12667D02*
X439750Y13000D01*
X440167Y13250D01*
X440750Y13333D01*
X441167Y13250D01*
X441667Y13000D01*
G01X453200Y15000D02*
Y10000D01*
G01Y10750D02*
X452867Y10333D01*
X452367Y10083D01*
X451783Y10000D01*
X451117Y10167D01*
X450617Y10583D01*
X450283Y11083D01*
X450200Y11667D01*
X450283Y12250D01*
X450617Y12750D01*
X451117Y13167D01*
X451783Y13333D01*
X452367Y13250D01*
X452783Y13083D01*
X453200Y12750D01*
G01X457300Y13333D02*
Y10000D01*
G01Y14667D02*
X457133Y14750D01*
Y14917D01*
X457300Y15000D01*
X457467Y14917D01*
Y14750D01*
X457300Y14667D01*
G01X464400Y10000D02*
Y13333D01*
G01Y12750D02*
X464067Y13083D01*
X463567Y13250D01*
X462983Y13333D01*
X462400Y13167D01*
X461900Y12833D01*
X461567Y12333D01*
X461400Y11667D01*
X461567Y11000D01*
X461900Y10500D01*
X462400Y10167D01*
X462983Y10000D01*
X463567Y10083D01*
X464067Y10333D01*
X464400Y10667D01*
G01X466000Y10000D02*
Y13333D01*
G01Y12417D02*
X466250Y12833D01*
X466667Y13167D01*
X467250Y13333D01*
X467833Y13167D01*
X468250Y12833D01*
X468500Y12417D01*
Y10000D01*
G01Y12417D02*
X468750Y12833D01*
X469167Y13167D01*
X469750Y13333D01*
X470333Y13167D01*
X470750Y12833D01*
X471000Y12333D01*
Y10000D01*
G01X472850Y12250D02*
X475517D01*
X475267Y12833D01*
X474850Y13167D01*
X474267Y13333D01*
X473683Y13250D01*
X473183Y13000D01*
X472850Y12417D01*
X472683Y11917D01*
Y11417D01*
X472850Y10917D01*
X473267Y10417D01*
X473767Y10083D01*
X474350Y10000D01*
X474933Y10167D01*
X475517Y10667D01*
G01X479700Y15000D02*
Y10000D01*
G01X478533Y13333D02*
X480867D01*
G01X484050Y12250D02*
X486717D01*
X486467Y12833D01*
X486050Y13167D01*
X485467Y13333D01*
X484883Y13250D01*
X484383Y13000D01*
X484050Y12417D01*
X483883Y11917D01*
Y11417D01*
X484050Y10917D01*
X484467Y10417D01*
X484967Y10083D01*
X485550Y10000D01*
X486133Y10167D01*
X486717Y10667D01*
G01X489733Y10000D02*
Y13333D01*
G01Y12667D02*
X490150Y13000D01*
X490567Y13250D01*
X491150Y13333D01*
X491567Y13250D01*
X492067Y13000D01*
G01X500433Y10000D02*
X503767Y11667D01*
X500433Y13333D01*
G01X507700Y10000D02*
Y15000D01*
X506700Y14000D01*
G01Y10000D02*
X508700D01*
G01X514300D02*
Y15000D01*
X511217Y11417D01*
X515383D01*
G01X522000Y10000D02*
Y13333D01*
G01Y12417D02*
X522250Y12833D01*
X522667Y13167D01*
X523250Y13333D01*
X523833Y13167D01*
X524250Y12833D01*
X524500Y12417D01*
Y10000D01*
G01Y12417D02*
X524750Y12833D01*
X525167Y13167D01*
X525750Y13333D01*
X526333Y13167D01*
X526750Y12833D01*
X527000Y12333D01*
Y10000D01*
G01X530100Y13333D02*
Y10000D01*
G01Y14667D02*
X529933Y14750D01*
Y14917D01*
X530100Y15000D01*
X530267Y14917D01*
Y14750D01*
X530100Y14667D01*
G01X535700Y10000D02*
Y15000D01*
G01X264000Y5500D02*
X694500D01*
G01X264000Y40500D02*
X694500D01*
G01X272500Y101500D02*
Y96500D01*
G01X271333Y99833D02*
X273667D01*
G01X276933Y96500D02*
Y99833D01*
G01Y99167D02*
X277350Y99500D01*
X277767Y99750D01*
X278350Y99833D01*
X278767Y99750D01*
X279267Y99500D01*
G01X285200Y96500D02*
Y99833D01*
G01Y99250D02*
X284867Y99583D01*
X284367Y99750D01*
X283783Y99833D01*
X283200Y99667D01*
X282700Y99333D01*
X282367Y98833D01*
X282200Y98167D01*
X282367Y97500D01*
X282700Y97000D01*
X283200Y96667D01*
X283783Y96500D01*
X284367Y96583D01*
X284867Y96833D01*
X285200Y97167D01*
G01X290633Y99417D02*
X290050Y99750D01*
X289550Y99833D01*
X288883Y99667D01*
X288383Y99333D01*
X288050Y98750D01*
X287967Y98167D01*
X288050Y97583D01*
X288383Y97083D01*
X288883Y96667D01*
X289550Y96500D01*
X290133Y96667D01*
X290633Y97000D01*
G01X293650Y98750D02*
X296317D01*
X296067Y99333D01*
X295650Y99667D01*
X295067Y99833D01*
X294483Y99750D01*
X293983Y99500D01*
X293650Y98917D01*
X293483Y98417D01*
Y97917D01*
X293650Y97417D01*
X294067Y96917D01*
X294567Y96583D01*
X295150Y96500D01*
X295733Y96667D01*
X296317Y97167D01*
G01X304017Y99833D02*
X305017Y96500D01*
X306100Y99833D01*
X307183Y96500D01*
X308183Y99833D01*
G01X311700D02*
Y96500D01*
G01Y101167D02*
X311533Y101250D01*
Y101417D01*
X311700Y101500D01*
X311867Y101417D01*
Y101250D01*
X311700Y101167D01*
G01X318800Y101500D02*
Y96500D01*
G01Y97250D02*
X318467Y96833D01*
X317967Y96583D01*
X317383Y96500D01*
X316717Y96667D01*
X316217Y97083D01*
X315883Y97583D01*
X315800Y98167D01*
X315883Y98750D01*
X316217Y99250D01*
X316717Y99667D01*
X317383Y99833D01*
X317967Y99750D01*
X318383Y99583D01*
X318800Y99250D01*
G01X322900Y101500D02*
Y96500D01*
G01X321733Y99833D02*
X324067D01*
G01X327083Y96500D02*
Y101500D01*
G01Y99083D02*
X327500Y99500D01*
X327917Y99750D01*
X328583Y99833D01*
X329083Y99750D01*
X329667Y99417D01*
X329917Y98917D01*
Y96500D01*
G01X341367D02*
X338033Y98167D01*
X341367Y99833D01*
G01X344217Y97417D02*
X346383D01*
G01Y98917D02*
X344217D01*
G01X354667Y97250D02*
X355167Y96833D01*
X355750Y96583D01*
X356500Y96500D01*
X357250Y96667D01*
X357833Y97000D01*
X358250Y97583D01*
X358333Y98250D01*
X358167Y98917D01*
X357750Y99333D01*
X357167Y99667D01*
X356583Y99750D01*
X356000Y99667D01*
X355250Y99333D01*
X355500Y101500D01*
X357750D01*
G01X365200Y96500D02*
Y99833D01*
G01Y98917D02*
X365450Y99333D01*
X365867Y99667D01*
X366450Y99833D01*
X367033Y99667D01*
X367450Y99333D01*
X367700Y98917D01*
Y96500D01*
G01Y98917D02*
X367950Y99333D01*
X368367Y99667D01*
X368950Y99833D01*
X369533Y99667D01*
X369950Y99333D01*
X370200Y98833D01*
Y96500D01*
G01X373300Y99833D02*
Y96500D01*
G01Y101167D02*
X373133Y101250D01*
Y101417D01*
X373300Y101500D01*
X373467Y101417D01*
Y101250D01*
X373300Y101167D01*
G01X378900Y96500D02*
Y101500D01*
G01X270667Y82250D02*
X271167Y81833D01*
X271750Y81583D01*
X272500Y81500D01*
X273250Y81667D01*
X273833Y82000D01*
X274250Y82583D01*
X274333Y83250D01*
X274167Y83917D01*
X273750Y84333D01*
X273167Y84667D01*
X272583Y84750D01*
X272000Y84667D01*
X271250Y84333D01*
X271500Y86500D01*
X273750D01*
G01X281200Y81500D02*
Y84833D01*
G01Y83917D02*
X281450Y84333D01*
X281867Y84667D01*
X282450Y84833D01*
X283033Y84667D01*
X283450Y84333D01*
X283700Y83917D01*
Y81500D01*
G01Y83917D02*
X283950Y84333D01*
X284367Y84667D01*
X284950Y84833D01*
X285533Y84667D01*
X285950Y84333D01*
X286200Y83833D01*
Y81500D01*
G01X289300Y84833D02*
Y81500D01*
G01Y86167D02*
X289133Y86250D01*
Y86417D01*
X289300Y86500D01*
X289467Y86417D01*
Y86250D01*
X289300Y86167D01*
G01X294900Y81500D02*
Y86500D01*
G01X307767Y81500D02*
X304433Y83167D01*
X307767Y84833D01*
G01X317300Y86500D02*
Y81500D01*
G01X316133Y84833D02*
X318467D01*
G01X321733Y81500D02*
Y84833D01*
G01Y84167D02*
X322150Y84500D01*
X322567Y84750D01*
X323150Y84833D01*
X323567Y84750D01*
X324067Y84500D01*
G01X330000Y81500D02*
Y84833D01*
G01Y84250D02*
X329667Y84583D01*
X329167Y84750D01*
X328583Y84833D01*
X328000Y84667D01*
X327500Y84333D01*
X327167Y83833D01*
X327000Y83167D01*
X327167Y82500D01*
X327500Y82000D01*
X328000Y81667D01*
X328583Y81500D01*
X329167Y81583D01*
X329667Y81833D01*
X330000Y82167D01*
G01X335433Y84417D02*
X334850Y84750D01*
X334350Y84833D01*
X333683Y84667D01*
X333183Y84333D01*
X332850Y83750D01*
X332767Y83167D01*
X332850Y82583D01*
X333183Y82083D01*
X333683Y81667D01*
X334350Y81500D01*
X334933Y81667D01*
X335433Y82000D01*
G01X338450Y83750D02*
X341117D01*
X340867Y84333D01*
X340450Y84667D01*
X339867Y84833D01*
X339283Y84750D01*
X338783Y84500D01*
X338450Y83917D01*
X338283Y83417D01*
Y82917D01*
X338450Y82417D01*
X338867Y81917D01*
X339367Y81583D01*
X339950Y81500D01*
X340533Y81667D01*
X341117Y82167D01*
G01X348817Y84833D02*
X349817Y81500D01*
X350900Y84833D01*
X351983Y81500D01*
X352983Y84833D01*
G01X356500D02*
Y81500D01*
G01Y86167D02*
X356333Y86250D01*
Y86417D01*
X356500Y86500D01*
X356667Y86417D01*
Y86250D01*
X356500Y86167D01*
G01X363600Y86500D02*
Y81500D01*
G01Y82250D02*
X363267Y81833D01*
X362767Y81583D01*
X362183Y81500D01*
X361517Y81667D01*
X361017Y82083D01*
X360683Y82583D01*
X360600Y83167D01*
X360683Y83750D01*
X361017Y84250D01*
X361517Y84667D01*
X362183Y84833D01*
X362767Y84750D01*
X363183Y84583D01*
X363600Y84250D01*
G01X367700Y86500D02*
Y81500D01*
G01X366533Y84833D02*
X368867D01*
G01X371883Y81500D02*
Y86500D01*
G01Y84083D02*
X372300Y84500D01*
X372717Y84750D01*
X373383Y84833D01*
X373883Y84750D01*
X374467Y84417D01*
X374717Y83917D01*
Y81500D01*
G01X386167D02*
X382833Y83167D01*
X386167Y84833D01*
G01X389017Y82417D02*
X391183D01*
G01Y83917D02*
X389017D01*
G01X401133Y81500D02*
X401300Y82583D01*
X401550Y83500D01*
X401883Y84333D01*
X402300Y85250D01*
X402967Y86500D01*
X399633D01*
G01X410000Y81500D02*
Y84833D01*
G01Y83917D02*
X410250Y84333D01*
X410667Y84667D01*
X411250Y84833D01*
X411833Y84667D01*
X412250Y84333D01*
X412500Y83917D01*
Y81500D01*
G01Y83917D02*
X412750Y84333D01*
X413167Y84667D01*
X413750Y84833D01*
X414333Y84667D01*
X414750Y84333D01*
X415000Y83833D01*
Y81500D01*
G01X418100Y84833D02*
Y81500D01*
G01Y86167D02*
X417933Y86250D01*
Y86417D01*
X418100Y86500D01*
X418267Y86417D01*
Y86250D01*
X418100Y86167D01*
G01X423700Y81500D02*
Y86500D01*
G01X272500Y71500D02*
Y66500D01*
G01X271333Y69833D02*
X273667D01*
G01X276933Y66500D02*
Y69833D01*
G01Y69167D02*
X277350Y69500D01*
X277767Y69750D01*
X278350Y69833D01*
X278767Y69750D01*
X279267Y69500D01*
G01X285200Y66500D02*
Y69833D01*
G01Y69250D02*
X284867Y69583D01*
X284367Y69750D01*
X283783Y69833D01*
X283200Y69667D01*
X282700Y69333D01*
X282367Y68833D01*
X282200Y68167D01*
X282367Y67500D01*
X282700Y67000D01*
X283200Y66667D01*
X283783Y66500D01*
X284367Y66583D01*
X284867Y66833D01*
X285200Y67167D01*
G01X290633Y69417D02*
X290050Y69750D01*
X289550Y69833D01*
X288883Y69667D01*
X288383Y69333D01*
X288050Y68750D01*
X287967Y68167D01*
X288050Y67583D01*
X288383Y67083D01*
X288883Y66667D01*
X289550Y66500D01*
X290133Y66667D01*
X290633Y67000D01*
G01X293650Y68750D02*
X296317D01*
X296067Y69333D01*
X295650Y69667D01*
X295067Y69833D01*
X294483Y69750D01*
X293983Y69500D01*
X293650Y68917D01*
X293483Y68417D01*
Y67917D01*
X293650Y67417D01*
X294067Y66917D01*
X294567Y66583D01*
X295150Y66500D01*
X295733Y66667D01*
X296317Y67167D01*
G01X304017Y69833D02*
X305017Y66500D01*
X306100Y69833D01*
X307183Y66500D01*
X308183Y69833D01*
G01X311700D02*
Y66500D01*
G01Y71167D02*
X311533Y71250D01*
Y71417D01*
X311700Y71500D01*
X311867Y71417D01*
Y71250D01*
X311700Y71167D01*
G01X318800Y71500D02*
Y66500D01*
G01Y67250D02*
X318467Y66833D01*
X317967Y66583D01*
X317383Y66500D01*
X316717Y66667D01*
X316217Y67083D01*
X315883Y67583D01*
X315800Y68167D01*
X315883Y68750D01*
X316217Y69250D01*
X316717Y69667D01*
X317383Y69833D01*
X317967Y69750D01*
X318383Y69583D01*
X318800Y69250D01*
G01X322900Y71500D02*
Y66500D01*
G01X321733Y69833D02*
X324067D01*
G01X327083Y66500D02*
Y71500D01*
G01Y69083D02*
X327500Y69500D01*
X327917Y69750D01*
X328583Y69833D01*
X329083Y69750D01*
X329667Y69417D01*
X329917Y68917D01*
Y66500D01*
G01X338033D02*
X341367Y68167D01*
X338033Y69833D01*
G01X350733Y66500D02*
X350900Y67583D01*
X351150Y68500D01*
X351483Y69333D01*
X351900Y70250D01*
X352567Y71500D01*
X349233D01*
G01X359600Y66500D02*
Y69833D01*
G01Y68917D02*
X359850Y69333D01*
X360267Y69667D01*
X360850Y69833D01*
X361433Y69667D01*
X361850Y69333D01*
X362100Y68917D01*
Y66500D01*
G01Y68917D02*
X362350Y69333D01*
X362767Y69667D01*
X363350Y69833D01*
X363933Y69667D01*
X364350Y69333D01*
X364600Y68833D01*
Y66500D01*
G01X367700Y69833D02*
Y66500D01*
G01Y71167D02*
X367533Y71250D01*
Y71417D01*
X367700Y71500D01*
X367867Y71417D01*
Y71250D01*
X367700Y71167D01*
G01X373300Y66500D02*
Y71500D01*
G01X270833Y110000D02*
Y115000D01*
X272917D01*
X273583Y114750D01*
X274000Y114417D01*
X274167Y113750D01*
X274000Y113083D01*
X273500Y112667D01*
X272917Y112417D01*
X270833D01*
G01X272917D02*
X274167Y110000D01*
G01X276850Y112250D02*
X279517D01*
X279267Y112833D01*
X278850Y113167D01*
X278267Y113333D01*
X277683Y113250D01*
X277183Y113000D01*
X276850Y112417D01*
X276683Y111917D01*
Y111417D01*
X276850Y110917D01*
X277267Y110417D01*
X277767Y110083D01*
X278350Y110000D01*
X278933Y110167D01*
X279517Y110667D01*
G01X283700Y110000D02*
Y115000D01*
G01X290800Y110000D02*
Y113333D01*
G01Y112750D02*
X290467Y113083D01*
X289967Y113250D01*
X289383Y113333D01*
X288800Y113167D01*
X288300Y112833D01*
X287967Y112333D01*
X287800Y111667D01*
X287967Y111000D01*
X288300Y110500D01*
X288800Y110167D01*
X289383Y110000D01*
X289967Y110083D01*
X290467Y110333D01*
X290800Y110667D01*
G01X294900Y115000D02*
Y110000D01*
G01X293733Y113333D02*
X296067D01*
G01X300500D02*
Y110000D01*
G01Y114667D02*
X300333Y114750D01*
Y114917D01*
X300500Y115000D01*
X300667Y114917D01*
Y114750D01*
X300500Y114667D01*
G01X304600Y113333D02*
X306100Y110000D01*
X307600Y113333D01*
G01X310450Y112250D02*
X313117D01*
X312867Y112833D01*
X312450Y113167D01*
X311867Y113333D01*
X311283Y113250D01*
X310783Y113000D01*
X310450Y112417D01*
X310283Y111917D01*
Y111417D01*
X310450Y110917D01*
X310867Y110417D01*
X311367Y110083D01*
X311950Y110000D01*
X312533Y110167D01*
X313117Y110667D01*
G01X321400Y108333D02*
Y113333D01*
G01Y112583D02*
X321817Y113000D01*
X322233Y113250D01*
X322900Y113333D01*
X323483Y113250D01*
X324067Y112833D01*
X324317Y112250D01*
X324400Y111667D01*
X324317Y111083D01*
X324067Y110500D01*
X323567Y110167D01*
X322900Y110000D01*
X322317Y110083D01*
X321733Y110333D01*
X321400Y110667D01*
G01X328500Y110000D02*
X328000Y110083D01*
X327500Y110417D01*
X327167Y111000D01*
X327000Y111667D01*
X327167Y112333D01*
X327500Y112917D01*
X328000Y113250D01*
X328500Y113333D01*
X329000Y113250D01*
X329500Y112917D01*
X329833Y112333D01*
X329917Y111667D01*
X329833Y111000D01*
X329500Y110417D01*
X329000Y110083D01*
X328500Y110000D01*
G01X332850Y110583D02*
X333267Y110250D01*
X333850Y110000D01*
X334350D01*
X334850Y110167D01*
X335183Y110417D01*
X335350Y110750D01*
X335267Y111250D01*
X334933Y111500D01*
X333433Y112000D01*
X333100Y112583D01*
X333267Y113000D01*
X333600Y113250D01*
X334100Y113333D01*
X334600Y113250D01*
X335100Y113000D01*
G01X339700Y113333D02*
Y110000D01*
G01Y114667D02*
X339533Y114750D01*
Y114917D01*
X339700Y115000D01*
X339867Y114917D01*
Y114750D01*
X339700Y114667D01*
G01X345300Y115000D02*
Y110000D01*
G01X344133Y113333D02*
X346467D01*
G01X350900D02*
Y110000D01*
G01Y114667D02*
X350733Y114750D01*
Y114917D01*
X350900Y115000D01*
X351067Y114917D01*
Y114750D01*
X350900Y114667D01*
G01X356500Y110000D02*
X356000Y110083D01*
X355500Y110417D01*
X355167Y111000D01*
X355000Y111667D01*
X355167Y112333D01*
X355500Y112917D01*
X356000Y113250D01*
X356500Y113333D01*
X357000Y113250D01*
X357500Y112917D01*
X357833Y112333D01*
X357917Y111667D01*
X357833Y111000D01*
X357500Y110417D01*
X357000Y110083D01*
X356500Y110000D01*
G01X360683D02*
Y113333D01*
G01Y112500D02*
X361017Y112917D01*
X361517Y113250D01*
X362183Y113333D01*
X362767Y113250D01*
X363267Y112917D01*
X363517Y112333D01*
Y110000D01*
G01X371800D02*
Y115000D01*
G01Y112500D02*
X372217Y113000D01*
X372717Y113250D01*
X373217Y113333D01*
X373967Y113167D01*
X374467Y112833D01*
X374800Y112250D01*
Y111583D01*
X374633Y110917D01*
X374300Y110417D01*
X373717Y110083D01*
X373217Y110000D01*
X372717Y110083D01*
X372217Y110333D01*
X371800Y110750D01*
G01X377650Y112250D02*
X380317D01*
X380067Y112833D01*
X379650Y113167D01*
X379067Y113333D01*
X378483Y113250D01*
X377983Y113000D01*
X377650Y112417D01*
X377483Y111917D01*
Y111417D01*
X377650Y110917D01*
X378067Y110417D01*
X378567Y110083D01*
X379150Y110000D01*
X379733Y110167D01*
X380317Y110667D01*
G01X384500Y115000D02*
Y110000D01*
G01X383333Y113333D02*
X385667D01*
G01X388017D02*
X389017Y110000D01*
X390100Y113333D01*
X391183Y110000D01*
X392183Y113333D01*
G01X394450Y112250D02*
X397117D01*
X396867Y112833D01*
X396450Y113167D01*
X395867Y113333D01*
X395283Y113250D01*
X394783Y113000D01*
X394450Y112417D01*
X394283Y111917D01*
Y111417D01*
X394450Y110917D01*
X394867Y110417D01*
X395367Y110083D01*
X395950Y110000D01*
X396533Y110167D01*
X397117Y110667D01*
G01X400050Y112250D02*
X402717D01*
X402467Y112833D01*
X402050Y113167D01*
X401467Y113333D01*
X400883Y113250D01*
X400383Y113000D01*
X400050Y112417D01*
X399883Y111917D01*
Y111417D01*
X400050Y110917D01*
X400467Y110417D01*
X400967Y110083D01*
X401550Y110000D01*
X402133Y110167D01*
X402717Y110667D01*
G01X405483Y110000D02*
Y113333D01*
G01Y112500D02*
X405817Y112917D01*
X406317Y113250D01*
X406983Y113333D01*
X407567Y113250D01*
X408067Y112917D01*
X408317Y112333D01*
Y110000D01*
G01X419600D02*
Y113333D01*
G01Y112750D02*
X419267Y113083D01*
X418767Y113250D01*
X418183Y113333D01*
X417600Y113167D01*
X417100Y112833D01*
X416767Y112333D01*
X416600Y111667D01*
X416767Y111000D01*
X417100Y110500D01*
X417600Y110167D01*
X418183Y110000D01*
X418767Y110083D01*
X419267Y110333D01*
X419600Y110667D01*
G01X422283Y110000D02*
Y113333D01*
G01Y112500D02*
X422617Y112917D01*
X423117Y113250D01*
X423783Y113333D01*
X424367Y113250D01*
X424867Y112917D01*
X425117Y112333D01*
Y110000D01*
G01X427550Y108500D02*
X428050Y108333D01*
X428717Y108500D01*
X429133Y108833D01*
X429467Y109250D01*
X429967Y110583D01*
X431050Y113333D01*
G01X428383D02*
X429967Y110583D01*
G01X439000Y108333D02*
Y113333D01*
G01Y112583D02*
X439417Y113000D01*
X439833Y113250D01*
X440500Y113333D01*
X441083Y113250D01*
X441667Y112833D01*
X441917Y112250D01*
X442000Y111667D01*
X441917Y111083D01*
X441667Y110500D01*
X441167Y110167D01*
X440500Y110000D01*
X439917Y110083D01*
X439333Y110333D01*
X439000Y110667D01*
G01X447600Y110000D02*
Y113333D01*
G01Y112750D02*
X447267Y113083D01*
X446767Y113250D01*
X446183Y113333D01*
X445600Y113167D01*
X445100Y112833D01*
X444767Y112333D01*
X444600Y111667D01*
X444767Y111000D01*
X445100Y110500D01*
X445600Y110167D01*
X446183Y110000D01*
X446767Y110083D01*
X447267Y110333D01*
X447600Y110667D01*
G01X453200Y115000D02*
Y110000D01*
G01Y110750D02*
X452867Y110333D01*
X452367Y110083D01*
X451783Y110000D01*
X451117Y110167D01*
X450617Y110583D01*
X450283Y111083D01*
X450200Y111667D01*
X450283Y112250D01*
X450617Y112750D01*
X451117Y113167D01*
X451783Y113333D01*
X452367Y113250D01*
X452783Y113083D01*
X453200Y112750D01*
G01X462900Y115000D02*
Y110000D01*
G01X461733Y113333D02*
X464067D01*
G01X468500Y110000D02*
X468000Y110083D01*
X467500Y110417D01*
X467167Y111000D01*
X467000Y111667D01*
X467167Y112333D01*
X467500Y112917D01*
X468000Y113250D01*
X468500Y113333D01*
X469000Y113250D01*
X469500Y112917D01*
X469833Y112333D01*
X469917Y111667D01*
X469833Y111000D01*
X469500Y110417D01*
X469000Y110083D01*
X468500Y110000D01*
G01X478200Y108333D02*
Y113333D01*
G01Y112583D02*
X478617Y113000D01*
X479033Y113250D01*
X479700Y113333D01*
X480283Y113250D01*
X480867Y112833D01*
X481117Y112250D01*
X481200Y111667D01*
X481117Y111083D01*
X480867Y110500D01*
X480367Y110167D01*
X479700Y110000D01*
X479117Y110083D01*
X478533Y110333D01*
X478200Y110667D01*
G01X486800Y110000D02*
Y113333D01*
G01Y112750D02*
X486467Y113083D01*
X485967Y113250D01*
X485383Y113333D01*
X484800Y113167D01*
X484300Y112833D01*
X483967Y112333D01*
X483800Y111667D01*
X483967Y111000D01*
X484300Y110500D01*
X484800Y110167D01*
X485383Y110000D01*
X485967Y110083D01*
X486467Y110333D01*
X486800Y110667D01*
G01X492400Y115000D02*
Y110000D01*
G01Y110750D02*
X492067Y110333D01*
X491567Y110083D01*
X490983Y110000D01*
X490317Y110167D01*
X489817Y110583D01*
X489483Y111083D01*
X489400Y111667D01*
X489483Y112250D01*
X489817Y112750D01*
X490317Y113167D01*
X490983Y113333D01*
X491567Y113250D01*
X491983Y113083D01*
X492400Y112750D01*
G01X264000Y75500D02*
X694500D01*
G01X264000Y90500D02*
X694500D01*
G01X271250Y141583D02*
X271667Y141250D01*
X272250Y141000D01*
X272750D01*
X273250Y141167D01*
X273583Y141417D01*
X273750Y141750D01*
X273667Y142250D01*
X273333Y142500D01*
X271833Y143000D01*
X271500Y143583D01*
X271667Y144000D01*
X272000Y144250D01*
X272500Y144333D01*
X273000Y144250D01*
X273500Y144000D01*
G01X276600Y139333D02*
Y144333D01*
G01Y143583D02*
X277017Y144000D01*
X277433Y144250D01*
X278100Y144333D01*
X278683Y144250D01*
X279267Y143833D01*
X279517Y143250D01*
X279600Y142667D01*
X279517Y142083D01*
X279267Y141500D01*
X278767Y141167D01*
X278100Y141000D01*
X277517Y141083D01*
X276933Y141333D01*
X276600Y141667D01*
G01X282450Y143250D02*
X285117D01*
X284867Y143833D01*
X284450Y144167D01*
X283867Y144333D01*
X283283Y144250D01*
X282783Y144000D01*
X282450Y143417D01*
X282283Y142917D01*
Y142417D01*
X282450Y141917D01*
X282867Y141417D01*
X283367Y141083D01*
X283950Y141000D01*
X284533Y141167D01*
X285117Y141667D01*
G01X290633Y143917D02*
X290050Y144250D01*
X289550Y144333D01*
X288883Y144167D01*
X288383Y143833D01*
X288050Y143250D01*
X287967Y142667D01*
X288050Y142083D01*
X288383Y141583D01*
X288883Y141167D01*
X289550Y141000D01*
X290133Y141167D01*
X290633Y141500D01*
G01X294900Y144333D02*
Y141000D01*
G01Y145667D02*
X294733Y145750D01*
Y145917D01*
X294900Y146000D01*
X295067Y145917D01*
Y145750D01*
X294900Y145667D01*
G01X300000Y141000D02*
Y145250D01*
X300167Y145667D01*
X300500Y145917D01*
X301000Y146000D01*
X301500Y145833D01*
X301750Y145417D01*
G01X300750Y144000D02*
X299083D01*
G01X306100Y144333D02*
Y141000D01*
G01Y145667D02*
X305933Y145750D01*
Y145917D01*
X306100Y146000D01*
X306267Y145917D01*
Y145750D01*
X306100Y145667D01*
G01X313033Y143917D02*
X312450Y144250D01*
X311950Y144333D01*
X311283Y144167D01*
X310783Y143833D01*
X310450Y143250D01*
X310367Y142667D01*
X310450Y142083D01*
X310783Y141583D01*
X311283Y141167D01*
X311950Y141000D01*
X312533Y141167D01*
X313033Y141500D01*
G01X318800Y141000D02*
Y144333D01*
G01Y143750D02*
X318467Y144083D01*
X317967Y144250D01*
X317383Y144333D01*
X316800Y144167D01*
X316300Y143833D01*
X315967Y143333D01*
X315800Y142667D01*
X315967Y142000D01*
X316300Y141500D01*
X316800Y141167D01*
X317383Y141000D01*
X317967Y141083D01*
X318467Y141333D01*
X318800Y141667D01*
G01X322900Y146000D02*
Y141000D01*
G01X321733Y144333D02*
X324067D01*
G01X328500D02*
Y141000D01*
G01Y145667D02*
X328333Y145750D01*
Y145917D01*
X328500Y146000D01*
X328667Y145917D01*
Y145750D01*
X328500Y145667D01*
G01X334100Y141000D02*
X333600Y141083D01*
X333100Y141417D01*
X332767Y142000D01*
X332600Y142667D01*
X332767Y143333D01*
X333100Y143917D01*
X333600Y144250D01*
X334100Y144333D01*
X334600Y144250D01*
X335100Y143917D01*
X335433Y143333D01*
X335517Y142667D01*
X335433Y142000D01*
X335100Y141417D01*
X334600Y141083D01*
X334100Y141000D01*
G01X338283D02*
Y144333D01*
G01Y143500D02*
X338617Y143917D01*
X339117Y144250D01*
X339783Y144333D01*
X340367Y144250D01*
X340867Y143917D01*
X341117Y143333D01*
Y141000D01*
G01X345300Y140833D02*
X345133Y140917D01*
Y141083D01*
X345300Y141167D01*
X345467Y141083D01*
Y140917D01*
X345300Y140833D01*
G01X270750Y125000D02*
Y130000D01*
G01X274250D02*
Y125000D01*
G01Y127500D02*
X270750D01*
G01X276267Y125000D02*
Y130000D01*
X277933D01*
X278600Y129750D01*
X279100Y129417D01*
X279517Y128917D01*
X279850Y128333D01*
X279933Y127500D01*
X279850Y126667D01*
X279517Y126083D01*
X279100Y125583D01*
X278600Y125250D01*
X277933Y125000D01*
X276267D01*
G01X282700Y130000D02*
X284700D01*
G01X283700D02*
Y125000D01*
G01X282700D02*
X284700D01*
G01X293233D02*
Y130000D01*
X295233D01*
X295900Y129750D01*
X296400Y129167D01*
X296567Y128500D01*
X296400Y127833D01*
X295983Y127333D01*
X295233Y127083D01*
X293233D01*
G01X302333Y129583D02*
X301833Y129833D01*
X301250Y130000D01*
X300583D01*
X299833Y129750D01*
X299250Y129333D01*
X298833Y128833D01*
X298500Y128000D01*
X298417Y127250D01*
X298583Y126500D01*
X298833Y126000D01*
X299333Y125500D01*
X299917Y125167D01*
X300500Y125000D01*
X301083D01*
X301667Y125167D01*
X302167Y125417D01*
X302583Y125750D01*
G01X306767Y127667D02*
X307100Y127917D01*
X307350Y128333D01*
X307517Y128917D01*
X307350Y129417D01*
X307017Y129750D01*
X306433Y130000D01*
X304183D01*
Y125000D01*
X306933D01*
X307517Y125333D01*
X307850Y125833D01*
X308017Y126417D01*
X307850Y127000D01*
X307350Y127500D01*
X306767Y127667D01*
X304183D01*
G01X311700Y124833D02*
X311533Y124917D01*
Y125083D01*
X311700Y125167D01*
X311867Y125083D01*
Y124917D01*
X311700Y124833D01*
G01X270750Y150667D02*
X271417Y150250D01*
X272167Y150000D01*
X272833D01*
X273500Y150250D01*
X274000Y150667D01*
X274250Y151250D01*
X274083Y151833D01*
X273667Y152333D01*
X272917Y152667D01*
X271917Y152833D01*
X271333Y153167D01*
X271083Y153750D01*
X271250Y154333D01*
X271667Y154750D01*
X272250Y155000D01*
X272833D01*
X273417Y154833D01*
X273917Y154417D01*
G01X276850Y152250D02*
X279517D01*
X279267Y152833D01*
X278850Y153167D01*
X278267Y153333D01*
X277683Y153250D01*
X277183Y153000D01*
X276850Y152417D01*
X276683Y151917D01*
Y151417D01*
X276850Y150917D01*
X277267Y150417D01*
X277767Y150083D01*
X278350Y150000D01*
X278933Y150167D01*
X279517Y150667D01*
G01X282533Y150000D02*
Y153333D01*
G01Y152667D02*
X282950Y153000D01*
X283367Y153250D01*
X283950Y153333D01*
X284367Y153250D01*
X284867Y153000D01*
G01X287800Y153333D02*
X289300Y150000D01*
X290800Y153333D01*
G01X293650Y152250D02*
X296317D01*
X296067Y152833D01*
X295650Y153167D01*
X295067Y153333D01*
X294483Y153250D01*
X293983Y153000D01*
X293650Y152417D01*
X293483Y151917D01*
Y151417D01*
X293650Y150917D01*
X294067Y150417D01*
X294567Y150083D01*
X295150Y150000D01*
X295733Y150167D01*
X296317Y150667D01*
G01X299333Y150000D02*
Y153333D01*
G01Y152667D02*
X299750Y153000D01*
X300167Y153250D01*
X300750Y153333D01*
X301167Y153250D01*
X301667Y153000D01*
G01X310033Y150000D02*
Y155000D01*
X312033D01*
X312700Y154750D01*
X313200Y154167D01*
X313367Y153500D01*
X313200Y152833D01*
X312783Y152333D01*
X312033Y152083D01*
X310033D01*
G01X319133Y154583D02*
X318633Y154833D01*
X318050Y155000D01*
X317383D01*
X316633Y154750D01*
X316050Y154333D01*
X315633Y153833D01*
X315300Y153000D01*
X315217Y152250D01*
X315383Y151500D01*
X315633Y151000D01*
X316133Y150500D01*
X316717Y150167D01*
X317300Y150000D01*
X317883D01*
X318467Y150167D01*
X318967Y150417D01*
X319383Y150750D01*
G01X323567Y152667D02*
X323900Y152917D01*
X324150Y153333D01*
X324317Y153917D01*
X324150Y154417D01*
X323817Y154750D01*
X323233Y155000D01*
X320983D01*
Y150000D01*
X323733D01*
X324317Y150333D01*
X324650Y150833D01*
X324817Y151417D01*
X324650Y152000D01*
X324150Y152500D01*
X323567Y152667D01*
X320983D01*
G01X328500Y149833D02*
X328333Y149917D01*
Y150083D01*
X328500Y150167D01*
X328667Y150083D01*
Y149917D01*
X328500Y149833D01*
G01Y152083D02*
X328333Y152167D01*
Y152333D01*
X328500Y152417D01*
X328667Y152333D01*
Y152167D01*
X328500Y152083D01*
G01X332517Y150000D02*
Y155000D01*
X335683D01*
G01X334517Y152583D02*
X332517D01*
G01X339700Y150000D02*
X339200Y150083D01*
X338700Y150417D01*
X338367Y151000D01*
X338200Y151667D01*
X338367Y152333D01*
X338700Y152917D01*
X339200Y153250D01*
X339700Y153333D01*
X340200Y153250D01*
X340700Y152917D01*
X341033Y152333D01*
X341117Y151667D01*
X341033Y151000D01*
X340700Y150417D01*
X340200Y150083D01*
X339700Y150000D01*
G01X345300D02*
Y155000D01*
G01X350900Y150000D02*
Y155000D01*
G01X356500Y150000D02*
X356000Y150083D01*
X355500Y150417D01*
X355167Y151000D01*
X355000Y151667D01*
X355167Y152333D01*
X355500Y152917D01*
X356000Y153250D01*
X356500Y153333D01*
X357000Y153250D01*
X357500Y152917D01*
X357833Y152333D01*
X357917Y151667D01*
X357833Y151000D01*
X357500Y150417D01*
X357000Y150083D01*
X356500Y150000D01*
G01X360017Y153333D02*
X361017Y150000D01*
X362100Y153333D01*
X363183Y150000D01*
X364183Y153333D01*
G01X372133Y150000D02*
Y153333D01*
G01Y152667D02*
X372550Y153000D01*
X372967Y153250D01*
X373550Y153333D01*
X373967Y153250D01*
X374467Y153000D01*
G01X378900Y153333D02*
Y150000D01*
G01Y154667D02*
X378733Y154750D01*
Y154917D01*
X378900Y155000D01*
X379067Y154917D01*
Y154750D01*
X378900Y154667D01*
G01X383333Y148750D02*
X383917Y148417D01*
X384583Y148333D01*
X385167Y148417D01*
X385667Y148833D01*
X386000Y149417D01*
Y153333D01*
G01Y152667D02*
X385667Y153000D01*
X385167Y153250D01*
X384583Y153333D01*
X383917Y153167D01*
X383500Y152833D01*
X383167Y152250D01*
X383000Y151667D01*
X383083Y151167D01*
X383417Y150583D01*
X383917Y150167D01*
X384583Y150000D01*
X385083Y150083D01*
X385667Y150417D01*
X386000Y150750D01*
G01X388683Y150000D02*
Y155000D01*
G01Y152583D02*
X389100Y153000D01*
X389517Y153250D01*
X390183Y153333D01*
X390683Y153250D01*
X391267Y152917D01*
X391517Y152417D01*
Y150000D01*
G01X395700Y155000D02*
Y150000D01*
G01X394533Y153333D02*
X396867D01*
G01X405650Y150583D02*
X406067Y150250D01*
X406650Y150000D01*
X407150D01*
X407650Y150167D01*
X407983Y150417D01*
X408150Y150750D01*
X408067Y151250D01*
X407733Y151500D01*
X406233Y152000D01*
X405900Y152583D01*
X406067Y153000D01*
X406400Y153250D01*
X406900Y153333D01*
X407400Y153250D01*
X407900Y153000D01*
G01X412500Y153333D02*
Y150000D01*
G01Y154667D02*
X412333Y154750D01*
Y154917D01*
X412500Y155000D01*
X412667Y154917D01*
Y154750D01*
X412500Y154667D01*
G01X419600Y155000D02*
Y150000D01*
G01Y150750D02*
X419267Y150333D01*
X418767Y150083D01*
X418183Y150000D01*
X417517Y150167D01*
X417017Y150583D01*
X416683Y151083D01*
X416600Y151667D01*
X416683Y152250D01*
X417017Y152750D01*
X417517Y153167D01*
X418183Y153333D01*
X418767Y153250D01*
X419183Y153083D01*
X419600Y152750D01*
G01X422450Y152250D02*
X425117D01*
X424867Y152833D01*
X424450Y153167D01*
X423867Y153333D01*
X423283Y153250D01*
X422783Y153000D01*
X422450Y152417D01*
X422283Y151917D01*
Y151417D01*
X422450Y150917D01*
X422867Y150417D01*
X423367Y150083D01*
X423950Y150000D01*
X424533Y150167D01*
X425117Y150667D01*
G01X433650Y150583D02*
X434067Y150250D01*
X434650Y150000D01*
X435150D01*
X435650Y150167D01*
X435983Y150417D01*
X436150Y150750D01*
X436067Y151250D01*
X435733Y151500D01*
X434233Y152000D01*
X433900Y152583D01*
X434067Y153000D01*
X434400Y153250D01*
X434900Y153333D01*
X435400Y153250D01*
X435900Y153000D01*
G01X439000Y148333D02*
Y153333D01*
G01Y152583D02*
X439417Y153000D01*
X439833Y153250D01*
X440500Y153333D01*
X441083Y153250D01*
X441667Y152833D01*
X441917Y152250D01*
X442000Y151667D01*
X441917Y151083D01*
X441667Y150500D01*
X441167Y150167D01*
X440500Y150000D01*
X439917Y150083D01*
X439333Y150333D01*
X439000Y150667D01*
G01X444850Y152250D02*
X447517D01*
X447267Y152833D01*
X446850Y153167D01*
X446267Y153333D01*
X445683Y153250D01*
X445183Y153000D01*
X444850Y152417D01*
X444683Y151917D01*
Y151417D01*
X444850Y150917D01*
X445267Y150417D01*
X445767Y150083D01*
X446350Y150000D01*
X446933Y150167D01*
X447517Y150667D01*
G01X453033Y152917D02*
X452450Y153250D01*
X451950Y153333D01*
X451283Y153167D01*
X450783Y152833D01*
X450450Y152250D01*
X450367Y151667D01*
X450450Y151083D01*
X450783Y150583D01*
X451283Y150167D01*
X451950Y150000D01*
X452533Y150167D01*
X453033Y150500D01*
G01X462733Y149083D02*
X463067Y150167D01*
G01X468500Y153333D02*
Y150000D01*
G01Y154667D02*
X468333Y154750D01*
Y154917D01*
X468500Y155000D01*
X468667Y154917D01*
Y154750D01*
X468500Y154667D01*
G01X473600Y150000D02*
Y154250D01*
X473767Y154667D01*
X474100Y154917D01*
X474600Y155000D01*
X475100Y154833D01*
X475350Y154417D01*
G01X474350Y153000D02*
X472683D01*
G01X484050Y150583D02*
X484467Y150250D01*
X485050Y150000D01*
X485550D01*
X486050Y150167D01*
X486383Y150417D01*
X486550Y150750D01*
X486467Y151250D01*
X486133Y151500D01*
X484633Y152000D01*
X484300Y152583D01*
X484467Y153000D01*
X484800Y153250D01*
X485300Y153333D01*
X485800Y153250D01*
X486300Y153000D01*
G01X490900Y155000D02*
Y150000D01*
G01X489733Y153333D02*
X492067D01*
G01X498000Y150000D02*
Y153333D01*
G01Y152750D02*
X497667Y153083D01*
X497167Y153250D01*
X496583Y153333D01*
X496000Y153167D01*
X495500Y152833D01*
X495167Y152333D01*
X495000Y151667D01*
X495167Y151000D01*
X495500Y150500D01*
X496000Y150167D01*
X496583Y150000D01*
X497167Y150083D01*
X497667Y150333D01*
X498000Y150667D01*
G01X503433Y152917D02*
X502850Y153250D01*
X502350Y153333D01*
X501683Y153167D01*
X501183Y152833D01*
X500850Y152250D01*
X500767Y151667D01*
X500850Y151083D01*
X501183Y150583D01*
X501683Y150167D01*
X502350Y150000D01*
X502933Y150167D01*
X503433Y150500D01*
G01X506283Y150000D02*
Y155000D01*
G01X508950Y153333D02*
X506283Y151417D01*
G01X507367Y152167D02*
X509117Y150000D01*
G01X517483Y153333D02*
Y151000D01*
X517817Y150417D01*
X518317Y150083D01*
X518900Y150000D01*
X519483Y150083D01*
X519983Y150417D01*
X520317Y151000D01*
G01Y150000D02*
Y153333D01*
G01X523000Y148333D02*
Y153333D01*
G01Y152583D02*
X523417Y153000D01*
X523833Y153250D01*
X524500Y153333D01*
X525083Y153250D01*
X525667Y152833D01*
X525917Y152250D01*
X526000Y151667D01*
X525917Y151083D01*
X525667Y150500D01*
X525167Y150167D01*
X524500Y150000D01*
X523917Y150083D01*
X523333Y150333D01*
X523000Y150667D01*
G01X533617Y153333D02*
X534617Y150000D01*
X535700Y153333D01*
X536783Y150000D01*
X537783Y153333D01*
G01X541300D02*
Y150000D01*
G01Y154667D02*
X541133Y154750D01*
Y154917D01*
X541300Y155000D01*
X541467Y154917D01*
Y154750D01*
X541300Y154667D01*
G01X546900Y155000D02*
Y150000D01*
G01X545733Y153333D02*
X548067D01*
G01X551083Y150000D02*
Y155000D01*
G01Y152583D02*
X551500Y153000D01*
X551917Y153250D01*
X552583Y153333D01*
X553083Y153250D01*
X553667Y152917D01*
X553917Y152417D01*
Y150000D01*
G01X558100D02*
X557600Y150083D01*
X557100Y150417D01*
X556767Y151000D01*
X556600Y151667D01*
X556767Y152333D01*
X557100Y152917D01*
X557600Y153250D01*
X558100Y153333D01*
X558600Y153250D01*
X559100Y152917D01*
X559433Y152333D01*
X559517Y151667D01*
X559433Y151000D01*
X559100Y150417D01*
X558600Y150083D01*
X558100Y150000D01*
G01X562283Y153333D02*
Y151000D01*
X562617Y150417D01*
X563117Y150083D01*
X563700Y150000D01*
X564283Y150083D01*
X564783Y150417D01*
X565117Y151000D01*
G01Y150000D02*
Y153333D01*
G01X569300Y155000D02*
Y150000D01*
G01X568133Y153333D02*
X570467D01*
G01X272500Y170000D02*
Y165000D01*
G01X270583Y170000D02*
X274417D01*
G01X276933Y165000D02*
Y168333D01*
G01Y167667D02*
X277350Y168000D01*
X277767Y168250D01*
X278350Y168333D01*
X278767Y168250D01*
X279267Y168000D01*
G01X285200Y165000D02*
Y168333D01*
G01Y167750D02*
X284867Y168083D01*
X284367Y168250D01*
X283783Y168333D01*
X283200Y168167D01*
X282700Y167833D01*
X282367Y167333D01*
X282200Y166667D01*
X282367Y166000D01*
X282700Y165500D01*
X283200Y165167D01*
X283783Y165000D01*
X284367Y165083D01*
X284867Y165333D01*
X285200Y165667D01*
G01X290800Y170000D02*
Y165000D01*
G01Y165750D02*
X290467Y165333D01*
X289967Y165083D01*
X289383Y165000D01*
X288717Y165167D01*
X288217Y165583D01*
X287883Y166083D01*
X287800Y166667D01*
X287883Y167250D01*
X288217Y167750D01*
X288717Y168167D01*
X289383Y168333D01*
X289967Y168250D01*
X290383Y168083D01*
X290800Y167750D01*
G01X294900Y168333D02*
Y165000D01*
G01Y169667D02*
X294733Y169750D01*
Y169917D01*
X294900Y170000D01*
X295067Y169917D01*
Y169750D01*
X294900Y169667D01*
G01X300500Y170000D02*
Y165000D01*
G01X299333Y168333D02*
X301667D01*
G01X306100D02*
Y165000D01*
G01Y169667D02*
X305933Y169750D01*
Y169917D01*
X306100Y170000D01*
X306267Y169917D01*
Y169750D01*
X306100Y169667D01*
G01X311700Y165000D02*
X311200Y165083D01*
X310700Y165417D01*
X310367Y166000D01*
X310200Y166667D01*
X310367Y167333D01*
X310700Y167917D01*
X311200Y168250D01*
X311700Y168333D01*
X312200Y168250D01*
X312700Y167917D01*
X313033Y167333D01*
X313117Y166667D01*
X313033Y166000D01*
X312700Y165417D01*
X312200Y165083D01*
X311700Y165000D01*
G01X315883D02*
Y168333D01*
G01Y167500D02*
X316217Y167917D01*
X316717Y168250D01*
X317383Y168333D01*
X317967Y168250D01*
X318467Y167917D01*
X318717Y167333D01*
Y165000D01*
G01X324400D02*
Y168333D01*
G01Y167750D02*
X324067Y168083D01*
X323567Y168250D01*
X322983Y168333D01*
X322400Y168167D01*
X321900Y167833D01*
X321567Y167333D01*
X321400Y166667D01*
X321567Y166000D01*
X321900Y165500D01*
X322400Y165167D01*
X322983Y165000D01*
X323567Y165083D01*
X324067Y165333D01*
X324400Y165667D01*
G01X328500Y165000D02*
Y170000D01*
G01X338033Y165000D02*
Y170000D01*
X340033D01*
X340700Y169750D01*
X341200Y169167D01*
X341367Y168500D01*
X341200Y167833D01*
X340783Y167333D01*
X340033Y167083D01*
X338033D01*
G01X347133Y169583D02*
X346633Y169833D01*
X346050Y170000D01*
X345383D01*
X344633Y169750D01*
X344050Y169333D01*
X343633Y168833D01*
X343300Y168000D01*
X343217Y167250D01*
X343383Y166500D01*
X343633Y166000D01*
X344133Y165500D01*
X344717Y165167D01*
X345300Y165000D01*
X345883D01*
X346467Y165167D01*
X346967Y165417D01*
X347383Y165750D01*
G01X351567Y167667D02*
X351900Y167917D01*
X352150Y168333D01*
X352317Y168917D01*
X352150Y169417D01*
X351817Y169750D01*
X351233Y170000D01*
X348983D01*
Y165000D01*
X351733D01*
X352317Y165333D01*
X352650Y165833D01*
X352817Y166417D01*
X352650Y167000D01*
X352150Y167500D01*
X351567Y167667D01*
X348983D01*
G01X356500Y164833D02*
X356333Y164917D01*
Y165083D01*
X356500Y165167D01*
X356667Y165083D01*
Y164917D01*
X356500Y164833D01*
G01X264000Y135500D02*
X694500D01*
G01X264000Y160500D02*
X694500D01*
G01X262500Y237500D02*
X694500D01*
G01X322623Y303963D02*
X322890Y304163D01*
X323090Y304497D01*
X323223Y304963D01*
X323090Y305363D01*
X322823Y305630D01*
X322357Y305830D01*
X320557D01*
Y301830D01*
X322757D01*
X323223Y302097D01*
X323490Y302497D01*
X323623Y302963D01*
X323490Y303430D01*
X323090Y303830D01*
X322623Y303963D01*
X320557D01*
G01X262500Y290500D02*
X694500D01*
G01X320423Y351330D02*
X322090Y355330D01*
X323757Y351330D01*
G01X323157Y352730D02*
X321023D01*
G01X270000Y374000D02*
Y369000D01*
G01X268833Y372333D02*
X271167D01*
G01X275600Y369000D02*
X275100Y369083D01*
X274600Y369417D01*
X274267Y370000D01*
X274100Y370667D01*
X274267Y371333D01*
X274600Y371917D01*
X275100Y372250D01*
X275600Y372333D01*
X276100Y372250D01*
X276600Y371917D01*
X276933Y371333D01*
X277017Y370667D01*
X276933Y370000D01*
X276600Y369417D01*
X276100Y369083D01*
X275600Y369000D01*
G01X281200D02*
Y374000D01*
G01X285550Y371250D02*
X288217D01*
X287967Y371833D01*
X287550Y372167D01*
X286967Y372333D01*
X286383Y372250D01*
X285883Y372000D01*
X285550Y371417D01*
X285383Y370917D01*
Y370417D01*
X285550Y369917D01*
X285967Y369417D01*
X286467Y369083D01*
X287050Y369000D01*
X287633Y369167D01*
X288217Y369667D01*
G01X291233Y369000D02*
Y372333D01*
G01Y371667D02*
X291650Y372000D01*
X292067Y372250D01*
X292650Y372333D01*
X293067Y372250D01*
X293567Y372000D01*
G01X299500Y369000D02*
Y372333D01*
G01Y371750D02*
X299167Y372083D01*
X298667Y372250D01*
X298083Y372333D01*
X297500Y372167D01*
X297000Y371833D01*
X296667Y371333D01*
X296500Y370667D01*
X296667Y370000D01*
X297000Y369500D01*
X297500Y369167D01*
X298083Y369000D01*
X298667Y369083D01*
X299167Y369333D01*
X299500Y369667D01*
G01X302183Y369000D02*
Y372333D01*
G01Y371500D02*
X302517Y371917D01*
X303017Y372250D01*
X303683Y372333D01*
X304267Y372250D01*
X304767Y371917D01*
X305017Y371333D01*
Y369000D01*
G01X310533Y371917D02*
X309950Y372250D01*
X309450Y372333D01*
X308783Y372167D01*
X308283Y371833D01*
X307950Y371250D01*
X307867Y370667D01*
X307950Y370083D01*
X308283Y369583D01*
X308783Y369167D01*
X309450Y369000D01*
X310033Y369167D01*
X310533Y369500D01*
G01X313550Y371250D02*
X316217D01*
X315967Y371833D01*
X315550Y372167D01*
X314967Y372333D01*
X314383Y372250D01*
X313883Y372000D01*
X313550Y371417D01*
X313383Y370917D01*
Y370417D01*
X313550Y369917D01*
X313967Y369417D01*
X314467Y369083D01*
X315050Y369000D01*
X315633Y369167D01*
X316217Y369667D01*
G01X326000Y374000D02*
Y369000D01*
G01X324833Y372333D02*
X327167D01*
G01X333100Y369000D02*
Y372333D01*
G01Y371750D02*
X332767Y372083D01*
X332267Y372250D01*
X331683Y372333D01*
X331100Y372167D01*
X330600Y371833D01*
X330267Y371333D01*
X330100Y370667D01*
X330267Y370000D01*
X330600Y369500D01*
X331100Y369167D01*
X331683Y369000D01*
X332267Y369083D01*
X332767Y369333D01*
X333100Y369667D01*
G01X335700Y369000D02*
Y374000D01*
G01Y371500D02*
X336117Y372000D01*
X336617Y372250D01*
X337117Y372333D01*
X337867Y372167D01*
X338367Y371833D01*
X338700Y371250D01*
Y370583D01*
X338533Y369917D01*
X338200Y369417D01*
X337617Y369083D01*
X337117Y369000D01*
X336617Y369083D01*
X336117Y369333D01*
X335700Y369750D01*
G01X342800Y369000D02*
Y374000D01*
G01X347150Y371250D02*
X349817D01*
X349567Y371833D01*
X349150Y372167D01*
X348567Y372333D01*
X347983Y372250D01*
X347483Y372000D01*
X347150Y371417D01*
X346983Y370917D01*
Y370417D01*
X347150Y369917D01*
X347567Y369417D01*
X348067Y369083D01*
X348650Y369000D01*
X349233Y369167D01*
X349817Y369667D01*
G01X354000Y368833D02*
X353833Y368917D01*
Y369083D01*
X354000Y369167D01*
X354167Y369083D01*
Y368917D01*
X354000Y368833D01*
G01X268667Y379750D02*
X269250Y379417D01*
X269750Y379333D01*
X270417Y379500D01*
X270917Y379917D01*
X271167Y380667D01*
Y384333D01*
G01Y385667D02*
X271000Y385750D01*
Y385917D01*
X271167Y386000D01*
X271333Y385917D01*
Y385750D01*
X271167Y385667D01*
G01X274183Y384333D02*
Y382000D01*
X274517Y381417D01*
X275017Y381083D01*
X275600Y381000D01*
X276183Y381083D01*
X276683Y381417D01*
X277017Y382000D01*
G01Y381000D02*
Y384333D01*
G01X279783Y381000D02*
Y384333D01*
G01Y383500D02*
X280117Y383917D01*
X280617Y384250D01*
X281283Y384333D01*
X281867Y384250D01*
X282367Y383917D01*
X282617Y383333D01*
Y381000D01*
G01X288133Y383917D02*
X287550Y384250D01*
X287050Y384333D01*
X286383Y384167D01*
X285883Y383833D01*
X285550Y383250D01*
X285467Y382667D01*
X285550Y382083D01*
X285883Y381583D01*
X286383Y381167D01*
X287050Y381000D01*
X287633Y381167D01*
X288133Y381500D01*
G01X292400Y386000D02*
Y381000D01*
G01X291233Y384333D02*
X293567D01*
G01X298000D02*
Y381000D01*
G01Y385667D02*
X297833Y385750D01*
Y385917D01*
X298000Y386000D01*
X298167Y385917D01*
Y385750D01*
X298000Y385667D01*
G01X303600Y381000D02*
X303100Y381083D01*
X302600Y381417D01*
X302267Y382000D01*
X302100Y382667D01*
X302267Y383333D01*
X302600Y383917D01*
X303100Y384250D01*
X303600Y384333D01*
X304100Y384250D01*
X304600Y383917D01*
X304933Y383333D01*
X305017Y382667D01*
X304933Y382000D01*
X304600Y381417D01*
X304100Y381083D01*
X303600Y381000D01*
G01X307783D02*
Y384333D01*
G01Y383500D02*
X308117Y383917D01*
X308617Y384250D01*
X309283Y384333D01*
X309867Y384250D01*
X310367Y383917D01*
X310617Y383333D01*
Y381000D01*
G01X318900D02*
Y386000D01*
G01Y383500D02*
X319317Y384000D01*
X319817Y384250D01*
X320317Y384333D01*
X321067Y384167D01*
X321567Y383833D01*
X321900Y383250D01*
Y382583D01*
X321733Y381917D01*
X321400Y381417D01*
X320817Y381083D01*
X320317Y381000D01*
X319817Y381083D01*
X319317Y381333D01*
X318900Y381750D01*
G01X324750Y383250D02*
X327417D01*
X327167Y383833D01*
X326750Y384167D01*
X326167Y384333D01*
X325583Y384250D01*
X325083Y384000D01*
X324750Y383417D01*
X324583Y382917D01*
Y382417D01*
X324750Y381917D01*
X325167Y381417D01*
X325667Y381083D01*
X326250Y381000D01*
X326833Y381167D01*
X327417Y381667D01*
G01X331600Y381000D02*
Y386000D01*
G01X337200Y381000D02*
X336700Y381083D01*
X336200Y381417D01*
X335867Y382000D01*
X335700Y382667D01*
X335867Y383333D01*
X336200Y383917D01*
X336700Y384250D01*
X337200Y384333D01*
X337700Y384250D01*
X338200Y383917D01*
X338533Y383333D01*
X338617Y382667D01*
X338533Y382000D01*
X338200Y381417D01*
X337700Y381083D01*
X337200Y381000D01*
G01X340717Y384333D02*
X341717Y381000D01*
X342800Y384333D01*
X343883Y381000D01*
X344883Y384333D01*
G01X354000Y386000D02*
Y381000D01*
G01X352833Y384333D02*
X355167D01*
G01X358183Y381000D02*
Y386000D01*
G01Y383583D02*
X358600Y384000D01*
X359017Y384250D01*
X359683Y384333D01*
X360183Y384250D01*
X360767Y383917D01*
X361017Y383417D01*
Y381000D01*
G01X363950Y383250D02*
X366617D01*
X366367Y383833D01*
X365950Y384167D01*
X365367Y384333D01*
X364783Y384250D01*
X364283Y384000D01*
X363950Y383417D01*
X363783Y382917D01*
Y382417D01*
X363950Y381917D01*
X364367Y381417D01*
X364867Y381083D01*
X365450Y381000D01*
X366033Y381167D01*
X366617Y381667D01*
G01X373900Y381000D02*
Y384333D01*
G01Y383417D02*
X374150Y383833D01*
X374567Y384167D01*
X375150Y384333D01*
X375733Y384167D01*
X376150Y383833D01*
X376400Y383417D01*
Y381000D01*
G01Y383417D02*
X376650Y383833D01*
X377067Y384167D01*
X377650Y384333D01*
X378233Y384167D01*
X378650Y383833D01*
X378900Y383333D01*
Y381000D01*
G01X382000Y384333D02*
Y381000D01*
G01Y385667D02*
X381833Y385750D01*
Y385917D01*
X382000Y386000D01*
X382167Y385917D01*
Y385750D01*
X382000Y385667D01*
G01X386183Y381000D02*
Y384333D01*
G01Y383500D02*
X386517Y383917D01*
X387017Y384250D01*
X387683Y384333D01*
X388267Y384250D01*
X388767Y383917D01*
X389017Y383333D01*
Y381000D01*
G01X400133Y383917D02*
X399550Y384250D01*
X399050Y384333D01*
X398383Y384167D01*
X397883Y383833D01*
X397550Y383250D01*
X397467Y382667D01*
X397550Y382083D01*
X397883Y381583D01*
X398383Y381167D01*
X399050Y381000D01*
X399633Y381167D01*
X400133Y381500D01*
G01X404400Y381000D02*
X403900Y381083D01*
X403400Y381417D01*
X403067Y382000D01*
X402900Y382667D01*
X403067Y383333D01*
X403400Y383917D01*
X403900Y384250D01*
X404400Y384333D01*
X404900Y384250D01*
X405400Y383917D01*
X405733Y383333D01*
X405817Y382667D01*
X405733Y382000D01*
X405400Y381417D01*
X404900Y381083D01*
X404400Y381000D01*
G01X408583D02*
Y384333D01*
G01Y383500D02*
X408917Y383917D01*
X409417Y384250D01*
X410083Y384333D01*
X410667Y384250D01*
X411167Y383917D01*
X411417Y383333D01*
Y381000D01*
G01X417100Y386000D02*
Y381000D01*
G01Y381750D02*
X416767Y381333D01*
X416267Y381083D01*
X415683Y381000D01*
X415017Y381167D01*
X414517Y381583D01*
X414183Y382083D01*
X414100Y382667D01*
X414183Y383250D01*
X414517Y383750D01*
X415017Y384167D01*
X415683Y384333D01*
X416267Y384250D01*
X416683Y384083D01*
X417100Y383750D01*
G01X419783Y384333D02*
Y382000D01*
X420117Y381417D01*
X420617Y381083D01*
X421200Y381000D01*
X421783Y381083D01*
X422283Y381417D01*
X422617Y382000D01*
G01Y381000D02*
Y384333D01*
G01X428133Y383917D02*
X427550Y384250D01*
X427050Y384333D01*
X426383Y384167D01*
X425883Y383833D01*
X425550Y383250D01*
X425467Y382667D01*
X425550Y382083D01*
X425883Y381583D01*
X426383Y381167D01*
X427050Y381000D01*
X427633Y381167D01*
X428133Y381500D01*
G01X432400Y386000D02*
Y381000D01*
G01X431233Y384333D02*
X433567D01*
G01X438000Y381000D02*
X437500Y381083D01*
X437000Y381417D01*
X436667Y382000D01*
X436500Y382667D01*
X436667Y383333D01*
X437000Y383917D01*
X437500Y384250D01*
X438000Y384333D01*
X438500Y384250D01*
X439000Y383917D01*
X439333Y383333D01*
X439417Y382667D01*
X439333Y382000D01*
X439000Y381417D01*
X438500Y381083D01*
X438000Y381000D01*
G01X442433D02*
Y384333D01*
G01Y383667D02*
X442850Y384000D01*
X443267Y384250D01*
X443850Y384333D01*
X444267Y384250D01*
X444767Y384000D01*
G01X452717Y384333D02*
X453717Y381000D01*
X454800Y384333D01*
X455883Y381000D01*
X456883Y384333D01*
G01X460400D02*
Y381000D01*
G01Y385667D02*
X460233Y385750D01*
Y385917D01*
X460400Y386000D01*
X460567Y385917D01*
Y385750D01*
X460400Y385667D01*
G01X467500Y386000D02*
Y381000D01*
G01Y381750D02*
X467167Y381333D01*
X466667Y381083D01*
X466083Y381000D01*
X465417Y381167D01*
X464917Y381583D01*
X464583Y382083D01*
X464500Y382667D01*
X464583Y383250D01*
X464917Y383750D01*
X465417Y384167D01*
X466083Y384333D01*
X466667Y384250D01*
X467083Y384083D01*
X467500Y383750D01*
G01X471600Y386000D02*
Y381000D01*
G01X470433Y384333D02*
X472767D01*
G01X475783Y381000D02*
Y386000D01*
G01Y383583D02*
X476200Y384000D01*
X476617Y384250D01*
X477283Y384333D01*
X477783Y384250D01*
X478367Y383917D01*
X478617Y383417D01*
Y381000D01*
G01X487150Y381583D02*
X487567Y381250D01*
X488150Y381000D01*
X488650D01*
X489150Y381167D01*
X489483Y381417D01*
X489650Y381750D01*
X489567Y382250D01*
X489233Y382500D01*
X487733Y383000D01*
X487400Y383583D01*
X487567Y384000D01*
X487900Y384250D01*
X488400Y384333D01*
X488900Y384250D01*
X489400Y384000D01*
G01X492500Y379333D02*
Y384333D01*
G01Y383583D02*
X492917Y384000D01*
X493333Y384250D01*
X494000Y384333D01*
X494583Y384250D01*
X495167Y383833D01*
X495417Y383250D01*
X495500Y382667D01*
X495417Y382083D01*
X495167Y381500D01*
X494667Y381167D01*
X494000Y381000D01*
X493417Y381083D01*
X492833Y381333D01*
X492500Y381667D01*
G01X498350Y383250D02*
X501017D01*
X500767Y383833D01*
X500350Y384167D01*
X499767Y384333D01*
X499183Y384250D01*
X498683Y384000D01*
X498350Y383417D01*
X498183Y382917D01*
Y382417D01*
X498350Y381917D01*
X498767Y381417D01*
X499267Y381083D01*
X499850Y381000D01*
X500433Y381167D01*
X501017Y381667D01*
G01X506533Y383917D02*
X505950Y384250D01*
X505450Y384333D01*
X504783Y384167D01*
X504283Y383833D01*
X503950Y383250D01*
X503867Y382667D01*
X503950Y382083D01*
X504283Y381583D01*
X504783Y381167D01*
X505450Y381000D01*
X506033Y381167D01*
X506533Y381500D01*
G01X510800Y384333D02*
Y381000D01*
G01Y385667D02*
X510633Y385750D01*
Y385917D01*
X510800Y386000D01*
X510967Y385917D01*
Y385750D01*
X510800Y385667D01*
G01X515900Y381000D02*
Y385250D01*
X516067Y385667D01*
X516400Y385917D01*
X516900Y386000D01*
X517400Y385833D01*
X517650Y385417D01*
G01X516650Y384000D02*
X514983D01*
G01X522000Y384333D02*
Y381000D01*
G01Y385667D02*
X521833Y385750D01*
Y385917D01*
X522000Y386000D01*
X522167Y385917D01*
Y385750D01*
X522000Y385667D01*
G01X526350Y383250D02*
X529017D01*
X528767Y383833D01*
X528350Y384167D01*
X527767Y384333D01*
X527183Y384250D01*
X526683Y384000D01*
X526350Y383417D01*
X526183Y382917D01*
Y382417D01*
X526350Y381917D01*
X526767Y381417D01*
X527267Y381083D01*
X527850Y381000D01*
X528433Y381167D01*
X529017Y381667D01*
G01X534700Y386000D02*
Y381000D01*
G01Y381750D02*
X534367Y381333D01*
X533867Y381083D01*
X533283Y381000D01*
X532617Y381167D01*
X532117Y381583D01*
X531783Y382083D01*
X531700Y382667D01*
X531783Y383250D01*
X532117Y383750D01*
X532617Y384167D01*
X533283Y384333D01*
X533867Y384250D01*
X534283Y384083D01*
X534700Y383750D01*
G01X544400Y381000D02*
X543900Y381083D01*
X543400Y381417D01*
X543067Y382000D01*
X542900Y382667D01*
X543067Y383333D01*
X543400Y383917D01*
X543900Y384250D01*
X544400Y384333D01*
X544900Y384250D01*
X545400Y383917D01*
X545733Y383333D01*
X545817Y382667D01*
X545733Y382000D01*
X545400Y381417D01*
X544900Y381083D01*
X544400Y381000D01*
G01X548583D02*
Y384333D01*
G01Y383500D02*
X548917Y383917D01*
X549417Y384250D01*
X550083Y384333D01*
X550667Y384250D01*
X551167Y383917D01*
X551417Y383333D01*
Y381000D01*
G01X561200Y386000D02*
Y381000D01*
G01X560033Y384333D02*
X562367D01*
G01X565383Y381000D02*
Y386000D01*
G01Y383583D02*
X565800Y384000D01*
X566217Y384250D01*
X566883Y384333D01*
X567383Y384250D01*
X567967Y383917D01*
X568217Y383417D01*
Y381000D01*
G01X571150Y383250D02*
X573817D01*
X573567Y383833D01*
X573150Y384167D01*
X572567Y384333D01*
X571983Y384250D01*
X571483Y384000D01*
X571150Y383417D01*
X570983Y382917D01*
Y382417D01*
X571150Y381917D01*
X571567Y381417D01*
X572067Y381083D01*
X572650Y381000D01*
X573233Y381167D01*
X573817Y381667D01*
G01X268250Y391500D02*
Y396500D01*
G01X271750D02*
Y391500D01*
G01Y394000D02*
X268250D01*
G01X275600Y391500D02*
X275100Y391583D01*
X274600Y391917D01*
X274267Y392500D01*
X274100Y393167D01*
X274267Y393833D01*
X274600Y394417D01*
X275100Y394750D01*
X275600Y394833D01*
X276100Y394750D01*
X276600Y394417D01*
X276933Y393833D01*
X277017Y393167D01*
X276933Y392500D01*
X276600Y391917D01*
X276100Y391583D01*
X275600Y391500D01*
G01X279117Y394833D02*
X280117Y391500D01*
X281200Y394833D01*
X282283Y391500D01*
X283283Y394833D01*
G01X285550Y393750D02*
X288217D01*
X287967Y394333D01*
X287550Y394667D01*
X286967Y394833D01*
X286383Y394750D01*
X285883Y394500D01*
X285550Y393917D01*
X285383Y393417D01*
Y392917D01*
X285550Y392417D01*
X285967Y391917D01*
X286467Y391583D01*
X287050Y391500D01*
X287633Y391667D01*
X288217Y392167D01*
G01X290900Y394833D02*
X292400Y391500D01*
X293900Y394833D01*
G01X296750Y393750D02*
X299417D01*
X299167Y394333D01*
X298750Y394667D01*
X298167Y394833D01*
X297583Y394750D01*
X297083Y394500D01*
X296750Y393917D01*
X296583Y393417D01*
Y392917D01*
X296750Y392417D01*
X297167Y391917D01*
X297667Y391583D01*
X298250Y391500D01*
X298833Y391667D01*
X299417Y392167D01*
G01X302433Y391500D02*
Y394833D01*
G01Y394167D02*
X302850Y394500D01*
X303267Y394750D01*
X303850Y394833D01*
X304267Y394750D01*
X304767Y394500D01*
G01X309033Y390583D02*
X309367Y391667D01*
G01X314800Y396500D02*
Y391500D01*
G01X313633Y394833D02*
X315967D01*
G01X318983Y391500D02*
Y396500D01*
G01Y394083D02*
X319400Y394500D01*
X319817Y394750D01*
X320483Y394833D01*
X320983Y394750D01*
X321567Y394417D01*
X321817Y393917D01*
Y391500D01*
G01X324750Y393750D02*
X327417D01*
X327167Y394333D01*
X326750Y394667D01*
X326167Y394833D01*
X325583Y394750D01*
X325083Y394500D01*
X324750Y393917D01*
X324583Y393417D01*
Y392917D01*
X324750Y392417D01*
X325167Y391917D01*
X325667Y391583D01*
X326250Y391500D01*
X326833Y391667D01*
X327417Y392167D01*
G01X337200Y396500D02*
Y391500D01*
G01X336033Y394833D02*
X338367D01*
G01X344300Y391500D02*
Y394833D01*
G01Y394250D02*
X343967Y394583D01*
X343467Y394750D01*
X342883Y394833D01*
X342300Y394667D01*
X341800Y394333D01*
X341467Y393833D01*
X341300Y393167D01*
X341467Y392500D01*
X341800Y392000D01*
X342300Y391667D01*
X342883Y391500D01*
X343467Y391583D01*
X343967Y391833D01*
X344300Y392167D01*
G01X346983Y391500D02*
Y394833D01*
G01Y394000D02*
X347317Y394417D01*
X347817Y394750D01*
X348483Y394833D01*
X349067Y394750D01*
X349567Y394417D01*
X349817Y393833D01*
Y391500D01*
G01X352833Y390250D02*
X353417Y389917D01*
X354083Y389833D01*
X354667Y389917D01*
X355167Y390333D01*
X355500Y390917D01*
Y394833D01*
G01Y394167D02*
X355167Y394500D01*
X354667Y394750D01*
X354083Y394833D01*
X353417Y394667D01*
X353000Y394333D01*
X352667Y393750D01*
X352500Y393167D01*
X352583Y392667D01*
X352917Y392083D01*
X353417Y391667D01*
X354083Y391500D01*
X354583Y391583D01*
X355167Y391917D01*
X355500Y392250D01*
G01X358350Y393750D02*
X361017D01*
X360767Y394333D01*
X360350Y394667D01*
X359767Y394833D01*
X359183Y394750D01*
X358683Y394500D01*
X358350Y393917D01*
X358183Y393417D01*
Y392917D01*
X358350Y392417D01*
X358767Y391917D01*
X359267Y391583D01*
X359850Y391500D01*
X360433Y391667D01*
X361017Y392167D01*
G01X363783Y391500D02*
Y394833D01*
G01Y394000D02*
X364117Y394417D01*
X364617Y394750D01*
X365283Y394833D01*
X365867Y394750D01*
X366367Y394417D01*
X366617Y393833D01*
Y391500D01*
G01X372133Y394417D02*
X371550Y394750D01*
X371050Y394833D01*
X370383Y394667D01*
X369883Y394333D01*
X369550Y393750D01*
X369467Y393167D01*
X369550Y392583D01*
X369883Y392083D01*
X370383Y391667D01*
X371050Y391500D01*
X371633Y391667D01*
X372133Y392000D01*
G01X374650Y390000D02*
X375150Y389833D01*
X375817Y390000D01*
X376233Y390333D01*
X376567Y390750D01*
X377067Y392083D01*
X378150Y394833D01*
G01X375483D02*
X377067Y392083D01*
G01X386350D02*
X386767Y391750D01*
X387350Y391500D01*
X387850D01*
X388350Y391667D01*
X388683Y391917D01*
X388850Y392250D01*
X388767Y392750D01*
X388433Y393000D01*
X386933Y393500D01*
X386600Y394083D01*
X386767Y394500D01*
X387100Y394750D01*
X387600Y394833D01*
X388100Y394750D01*
X388600Y394500D01*
G01X391783Y391500D02*
Y396500D01*
G01Y394083D02*
X392200Y394500D01*
X392617Y394750D01*
X393283Y394833D01*
X393783Y394750D01*
X394367Y394417D01*
X394617Y393917D01*
Y391500D01*
G01X398800D02*
X398300Y391583D01*
X397800Y391917D01*
X397467Y392500D01*
X397300Y393167D01*
X397467Y393833D01*
X397800Y394417D01*
X398300Y394750D01*
X398800Y394833D01*
X399300Y394750D01*
X399800Y394417D01*
X400133Y393833D01*
X400217Y393167D01*
X400133Y392500D01*
X399800Y391917D01*
X399300Y391583D01*
X398800Y391500D01*
G01X402983Y394833D02*
Y392500D01*
X403317Y391917D01*
X403817Y391583D01*
X404400Y391500D01*
X404983Y391583D01*
X405483Y391917D01*
X405817Y392500D01*
G01Y391500D02*
Y394833D01*
G01X410000Y391500D02*
Y396500D01*
G01X417100D02*
Y391500D01*
G01Y392250D02*
X416767Y391833D01*
X416267Y391583D01*
X415683Y391500D01*
X415017Y391667D01*
X414517Y392083D01*
X414183Y392583D01*
X414100Y393167D01*
X414183Y393750D01*
X414517Y394250D01*
X415017Y394667D01*
X415683Y394833D01*
X416267Y394750D01*
X416683Y394583D01*
X417100Y394250D01*
G01X425383Y391500D02*
Y394833D01*
G01Y394000D02*
X425717Y394417D01*
X426217Y394750D01*
X426883Y394833D01*
X427467Y394750D01*
X427967Y394417D01*
X428217Y393833D01*
Y391500D01*
G01X432400D02*
X431900Y391583D01*
X431400Y391917D01*
X431067Y392500D01*
X430900Y393167D01*
X431067Y393833D01*
X431400Y394417D01*
X431900Y394750D01*
X432400Y394833D01*
X432900Y394750D01*
X433400Y394417D01*
X433733Y393833D01*
X433817Y393167D01*
X433733Y392500D01*
X433400Y391917D01*
X432900Y391583D01*
X432400Y391500D01*
G01X438000Y396500D02*
Y391500D01*
G01X436833Y394833D02*
X439167D01*
G01X448033Y391500D02*
Y394833D01*
G01Y394167D02*
X448450Y394500D01*
X448867Y394750D01*
X449450Y394833D01*
X449867Y394750D01*
X450367Y394500D01*
G01X453550Y393750D02*
X456217D01*
X455967Y394333D01*
X455550Y394667D01*
X454967Y394833D01*
X454383Y394750D01*
X453883Y394500D01*
X453550Y393917D01*
X453383Y393417D01*
Y392917D01*
X453550Y392417D01*
X453967Y391917D01*
X454467Y391583D01*
X455050Y391500D01*
X455633Y391667D01*
X456217Y392167D01*
G01X461900Y396500D02*
Y391500D01*
G01Y392250D02*
X461567Y391833D01*
X461067Y391583D01*
X460483Y391500D01*
X459817Y391667D01*
X459317Y392083D01*
X458983Y392583D01*
X458900Y393167D01*
X458983Y393750D01*
X459317Y394250D01*
X459817Y394667D01*
X460483Y394833D01*
X461067Y394750D01*
X461483Y394583D01*
X461900Y394250D01*
G01X464583Y394833D02*
Y392500D01*
X464917Y391917D01*
X465417Y391583D01*
X466000Y391500D01*
X466583Y391583D01*
X467083Y391917D01*
X467417Y392500D01*
G01Y391500D02*
Y394833D01*
G01X472933Y394417D02*
X472350Y394750D01*
X471850Y394833D01*
X471183Y394667D01*
X470683Y394333D01*
X470350Y393750D01*
X470267Y393167D01*
X470350Y392583D01*
X470683Y392083D01*
X471183Y391667D01*
X471850Y391500D01*
X472433Y391667D01*
X472933Y392000D01*
G01X475950Y393750D02*
X478617D01*
X478367Y394333D01*
X477950Y394667D01*
X477367Y394833D01*
X476783Y394750D01*
X476283Y394500D01*
X475950Y393917D01*
X475783Y393417D01*
Y392917D01*
X475950Y392417D01*
X476367Y391917D01*
X476867Y391583D01*
X477450Y391500D01*
X478033Y391667D01*
X478617Y392167D01*
G01X488400Y396500D02*
Y391500D01*
G01X487233Y394833D02*
X489567D01*
G01X492583Y391500D02*
Y396500D01*
G01Y394083D02*
X493000Y394500D01*
X493417Y394750D01*
X494083Y394833D01*
X494583Y394750D01*
X495167Y394417D01*
X495417Y393917D01*
Y391500D01*
G01X498350Y393750D02*
X501017D01*
X500767Y394333D01*
X500350Y394667D01*
X499767Y394833D01*
X499183Y394750D01*
X498683Y394500D01*
X498350Y393917D01*
X498183Y393417D01*
Y392917D01*
X498350Y392417D01*
X498767Y391917D01*
X499267Y391583D01*
X499850Y391500D01*
X500433Y391667D01*
X501017Y392167D01*
G01X510800Y391500D02*
Y396500D01*
G01X517900Y391500D02*
Y394833D01*
G01Y394250D02*
X517567Y394583D01*
X517067Y394750D01*
X516483Y394833D01*
X515900Y394667D01*
X515400Y394333D01*
X515067Y393833D01*
X514900Y393167D01*
X515067Y392500D01*
X515400Y392000D01*
X515900Y391667D01*
X516483Y391500D01*
X517067Y391583D01*
X517567Y391833D01*
X517900Y392167D01*
G01X520583Y391500D02*
Y394833D01*
G01Y394000D02*
X520917Y394417D01*
X521417Y394750D01*
X522083Y394833D01*
X522667Y394750D01*
X523167Y394417D01*
X523417Y393833D01*
Y391500D01*
G01X529100Y396500D02*
Y391500D01*
G01Y392250D02*
X528767Y391833D01*
X528267Y391583D01*
X527683Y391500D01*
X527017Y391667D01*
X526517Y392083D01*
X526183Y392583D01*
X526100Y393167D01*
X526183Y393750D01*
X526517Y394250D01*
X527017Y394667D01*
X527683Y394833D01*
X528267Y394750D01*
X528683Y394583D01*
X529100Y394250D01*
G01X531700Y391333D02*
X534700Y396500D01*
G01X540133Y394417D02*
X539550Y394750D01*
X539050Y394833D01*
X538383Y394667D01*
X537883Y394333D01*
X537550Y393750D01*
X537467Y393167D01*
X537550Y392583D01*
X537883Y392083D01*
X538383Y391667D01*
X539050Y391500D01*
X539633Y391667D01*
X540133Y392000D01*
G01X544400Y391500D02*
X543900Y391583D01*
X543400Y391917D01*
X543067Y392500D01*
X542900Y393167D01*
X543067Y393833D01*
X543400Y394417D01*
X543900Y394750D01*
X544400Y394833D01*
X544900Y394750D01*
X545400Y394417D01*
X545733Y393833D01*
X545817Y393167D01*
X545733Y392500D01*
X545400Y391917D01*
X544900Y391583D01*
X544400Y391500D01*
G01X548583D02*
Y394833D01*
G01Y394000D02*
X548917Y394417D01*
X549417Y394750D01*
X550083Y394833D01*
X550667Y394750D01*
X551167Y394417D01*
X551417Y393833D01*
Y391500D01*
G01X557100Y396500D02*
Y391500D01*
G01Y392250D02*
X556767Y391833D01*
X556267Y391583D01*
X555683Y391500D01*
X555017Y391667D01*
X554517Y392083D01*
X554183Y392583D01*
X554100Y393167D01*
X554183Y393750D01*
X554517Y394250D01*
X555017Y394667D01*
X555683Y394833D01*
X556267Y394750D01*
X556683Y394583D01*
X557100Y394250D01*
G01X559783Y394833D02*
Y392500D01*
X560117Y391917D01*
X560617Y391583D01*
X561200Y391500D01*
X561783Y391583D01*
X562283Y391917D01*
X562617Y392500D01*
G01Y391500D02*
Y394833D01*
G01X568133Y394417D02*
X567550Y394750D01*
X567050Y394833D01*
X566383Y394667D01*
X565883Y394333D01*
X565550Y393750D01*
X565467Y393167D01*
X565550Y392583D01*
X565883Y392083D01*
X566383Y391667D01*
X567050Y391500D01*
X567633Y391667D01*
X568133Y392000D01*
G01X572400Y396500D02*
Y391500D01*
G01X571233Y394833D02*
X573567D01*
G01X578000Y391500D02*
X577500Y391583D01*
X577000Y391917D01*
X576667Y392500D01*
X576500Y393167D01*
X576667Y393833D01*
X577000Y394417D01*
X577500Y394750D01*
X578000Y394833D01*
X578500Y394750D01*
X579000Y394417D01*
X579333Y393833D01*
X579417Y393167D01*
X579333Y392500D01*
X579000Y391917D01*
X578500Y391583D01*
X578000Y391500D01*
G01X582433D02*
Y394833D01*
G01Y394167D02*
X582850Y394500D01*
X583267Y394750D01*
X583850Y394833D01*
X584267Y394750D01*
X584767Y394500D01*
G01X271500Y402000D02*
Y405333D01*
G01Y404750D02*
X271167Y405083D01*
X270667Y405250D01*
X270083Y405333D01*
X269500Y405167D01*
X269000Y404833D01*
X268667Y404333D01*
X268500Y403667D01*
X268667Y403000D01*
X269000Y402500D01*
X269500Y402167D01*
X270083Y402000D01*
X270667Y402083D01*
X271167Y402333D01*
X271500Y402667D01*
G01X276933Y404917D02*
X276350Y405250D01*
X275850Y405333D01*
X275183Y405167D01*
X274683Y404833D01*
X274350Y404250D01*
X274267Y403667D01*
X274350Y403083D01*
X274683Y402583D01*
X275183Y402167D01*
X275850Y402000D01*
X276433Y402167D01*
X276933Y402500D01*
G01X282533Y404917D02*
X281950Y405250D01*
X281450Y405333D01*
X280783Y405167D01*
X280283Y404833D01*
X279950Y404250D01*
X279867Y403667D01*
X279950Y403083D01*
X280283Y402583D01*
X280783Y402167D01*
X281450Y402000D01*
X282033Y402167D01*
X282533Y402500D01*
G01X285550Y404250D02*
X288217D01*
X287967Y404833D01*
X287550Y405167D01*
X286967Y405333D01*
X286383Y405250D01*
X285883Y405000D01*
X285550Y404417D01*
X285383Y403917D01*
Y403417D01*
X285550Y402917D01*
X285967Y402417D01*
X286467Y402083D01*
X287050Y402000D01*
X287633Y402167D01*
X288217Y402667D01*
G01X290900Y400333D02*
Y405333D01*
G01Y404583D02*
X291317Y405000D01*
X291733Y405250D01*
X292400Y405333D01*
X292983Y405250D01*
X293567Y404833D01*
X293817Y404250D01*
X293900Y403667D01*
X293817Y403083D01*
X293567Y402500D01*
X293067Y402167D01*
X292400Y402000D01*
X291817Y402083D01*
X291233Y402333D01*
X290900Y402667D01*
G01X298000Y407000D02*
Y402000D01*
G01X296833Y405333D02*
X299167D01*
G01X305100Y402000D02*
Y405333D01*
G01Y404750D02*
X304767Y405083D01*
X304267Y405250D01*
X303683Y405333D01*
X303100Y405167D01*
X302600Y404833D01*
X302267Y404333D01*
X302100Y403667D01*
X302267Y403000D01*
X302600Y402500D01*
X303100Y402167D01*
X303683Y402000D01*
X304267Y402083D01*
X304767Y402333D01*
X305100Y402667D01*
G01X307700Y402000D02*
Y407000D01*
G01Y404500D02*
X308117Y405000D01*
X308617Y405250D01*
X309117Y405333D01*
X309867Y405167D01*
X310367Y404833D01*
X310700Y404250D01*
Y403583D01*
X310533Y402917D01*
X310200Y402417D01*
X309617Y402083D01*
X309117Y402000D01*
X308617Y402083D01*
X308117Y402333D01*
X307700Y402750D01*
G01X314800Y402000D02*
Y407000D01*
G01X319150Y404250D02*
X321817D01*
X321567Y404833D01*
X321150Y405167D01*
X320567Y405333D01*
X319983Y405250D01*
X319483Y405000D01*
X319150Y404417D01*
X318983Y403917D01*
Y403417D01*
X319150Y402917D01*
X319567Y402417D01*
X320067Y402083D01*
X320650Y402000D01*
X321233Y402167D01*
X321817Y402667D01*
G01X326000Y401833D02*
X325833Y401917D01*
Y402083D01*
X326000Y402167D01*
X326167Y402083D01*
Y401917D01*
X326000Y401833D01*
G01X270000Y417500D02*
Y412500D01*
G01X268083Y417500D02*
X271917D01*
G01X274183Y412500D02*
Y417500D01*
G01Y415083D02*
X274600Y415500D01*
X275017Y415750D01*
X275683Y415833D01*
X276183Y415750D01*
X276767Y415417D01*
X277017Y414917D01*
Y412500D01*
G01X279950Y414750D02*
X282617D01*
X282367Y415333D01*
X281950Y415667D01*
X281367Y415833D01*
X280783Y415750D01*
X280283Y415500D01*
X279950Y414917D01*
X279783Y414417D01*
Y413917D01*
X279950Y413417D01*
X280367Y412917D01*
X280867Y412583D01*
X281450Y412500D01*
X282033Y412667D01*
X282617Y413167D01*
G01X290900Y412500D02*
Y417500D01*
G01Y415000D02*
X291317Y415500D01*
X291817Y415750D01*
X292317Y415833D01*
X293067Y415667D01*
X293567Y415333D01*
X293900Y414750D01*
Y414083D01*
X293733Y413417D01*
X293400Y412917D01*
X292817Y412583D01*
X292317Y412500D01*
X291817Y412583D01*
X291317Y412833D01*
X290900Y413250D01*
G01X296833Y412500D02*
Y415833D01*
G01Y415167D02*
X297250Y415500D01*
X297667Y415750D01*
X298250Y415833D01*
X298667Y415750D01*
X299167Y415500D01*
G01X302350Y414750D02*
X305017D01*
X304767Y415333D01*
X304350Y415667D01*
X303767Y415833D01*
X303183Y415750D01*
X302683Y415500D01*
X302350Y414917D01*
X302183Y414417D01*
Y413917D01*
X302350Y413417D01*
X302767Y412917D01*
X303267Y412583D01*
X303850Y412500D01*
X304433Y412667D01*
X305017Y413167D01*
G01X310700Y412500D02*
Y415833D01*
G01Y415250D02*
X310367Y415583D01*
X309867Y415750D01*
X309283Y415833D01*
X308700Y415667D01*
X308200Y415333D01*
X307867Y414833D01*
X307700Y414167D01*
X307867Y413500D01*
X308200Y413000D01*
X308700Y412667D01*
X309283Y412500D01*
X309867Y412583D01*
X310367Y412833D01*
X310700Y413167D01*
G01X313383Y412500D02*
Y417500D01*
G01X316050Y415833D02*
X313383Y413917D01*
G01X314467Y414667D02*
X316217Y412500D01*
G01X320400D02*
X319900Y412583D01*
X319400Y412917D01*
X319067Y413500D01*
X318900Y414167D01*
X319067Y414833D01*
X319400Y415417D01*
X319900Y415750D01*
X320400Y415833D01*
X320900Y415750D01*
X321400Y415417D01*
X321733Y414833D01*
X321817Y414167D01*
X321733Y413500D01*
X321400Y412917D01*
X320900Y412583D01*
X320400Y412500D01*
G01X324583Y415833D02*
Y413500D01*
X324917Y412917D01*
X325417Y412583D01*
X326000Y412500D01*
X326583Y412583D01*
X327083Y412917D01*
X327417Y413500D01*
G01Y412500D02*
Y415833D01*
G01X331600Y417500D02*
Y412500D01*
G01X330433Y415833D02*
X332767D01*
G01X342800D02*
Y412500D01*
G01Y417167D02*
X342633Y417250D01*
Y417417D01*
X342800Y417500D01*
X342967Y417417D01*
Y417250D01*
X342800Y417167D01*
G01X347150Y413083D02*
X347567Y412750D01*
X348150Y412500D01*
X348650D01*
X349150Y412667D01*
X349483Y412917D01*
X349650Y413250D01*
X349567Y413750D01*
X349233Y414000D01*
X347733Y414500D01*
X347400Y415083D01*
X347567Y415500D01*
X347900Y415750D01*
X348400Y415833D01*
X348900Y415750D01*
X349400Y415500D01*
G01X358183Y412500D02*
Y415833D01*
G01Y415000D02*
X358517Y415417D01*
X359017Y415750D01*
X359683Y415833D01*
X360267Y415750D01*
X360767Y415417D01*
X361017Y414833D01*
Y412500D01*
G01X365200D02*
X364700Y412583D01*
X364200Y412917D01*
X363867Y413500D01*
X363700Y414167D01*
X363867Y414833D01*
X364200Y415417D01*
X364700Y415750D01*
X365200Y415833D01*
X365700Y415750D01*
X366200Y415417D01*
X366533Y414833D01*
X366617Y414167D01*
X366533Y413500D01*
X366200Y412917D01*
X365700Y412583D01*
X365200Y412500D01*
G01X370800Y417500D02*
Y412500D01*
G01X369633Y415833D02*
X371967D01*
G01X383500Y412500D02*
Y415833D01*
G01Y415250D02*
X383167Y415583D01*
X382667Y415750D01*
X382083Y415833D01*
X381500Y415667D01*
X381000Y415333D01*
X380667Y414833D01*
X380500Y414167D01*
X380667Y413500D01*
X381000Y413000D01*
X381500Y412667D01*
X382083Y412500D01*
X382667Y412583D01*
X383167Y412833D01*
X383500Y413167D01*
G01X387600Y412500D02*
Y417500D01*
G01X393200Y412500D02*
Y417500D01*
G01X398800Y412500D02*
X398300Y412583D01*
X397800Y412917D01*
X397467Y413500D01*
X397300Y414167D01*
X397467Y414833D01*
X397800Y415417D01*
X398300Y415750D01*
X398800Y415833D01*
X399300Y415750D01*
X399800Y415417D01*
X400133Y414833D01*
X400217Y414167D01*
X400133Y413500D01*
X399800Y412917D01*
X399300Y412583D01*
X398800Y412500D01*
G01X402317Y415833D02*
X403317Y412500D01*
X404400Y415833D01*
X405483Y412500D01*
X406483Y415833D01*
G01X408750Y414750D02*
X411417D01*
X411167Y415333D01*
X410750Y415667D01*
X410167Y415833D01*
X409583Y415750D01*
X409083Y415500D01*
X408750Y414917D01*
X408583Y414417D01*
Y413917D01*
X408750Y413417D01*
X409167Y412917D01*
X409667Y412583D01*
X410250Y412500D01*
X410833Y412667D01*
X411417Y413167D01*
G01X417100Y417500D02*
Y412500D01*
G01Y413250D02*
X416767Y412833D01*
X416267Y412583D01*
X415683Y412500D01*
X415017Y412667D01*
X414517Y413083D01*
X414183Y413583D01*
X414100Y414167D01*
X414183Y414750D01*
X414517Y415250D01*
X415017Y415667D01*
X415683Y415833D01*
X416267Y415750D01*
X416683Y415583D01*
X417100Y415250D01*
G01X421033Y411583D02*
X421367Y412667D01*
G01X436500Y412500D02*
Y417500D01*
G01Y415000D02*
X436917Y415500D01*
X437417Y415750D01*
X437917Y415833D01*
X438667Y415667D01*
X439167Y415333D01*
X439500Y414750D01*
Y414083D01*
X439333Y413417D01*
X439000Y412917D01*
X438417Y412583D01*
X437917Y412500D01*
X437417Y412583D01*
X436917Y412833D01*
X436500Y413250D01*
G01X442183Y415833D02*
Y413500D01*
X442517Y412917D01*
X443017Y412583D01*
X443600Y412500D01*
X444183Y412583D01*
X444683Y412917D01*
X445017Y413500D01*
G01Y412500D02*
Y415833D01*
G01X449200Y417500D02*
Y412500D01*
G01X448033Y415833D02*
X450367D01*
G01X461900Y412500D02*
Y415833D01*
G01Y415250D02*
X461567Y415583D01*
X461067Y415750D01*
X460483Y415833D01*
X459900Y415667D01*
X459400Y415333D01*
X459067Y414833D01*
X458900Y414167D01*
X459067Y413500D01*
X459400Y413000D01*
X459900Y412667D01*
X460483Y412500D01*
X461067Y412583D01*
X461567Y412833D01*
X461900Y413167D01*
G01X464583Y412500D02*
Y415833D01*
G01Y415000D02*
X464917Y415417D01*
X465417Y415750D01*
X466083Y415833D01*
X466667Y415750D01*
X467167Y415417D01*
X467417Y414833D01*
Y412500D01*
G01X470183D02*
Y415833D01*
G01Y415000D02*
X470517Y415417D01*
X471017Y415750D01*
X471683Y415833D01*
X472267Y415750D01*
X472767Y415417D01*
X473017Y414833D01*
Y412500D01*
G01X475783Y415833D02*
Y413500D01*
X476117Y412917D01*
X476617Y412583D01*
X477200Y412500D01*
X477783Y412583D01*
X478283Y412917D01*
X478617Y413500D01*
G01Y412500D02*
Y415833D01*
G01X484300Y412500D02*
Y415833D01*
G01Y415250D02*
X483967Y415583D01*
X483467Y415750D01*
X482883Y415833D01*
X482300Y415667D01*
X481800Y415333D01*
X481467Y414833D01*
X481300Y414167D01*
X481467Y413500D01*
X481800Y413000D01*
X482300Y412667D01*
X482883Y412500D01*
X483467Y412583D01*
X483967Y412833D01*
X484300Y413167D01*
G01X488400Y412500D02*
Y417500D01*
G01X498433Y412500D02*
Y415833D01*
G01Y415167D02*
X498850Y415500D01*
X499267Y415750D01*
X499850Y415833D01*
X500267Y415750D01*
X500767Y415500D01*
G01X505200Y415833D02*
Y412500D01*
G01Y417167D02*
X505033Y417250D01*
Y417417D01*
X505200Y417500D01*
X505367Y417417D01*
Y417250D01*
X505200Y417167D01*
G01X509383Y412500D02*
Y415833D01*
G01Y415000D02*
X509717Y415417D01*
X510217Y415750D01*
X510883Y415833D01*
X511467Y415750D01*
X511967Y415417D01*
X512217Y414833D01*
Y412500D01*
G01X515233Y411250D02*
X515817Y410917D01*
X516483Y410833D01*
X517067Y410917D01*
X517567Y411333D01*
X517900Y411917D01*
Y415833D01*
G01Y415167D02*
X517567Y415500D01*
X517067Y415750D01*
X516483Y415833D01*
X515817Y415667D01*
X515400Y415333D01*
X515067Y414750D01*
X514900Y414167D01*
X514983Y413667D01*
X515317Y413083D01*
X515817Y412667D01*
X516483Y412500D01*
X516983Y412583D01*
X517567Y412917D01*
X517900Y413250D01*
G01X527600Y417500D02*
Y412500D01*
G01X526433Y415833D02*
X528767D01*
G01X534700Y412500D02*
Y415833D01*
G01Y415250D02*
X534367Y415583D01*
X533867Y415750D01*
X533283Y415833D01*
X532700Y415667D01*
X532200Y415333D01*
X531867Y414833D01*
X531700Y414167D01*
X531867Y413500D01*
X532200Y413000D01*
X532700Y412667D01*
X533283Y412500D01*
X533867Y412583D01*
X534367Y412833D01*
X534700Y413167D01*
G01X537383Y412500D02*
Y415833D01*
G01Y415000D02*
X537717Y415417D01*
X538217Y415750D01*
X538883Y415833D01*
X539467Y415750D01*
X539967Y415417D01*
X540217Y414833D01*
Y412500D01*
G01X543233Y411250D02*
X543817Y410917D01*
X544483Y410833D01*
X545067Y410917D01*
X545567Y411333D01*
X545900Y411917D01*
Y415833D01*
G01Y415167D02*
X545567Y415500D01*
X545067Y415750D01*
X544483Y415833D01*
X543817Y415667D01*
X543400Y415333D01*
X543067Y414750D01*
X542900Y414167D01*
X542983Y413667D01*
X543317Y413083D01*
X543817Y412667D01*
X544483Y412500D01*
X544983Y412583D01*
X545567Y412917D01*
X545900Y413250D01*
G01X548750Y414750D02*
X551417D01*
X551167Y415333D01*
X550750Y415667D01*
X550167Y415833D01*
X549583Y415750D01*
X549083Y415500D01*
X548750Y414917D01*
X548583Y414417D01*
Y413917D01*
X548750Y413417D01*
X549167Y412917D01*
X549667Y412583D01*
X550250Y412500D01*
X550833Y412667D01*
X551417Y413167D01*
G01X554183Y412500D02*
Y415833D01*
G01Y415000D02*
X554517Y415417D01*
X555017Y415750D01*
X555683Y415833D01*
X556267Y415750D01*
X556767Y415417D01*
X557017Y414833D01*
Y412500D01*
G01X562533Y415417D02*
X561950Y415750D01*
X561450Y415833D01*
X560783Y415667D01*
X560283Y415333D01*
X559950Y414750D01*
X559867Y414167D01*
X559950Y413583D01*
X560283Y413083D01*
X560783Y412667D01*
X561450Y412500D01*
X562033Y412667D01*
X562533Y413000D01*
G01X565050Y411000D02*
X565550Y410833D01*
X566217Y411000D01*
X566633Y411333D01*
X566967Y411750D01*
X567467Y413083D01*
X568550Y415833D01*
G01X565883D02*
X567467Y413083D01*
G01X578000Y415833D02*
Y412500D01*
G01Y417167D02*
X577833Y417250D01*
Y417417D01*
X578000Y417500D01*
X578167Y417417D01*
Y417250D01*
X578000Y417167D01*
G01X582350Y413083D02*
X582767Y412750D01*
X583350Y412500D01*
X583850D01*
X584350Y412667D01*
X584683Y412917D01*
X584850Y413250D01*
X584767Y413750D01*
X584433Y414000D01*
X582933Y414500D01*
X582600Y415083D01*
X582767Y415500D01*
X583100Y415750D01*
X583600Y415833D01*
X584100Y415750D01*
X584600Y415500D01*
G01X262500Y397000D02*
Y679000D01*
G01X273000Y437500D02*
Y432500D01*
G01Y433250D02*
X272667Y432833D01*
X272167Y432583D01*
X271583Y432500D01*
X270917Y432667D01*
X270417Y433083D01*
X270083Y433583D01*
X270000Y434167D01*
X270083Y434750D01*
X270417Y435250D01*
X270917Y435667D01*
X271583Y435833D01*
X272167Y435750D01*
X272583Y435583D01*
X273000Y435250D01*
G01X275850Y434750D02*
X278517D01*
X278267Y435333D01*
X277850Y435667D01*
X277267Y435833D01*
X276683Y435750D01*
X276183Y435500D01*
X275850Y434917D01*
X275683Y434417D01*
Y433917D01*
X275850Y433417D01*
X276267Y432917D01*
X276767Y432583D01*
X277350Y432500D01*
X277933Y432667D01*
X278517Y433167D01*
G01X281200Y430833D02*
Y435833D01*
G01Y435083D02*
X281617Y435500D01*
X282033Y435750D01*
X282700Y435833D01*
X283283Y435750D01*
X283867Y435333D01*
X284117Y434750D01*
X284200Y434167D01*
X284117Y433583D01*
X283867Y433000D01*
X283367Y432667D01*
X282700Y432500D01*
X282117Y432583D01*
X281533Y432833D01*
X281200Y433167D01*
G01X288300Y437500D02*
Y432500D01*
G01X287133Y435833D02*
X289467D01*
G01X292483Y432500D02*
Y437500D01*
G01Y435083D02*
X292900Y435500D01*
X293317Y435750D01*
X293983Y435833D01*
X294483Y435750D01*
X295067Y435417D01*
X295317Y434917D01*
Y432500D01*
G01X305100Y437500D02*
Y432500D01*
G01X303933Y435833D02*
X306267D01*
G01X310700Y432500D02*
X310200Y432583D01*
X309700Y432917D01*
X309367Y433500D01*
X309200Y434167D01*
X309367Y434833D01*
X309700Y435417D01*
X310200Y435750D01*
X310700Y435833D01*
X311200Y435750D01*
X311700Y435417D01*
X312033Y434833D01*
X312117Y434167D01*
X312033Y433500D01*
X311700Y432917D01*
X311200Y432583D01*
X310700Y432500D01*
G01X316300D02*
Y437500D01*
G01X320650Y434750D02*
X323317D01*
X323067Y435333D01*
X322650Y435667D01*
X322067Y435833D01*
X321483Y435750D01*
X320983Y435500D01*
X320650Y434917D01*
X320483Y434417D01*
Y433917D01*
X320650Y433417D01*
X321067Y432917D01*
X321567Y432583D01*
X322150Y432500D01*
X322733Y432667D01*
X323317Y433167D01*
G01X326333Y432500D02*
Y435833D01*
G01Y435167D02*
X326750Y435500D01*
X327167Y435750D01*
X327750Y435833D01*
X328167Y435750D01*
X328667Y435500D01*
G01X334600Y432500D02*
Y435833D01*
G01Y435250D02*
X334267Y435583D01*
X333767Y435750D01*
X333183Y435833D01*
X332600Y435667D01*
X332100Y435333D01*
X331767Y434833D01*
X331600Y434167D01*
X331767Y433500D01*
X332100Y433000D01*
X332600Y432667D01*
X333183Y432500D01*
X333767Y432583D01*
X334267Y432833D01*
X334600Y433167D01*
G01X337283Y432500D02*
Y435833D01*
G01Y435000D02*
X337617Y435417D01*
X338117Y435750D01*
X338783Y435833D01*
X339367Y435750D01*
X339867Y435417D01*
X340117Y434833D01*
Y432500D01*
G01X345633Y435417D02*
X345050Y435750D01*
X344550Y435833D01*
X343883Y435667D01*
X343383Y435333D01*
X343050Y434750D01*
X342967Y434167D01*
X343050Y433583D01*
X343383Y433083D01*
X343883Y432667D01*
X344550Y432500D01*
X345133Y432667D01*
X345633Y433000D01*
G01X348650Y434750D02*
X351317D01*
X351067Y435333D01*
X350650Y435667D01*
X350067Y435833D01*
X349483Y435750D01*
X348983Y435500D01*
X348650Y434917D01*
X348483Y434417D01*
Y433917D01*
X348650Y433417D01*
X349067Y432917D01*
X349567Y432583D01*
X350150Y432500D01*
X350733Y432667D01*
X351317Y433167D01*
G01X270750Y453500D02*
Y458500D01*
G01X274250D02*
Y453500D01*
G01Y456000D02*
X270750D01*
G01X278100Y453500D02*
X277600Y453583D01*
X277100Y453917D01*
X276767Y454500D01*
X276600Y455167D01*
X276767Y455833D01*
X277100Y456417D01*
X277600Y456750D01*
X278100Y456833D01*
X278600Y456750D01*
X279100Y456417D01*
X279433Y455833D01*
X279517Y455167D01*
X279433Y454500D01*
X279100Y453917D01*
X278600Y453583D01*
X278100Y453500D01*
G01X283700D02*
Y458500D01*
G01X288050Y455750D02*
X290717D01*
X290467Y456333D01*
X290050Y456667D01*
X289467Y456833D01*
X288883Y456750D01*
X288383Y456500D01*
X288050Y455917D01*
X287883Y455417D01*
Y454917D01*
X288050Y454417D01*
X288467Y453917D01*
X288967Y453583D01*
X289550Y453500D01*
X290133Y453667D01*
X290717Y454167D01*
G01X298000Y458500D02*
X299167Y453500D01*
X300500Y458500D01*
X301833Y453500D01*
X303000Y458500D01*
G01X307600Y453500D02*
Y456833D01*
G01Y456250D02*
X307267Y456583D01*
X306767Y456750D01*
X306183Y456833D01*
X305600Y456667D01*
X305100Y456333D01*
X304767Y455833D01*
X304600Y455167D01*
X304767Y454500D01*
X305100Y454000D01*
X305600Y453667D01*
X306183Y453500D01*
X306767Y453583D01*
X307267Y453833D01*
X307600Y454167D01*
G01X311700Y453500D02*
Y458500D01*
G01X317300Y453500D02*
Y458500D01*
G01X326833Y453500D02*
Y458500D01*
X328917D01*
X329583Y458250D01*
X330000Y457917D01*
X330167Y457250D01*
X330000Y456583D01*
X329500Y456167D01*
X328917Y455917D01*
X326833D01*
G01X328917D02*
X330167Y453500D01*
G01X334100D02*
X333600Y453583D01*
X333100Y453917D01*
X332767Y454500D01*
X332600Y455167D01*
X332767Y455833D01*
X333100Y456417D01*
X333600Y456750D01*
X334100Y456833D01*
X334600Y456750D01*
X335100Y456417D01*
X335433Y455833D01*
X335517Y455167D01*
X335433Y454500D01*
X335100Y453917D01*
X334600Y453583D01*
X334100Y453500D01*
G01X338283Y456833D02*
Y454500D01*
X338617Y453917D01*
X339117Y453583D01*
X339700Y453500D01*
X340283Y453583D01*
X340783Y453917D01*
X341117Y454500D01*
G01Y453500D02*
Y456833D01*
G01X344133Y452250D02*
X344717Y451917D01*
X345383Y451833D01*
X345967Y451917D01*
X346467Y452333D01*
X346800Y452917D01*
Y456833D01*
G01Y456167D02*
X346467Y456500D01*
X345967Y456750D01*
X345383Y456833D01*
X344717Y456667D01*
X344300Y456333D01*
X343967Y455750D01*
X343800Y455167D01*
X343883Y454667D01*
X344217Y454083D01*
X344717Y453667D01*
X345383Y453500D01*
X345883Y453583D01*
X346467Y453917D01*
X346800Y454250D01*
G01X349483Y453500D02*
Y458500D01*
G01Y456083D02*
X349900Y456500D01*
X350317Y456750D01*
X350983Y456833D01*
X351483Y456750D01*
X352067Y456417D01*
X352317Y455917D01*
Y453500D01*
G01X355083D02*
Y456833D01*
G01Y456000D02*
X355417Y456417D01*
X355917Y456750D01*
X356583Y456833D01*
X357167Y456750D01*
X357667Y456417D01*
X357917Y455833D01*
Y453500D01*
G01X360850Y455750D02*
X363517D01*
X363267Y456333D01*
X362850Y456667D01*
X362267Y456833D01*
X361683Y456750D01*
X361183Y456500D01*
X360850Y455917D01*
X360683Y455417D01*
Y454917D01*
X360850Y454417D01*
X361267Y453917D01*
X361767Y453583D01*
X362350Y453500D01*
X362933Y453667D01*
X363517Y454167D01*
G01X366450Y454083D02*
X366867Y453750D01*
X367450Y453500D01*
X367950D01*
X368450Y453667D01*
X368783Y453917D01*
X368950Y454250D01*
X368867Y454750D01*
X368533Y455000D01*
X367033Y455500D01*
X366700Y456083D01*
X366867Y456500D01*
X367200Y456750D01*
X367700Y456833D01*
X368200Y456750D01*
X368700Y456500D01*
G01X372050Y454083D02*
X372467Y453750D01*
X373050Y453500D01*
X373550D01*
X374050Y453667D01*
X374383Y453917D01*
X374550Y454250D01*
X374467Y454750D01*
X374133Y455000D01*
X372633Y455500D01*
X372300Y456083D01*
X372467Y456500D01*
X372800Y456750D01*
X373300Y456833D01*
X373800Y456750D01*
X374300Y456500D01*
G01X272500Y470000D02*
X271833Y470083D01*
X271250Y470417D01*
X270750Y470917D01*
X270417Y471500D01*
X270250Y472167D01*
Y472833D01*
X270417Y473500D01*
X270750Y474083D01*
X271250Y474583D01*
X271833Y474917D01*
X272500Y475000D01*
X273167Y474917D01*
X273750Y474583D01*
X274250Y474083D01*
X274583Y473500D01*
X274750Y472833D01*
Y472167D01*
X274583Y471500D01*
X274250Y470917D01*
X273750Y470417D01*
X273167Y470083D01*
X272500Y470000D01*
G01X278100Y475000D02*
Y470000D01*
G01X276933Y473333D02*
X279267D01*
G01X282283Y470000D02*
Y475000D01*
G01Y472583D02*
X282700Y473000D01*
X283117Y473250D01*
X283783Y473333D01*
X284283Y473250D01*
X284867Y472917D01*
X285117Y472417D01*
Y470000D01*
G01X288050Y472250D02*
X290717D01*
X290467Y472833D01*
X290050Y473167D01*
X289467Y473333D01*
X288883Y473250D01*
X288383Y473000D01*
X288050Y472417D01*
X287883Y471917D01*
Y471417D01*
X288050Y470917D01*
X288467Y470417D01*
X288967Y470083D01*
X289550Y470000D01*
X290133Y470167D01*
X290717Y470667D01*
G01X293733Y470000D02*
Y473333D01*
G01Y472667D02*
X294150Y473000D01*
X294567Y473250D01*
X295150Y473333D01*
X295567Y473250D01*
X296067Y473000D01*
G01X299250Y470583D02*
X299667Y470250D01*
X300250Y470000D01*
X300750D01*
X301250Y470167D01*
X301583Y470417D01*
X301750Y470750D01*
X301667Y471250D01*
X301333Y471500D01*
X299833Y472000D01*
X299500Y472583D01*
X299667Y473000D01*
X300000Y473250D01*
X300500Y473333D01*
X301000Y473250D01*
X301500Y473000D01*
G01X311283Y468333D02*
X310450Y469167D01*
X310033Y470000D01*
Y473333D01*
X310450Y474167D01*
X311283Y475000D01*
G01X317300Y470000D02*
Y475000D01*
G01X322900Y473333D02*
Y470000D01*
G01Y474667D02*
X322733Y474750D01*
Y474917D01*
X322900Y475000D01*
X323067Y474917D01*
Y474750D01*
X322900Y474667D01*
G01X327083Y470000D02*
Y475000D01*
G01X329750Y473333D02*
X327083Y471417D01*
G01X328167Y472167D02*
X329917Y470000D01*
G01X332850Y472250D02*
X335517D01*
X335267Y472833D01*
X334850Y473167D01*
X334267Y473333D01*
X333683Y473250D01*
X333183Y473000D01*
X332850Y472417D01*
X332683Y471917D01*
Y471417D01*
X332850Y470917D01*
X333267Y470417D01*
X333767Y470083D01*
X334350Y470000D01*
X334933Y470167D01*
X335517Y470667D01*
G01X344050Y472250D02*
X346717D01*
X346467Y472833D01*
X346050Y473167D01*
X345467Y473333D01*
X344883Y473250D01*
X344383Y473000D01*
X344050Y472417D01*
X343883Y471917D01*
Y471417D01*
X344050Y470917D01*
X344467Y470417D01*
X344967Y470083D01*
X345550Y470000D01*
X346133Y470167D01*
X346717Y470667D01*
G01X350900Y470000D02*
Y475000D01*
G01X356500Y470000D02*
Y475000D01*
G01X362100Y473333D02*
Y470000D01*
G01Y474667D02*
X361933Y474750D01*
Y474917D01*
X362100Y475000D01*
X362267Y474917D01*
Y474750D01*
X362100Y474667D01*
G01X366200Y468333D02*
Y473333D01*
G01Y472583D02*
X366617Y473000D01*
X367033Y473250D01*
X367700Y473333D01*
X368283Y473250D01*
X368867Y472833D01*
X369117Y472250D01*
X369200Y471667D01*
X369117Y471083D01*
X368867Y470500D01*
X368367Y470167D01*
X367700Y470000D01*
X367117Y470083D01*
X366533Y470333D01*
X366200Y470667D01*
G01X372050Y470583D02*
X372467Y470250D01*
X373050Y470000D01*
X373550D01*
X374050Y470167D01*
X374383Y470417D01*
X374550Y470750D01*
X374467Y471250D01*
X374133Y471500D01*
X372633Y472000D01*
X372300Y472583D01*
X372467Y473000D01*
X372800Y473250D01*
X373300Y473333D01*
X373800Y473250D01*
X374300Y473000D01*
G01X377650Y472250D02*
X380317D01*
X380067Y472833D01*
X379650Y473167D01*
X379067Y473333D01*
X378483Y473250D01*
X377983Y473000D01*
X377650Y472417D01*
X377483Y471917D01*
Y471417D01*
X377650Y470917D01*
X378067Y470417D01*
X378567Y470083D01*
X379150Y470000D01*
X379733Y470167D01*
X380317Y470667D01*
G01X391600Y470000D02*
Y473333D01*
G01Y472750D02*
X391267Y473083D01*
X390767Y473250D01*
X390183Y473333D01*
X389600Y473167D01*
X389100Y472833D01*
X388767Y472333D01*
X388600Y471667D01*
X388767Y471000D01*
X389100Y470500D01*
X389600Y470167D01*
X390183Y470000D01*
X390767Y470083D01*
X391267Y470333D01*
X391600Y470667D01*
G01X394283Y470000D02*
Y473333D01*
G01Y472500D02*
X394617Y472917D01*
X395117Y473250D01*
X395783Y473333D01*
X396367Y473250D01*
X396867Y472917D01*
X397117Y472333D01*
Y470000D01*
G01X402800Y475000D02*
Y470000D01*
G01Y470750D02*
X402467Y470333D01*
X401967Y470083D01*
X401383Y470000D01*
X400717Y470167D01*
X400217Y470583D01*
X399883Y471083D01*
X399800Y471667D01*
X399883Y472250D01*
X400217Y472750D01*
X400717Y473167D01*
X401383Y473333D01*
X401967Y473250D01*
X402383Y473083D01*
X402800Y472750D01*
G01X412500Y470000D02*
X412000Y470083D01*
X411500Y470417D01*
X411167Y471000D01*
X411000Y471667D01*
X411167Y472333D01*
X411500Y472917D01*
X412000Y473250D01*
X412500Y473333D01*
X413000Y473250D01*
X413500Y472917D01*
X413833Y472333D01*
X413917Y471667D01*
X413833Y471000D01*
X413500Y470417D01*
X413000Y470083D01*
X412500Y470000D01*
G01X418100Y475000D02*
Y470000D01*
G01X416933Y473333D02*
X419267D01*
G01X422283Y470000D02*
Y475000D01*
G01Y472583D02*
X422700Y473000D01*
X423117Y473250D01*
X423783Y473333D01*
X424283Y473250D01*
X424867Y472917D01*
X425117Y472417D01*
Y470000D01*
G01X428050Y472250D02*
X430717D01*
X430467Y472833D01*
X430050Y473167D01*
X429467Y473333D01*
X428883Y473250D01*
X428383Y473000D01*
X428050Y472417D01*
X427883Y471917D01*
Y471417D01*
X428050Y470917D01*
X428467Y470417D01*
X428967Y470083D01*
X429550Y470000D01*
X430133Y470167D01*
X430717Y470667D01*
G01X433733Y470000D02*
Y473333D01*
G01Y472667D02*
X434150Y473000D01*
X434567Y473250D01*
X435150Y473333D01*
X435567Y473250D01*
X436067Y473000D01*
G01X439250Y470583D02*
X439667Y470250D01*
X440250Y470000D01*
X440750D01*
X441250Y470167D01*
X441583Y470417D01*
X441750Y470750D01*
X441667Y471250D01*
X441333Y471500D01*
X439833Y472000D01*
X439500Y472583D01*
X439667Y473000D01*
X440000Y473250D01*
X440500Y473333D01*
X441000Y473250D01*
X441500Y473000D01*
G01X446517Y468333D02*
X447350Y469167D01*
X447767Y470000D01*
Y473333D01*
X447350Y474167D01*
X446517Y475000D01*
G01X270833Y485000D02*
Y490000D01*
X272833D01*
X273500Y489750D01*
X274000Y489167D01*
X274167Y488500D01*
X274000Y487833D01*
X273583Y487333D01*
X272833Y487083D01*
X270833D01*
G01X278100Y490000D02*
Y485000D01*
G01X276183Y490000D02*
X280017D01*
G01X281950Y485000D02*
Y490000D01*
G01X285450D02*
Y485000D01*
G01Y487500D02*
X281950D01*
G01X287800Y484833D02*
X290800Y490000D01*
G01X292983Y485000D02*
Y490000D01*
X296817Y485000D01*
Y490000D01*
G01X298833Y485000D02*
Y490000D01*
X300833D01*
X301500Y489750D01*
X302000Y489167D01*
X302167Y488500D01*
X302000Y487833D01*
X301583Y487333D01*
X300833Y487083D01*
X298833D01*
G01X306100Y490000D02*
Y485000D01*
G01X304183Y490000D02*
X308017D01*
G01X309950Y485000D02*
Y490000D01*
G01X313450D02*
Y485000D01*
G01Y487500D02*
X309950D01*
G01X321233Y485000D02*
X324567Y486667D01*
X321233Y488333D01*
G01X327417Y485917D02*
X329583D01*
G01Y487417D02*
X327417D01*
G01X332267Y485750D02*
X332767Y485333D01*
X333350Y485083D01*
X334100Y485000D01*
X334850Y485167D01*
X335433Y485500D01*
X335850Y486083D01*
X335933Y486750D01*
X335767Y487417D01*
X335350Y487833D01*
X334767Y488167D01*
X334183Y488250D01*
X333600Y488167D01*
X332850Y487833D01*
X333100Y490000D01*
X335350D01*
G01X342800Y485000D02*
Y488333D01*
G01Y487417D02*
X343050Y487833D01*
X343467Y488167D01*
X344050Y488333D01*
X344633Y488167D01*
X345050Y487833D01*
X345300Y487417D01*
Y485000D01*
G01Y487417D02*
X345550Y487833D01*
X345967Y488167D01*
X346550Y488333D01*
X347133Y488167D01*
X347550Y487833D01*
X347800Y487333D01*
Y485000D01*
G01X348400D02*
Y488333D01*
G01Y487417D02*
X348650Y487833D01*
X349067Y488167D01*
X349650Y488333D01*
X350233Y488167D01*
X350650Y487833D01*
X350900Y487417D01*
Y485000D01*
G01Y487417D02*
X351150Y487833D01*
X351567Y488167D01*
X352150Y488333D01*
X352733Y488167D01*
X353150Y487833D01*
X353400Y487333D01*
Y485000D01*
G01X262500Y479000D02*
X694500D01*
G01X270583Y498500D02*
Y503500D01*
X274417Y498500D01*
Y503500D01*
G01X276433Y498500D02*
Y503500D01*
X278433D01*
X279100Y503250D01*
X279600Y502667D01*
X279767Y502000D01*
X279600Y501333D01*
X279183Y500833D01*
X278433Y500583D01*
X276433D01*
G01X283700Y503500D02*
Y498500D01*
G01X281783Y503500D02*
X285617D01*
G01X287550Y498500D02*
Y503500D01*
G01X291050D02*
Y498500D01*
G01Y501000D02*
X287550D01*
G01X298750Y499167D02*
X299417Y498750D01*
X300167Y498500D01*
X300833D01*
X301500Y498750D01*
X302000Y499167D01*
X302250Y499750D01*
X302083Y500333D01*
X301667Y500833D01*
X300917Y501167D01*
X299917Y501333D01*
X299333Y501667D01*
X299083Y502250D01*
X299250Y502833D01*
X299667Y503250D01*
X300250Y503500D01*
X300833D01*
X301417Y503333D01*
X301917Y502917D01*
G01X306100Y501833D02*
Y498500D01*
G01Y503167D02*
X305933Y503250D01*
Y503417D01*
X306100Y503500D01*
X306267Y503417D01*
Y503250D01*
X306100Y503167D01*
G01X310450Y501833D02*
X312950D01*
X310450Y498500D01*
X312950D01*
G01X316050Y500750D02*
X318717D01*
X318467Y501333D01*
X318050Y501667D01*
X317467Y501833D01*
X316883Y501750D01*
X316383Y501500D01*
X316050Y500917D01*
X315883Y500417D01*
Y499917D01*
X316050Y499417D01*
X316467Y498917D01*
X316967Y498583D01*
X317550Y498500D01*
X318133Y498667D01*
X318717Y499167D01*
G01X326667Y499500D02*
X327167Y498917D01*
X327833Y498583D01*
X328583Y498500D01*
X329250Y498583D01*
X329917Y499000D01*
X330333Y499500D01*
X330417Y500000D01*
X330250Y500583D01*
X329667Y501000D01*
X329083Y501167D01*
X328333D01*
G01X329083D02*
X329583Y501417D01*
X330000Y501833D01*
X330167Y502333D01*
X330000Y502833D01*
X329583Y503250D01*
X328833Y503500D01*
X328083Y503417D01*
X327333Y503083D01*
G01X334100Y498333D02*
X333933Y498417D01*
Y498583D01*
X334100Y498667D01*
X334267Y498583D01*
Y498417D01*
X334100Y498333D01*
G01X337867Y499250D02*
X338367Y498833D01*
X338950Y498583D01*
X339700Y498500D01*
X340450Y498667D01*
X341033Y499000D01*
X341450Y499583D01*
X341533Y500250D01*
X341367Y500917D01*
X340950Y501333D01*
X340367Y501667D01*
X339783Y501750D01*
X339200Y501667D01*
X338450Y501333D01*
X338700Y503500D01*
X340950D01*
G01X343467Y499250D02*
X343967Y498833D01*
X344550Y498583D01*
X345300Y498500D01*
X346050Y498667D01*
X346633Y499000D01*
X347050Y499583D01*
X347133Y500250D01*
X346967Y500917D01*
X346550Y501333D01*
X345967Y501667D01*
X345383Y501750D01*
X344800Y501667D01*
X344050Y501333D01*
X344300Y503500D01*
X346550D01*
G01X348400Y498500D02*
Y501833D01*
G01Y500917D02*
X348650Y501333D01*
X349067Y501667D01*
X349650Y501833D01*
X350233Y501667D01*
X350650Y501333D01*
X350900Y500917D01*
Y498500D01*
G01Y500917D02*
X351150Y501333D01*
X351567Y501667D01*
X352150Y501833D01*
X352733Y501667D01*
X353150Y501333D01*
X353400Y500833D01*
Y498500D01*
G01X354000D02*
Y501833D01*
G01Y500917D02*
X354250Y501333D01*
X354667Y501667D01*
X355250Y501833D01*
X355833Y501667D01*
X356250Y501333D01*
X356500Y500917D01*
Y498500D01*
G01Y500917D02*
X356750Y501333D01*
X357167Y501667D01*
X357750Y501833D01*
X358333Y501667D01*
X358750Y501333D01*
X359000Y500833D01*
Y498500D01*
G01X270583Y513500D02*
Y518500D01*
X274417Y513500D01*
Y518500D01*
G01X276433Y513500D02*
Y518500D01*
X278433D01*
X279100Y518250D01*
X279600Y517667D01*
X279767Y517000D01*
X279600Y516333D01*
X279183Y515833D01*
X278433Y515583D01*
X276433D01*
G01X283700Y518500D02*
Y513500D01*
G01X281783Y518500D02*
X285617D01*
G01X287550Y513500D02*
Y518500D01*
G01X291050D02*
Y513500D01*
G01Y516000D02*
X287550D01*
G01X298750Y514167D02*
X299417Y513750D01*
X300167Y513500D01*
X300833D01*
X301500Y513750D01*
X302000Y514167D01*
X302250Y514750D01*
X302083Y515333D01*
X301667Y515833D01*
X300917Y516167D01*
X299917Y516333D01*
X299333Y516667D01*
X299083Y517250D01*
X299250Y517833D01*
X299667Y518250D01*
X300250Y518500D01*
X300833D01*
X301417Y518333D01*
X301917Y517917D01*
G01X306100Y516833D02*
Y513500D01*
G01Y518167D02*
X305933Y518250D01*
Y518417D01*
X306100Y518500D01*
X306267Y518417D01*
Y518250D01*
X306100Y518167D01*
G01X310450Y516833D02*
X312950D01*
X310450Y513500D01*
X312950D01*
G01X316050Y515750D02*
X318717D01*
X318467Y516333D01*
X318050Y516667D01*
X317467Y516833D01*
X316883Y516750D01*
X316383Y516500D01*
X316050Y515917D01*
X315883Y515417D01*
Y514917D01*
X316050Y514417D01*
X316467Y513917D01*
X316967Y513583D01*
X317550Y513500D01*
X318133Y513667D01*
X318717Y514167D01*
G01X324567Y513500D02*
X321233Y515167D01*
X324567Y516833D01*
G01X332267Y514250D02*
X332767Y513833D01*
X333350Y513583D01*
X334100Y513500D01*
X334850Y513667D01*
X335433Y514000D01*
X335850Y514583D01*
X335933Y515250D01*
X335767Y515917D01*
X335350Y516333D01*
X334767Y516667D01*
X334183Y516750D01*
X333600Y516667D01*
X332850Y516333D01*
X333100Y518500D01*
X335350D01*
G01X337200Y513500D02*
Y516833D01*
G01Y515917D02*
X337450Y516333D01*
X337867Y516667D01*
X338450Y516833D01*
X339033Y516667D01*
X339450Y516333D01*
X339700Y515917D01*
Y513500D01*
G01Y515917D02*
X339950Y516333D01*
X340367Y516667D01*
X340950Y516833D01*
X341533Y516667D01*
X341950Y516333D01*
X342200Y515833D01*
Y513500D01*
G01X342800D02*
Y516833D01*
G01Y515917D02*
X343050Y516333D01*
X343467Y516667D01*
X344050Y516833D01*
X344633Y516667D01*
X345050Y516333D01*
X345300Y515917D01*
Y513500D01*
G01Y515917D02*
X345550Y516333D01*
X345967Y516667D01*
X346550Y516833D01*
X347133Y516667D01*
X347550Y516333D01*
X347800Y515833D01*
Y513500D01*
G01X270667Y535000D02*
Y531417D01*
X271000Y530667D01*
X271667Y530167D01*
X272500Y530000D01*
X273333Y530167D01*
X274000Y530667D01*
X274333Y531417D01*
Y535000D01*
G01X276683Y530000D02*
Y533333D01*
G01Y532500D02*
X277017Y532917D01*
X277517Y533250D01*
X278183Y533333D01*
X278767Y533250D01*
X279267Y532917D01*
X279517Y532333D01*
Y530000D01*
G01X282617Y531667D02*
X284783D01*
G01X287800Y528333D02*
Y533333D01*
G01Y532583D02*
X288217Y533000D01*
X288633Y533250D01*
X289300Y533333D01*
X289883Y533250D01*
X290467Y532833D01*
X290717Y532250D01*
X290800Y531667D01*
X290717Y531083D01*
X290467Y530500D01*
X289967Y530167D01*
X289300Y530000D01*
X288717Y530083D01*
X288133Y530333D01*
X287800Y530667D01*
G01X294900Y530000D02*
Y535000D01*
G01X299083Y533333D02*
Y531000D01*
X299417Y530417D01*
X299917Y530083D01*
X300500Y530000D01*
X301083Y530083D01*
X301583Y530417D01*
X301917Y531000D01*
G01Y530000D02*
Y533333D01*
G01X304933Y528750D02*
X305517Y528417D01*
X306183Y528333D01*
X306767Y528417D01*
X307267Y528833D01*
X307600Y529417D01*
Y533333D01*
G01Y532667D02*
X307267Y533000D01*
X306767Y533250D01*
X306183Y533333D01*
X305517Y533167D01*
X305100Y532833D01*
X304767Y532250D01*
X304600Y531667D01*
X304683Y531167D01*
X305017Y530583D01*
X305517Y530167D01*
X306183Y530000D01*
X306683Y530083D01*
X307267Y530417D01*
X307600Y530750D01*
G01X310533Y528750D02*
X311117Y528417D01*
X311783Y528333D01*
X312367Y528417D01*
X312867Y528833D01*
X313200Y529417D01*
Y533333D01*
G01Y532667D02*
X312867Y533000D01*
X312367Y533250D01*
X311783Y533333D01*
X311117Y533167D01*
X310700Y532833D01*
X310367Y532250D01*
X310200Y531667D01*
X310283Y531167D01*
X310617Y530583D01*
X311117Y530167D01*
X311783Y530000D01*
X312283Y530083D01*
X312867Y530417D01*
X313200Y530750D01*
G01X316050Y532250D02*
X318717D01*
X318467Y532833D01*
X318050Y533167D01*
X317467Y533333D01*
X316883Y533250D01*
X316383Y533000D01*
X316050Y532417D01*
X315883Y531917D01*
Y531417D01*
X316050Y530917D01*
X316467Y530417D01*
X316967Y530083D01*
X317550Y530000D01*
X318133Y530167D01*
X318717Y530667D01*
G01X324400Y535000D02*
Y530000D01*
G01Y530750D02*
X324067Y530333D01*
X323567Y530083D01*
X322983Y530000D01*
X322317Y530167D01*
X321817Y530583D01*
X321483Y531083D01*
X321400Y531667D01*
X321483Y532250D01*
X321817Y532750D01*
X322317Y533167D01*
X322983Y533333D01*
X323567Y533250D01*
X323983Y533083D01*
X324400Y532750D01*
G01X332433Y530000D02*
Y535000D01*
X334433D01*
X335100Y534750D01*
X335600Y534167D01*
X335767Y533500D01*
X335600Y532833D01*
X335183Y532333D01*
X334433Y532083D01*
X332433D01*
G01X339700Y535000D02*
Y530000D01*
G01X337783Y535000D02*
X341617D01*
G01X343550Y530000D02*
Y535000D01*
G01X347050D02*
Y530000D01*
G01Y532500D02*
X343550D01*
G01X356083Y528333D02*
X355250Y529167D01*
X354833Y530000D01*
Y533333D01*
X355250Y534167D01*
X356083Y535000D01*
G01X360350Y530000D02*
Y535000D01*
G01X363850D02*
Y530000D01*
G01Y532500D02*
X360350D01*
G01X367700Y530000D02*
X367200Y530083D01*
X366700Y530417D01*
X366367Y531000D01*
X366200Y531667D01*
X366367Y532333D01*
X366700Y532917D01*
X367200Y533250D01*
X367700Y533333D01*
X368200Y533250D01*
X368700Y532917D01*
X369033Y532333D01*
X369117Y531667D01*
X369033Y531000D01*
X368700Y530417D01*
X368200Y530083D01*
X367700Y530000D01*
G01X373300D02*
Y535000D01*
G01X377650Y532250D02*
X380317D01*
X380067Y532833D01*
X379650Y533167D01*
X379067Y533333D01*
X378483Y533250D01*
X377983Y533000D01*
X377650Y532417D01*
X377483Y531917D01*
Y531417D01*
X377650Y530917D01*
X378067Y530417D01*
X378567Y530083D01*
X379150Y530000D01*
X379733Y530167D01*
X380317Y530667D01*
G01X388350D02*
X389017Y530250D01*
X389767Y530000D01*
X390433D01*
X391100Y530250D01*
X391600Y530667D01*
X391850Y531250D01*
X391683Y531833D01*
X391267Y532333D01*
X390517Y532667D01*
X389517Y532833D01*
X388933Y533167D01*
X388683Y533750D01*
X388850Y534333D01*
X389267Y534750D01*
X389850Y535000D01*
X390433D01*
X391017Y534833D01*
X391517Y534417D01*
G01X395700Y533333D02*
Y530000D01*
G01Y534667D02*
X395533Y534750D01*
Y534917D01*
X395700Y535000D01*
X395867Y534917D01*
Y534750D01*
X395700Y534667D01*
G01X400050Y533333D02*
X402550D01*
X400050Y530000D01*
X402550D01*
G01X405650Y532250D02*
X408317D01*
X408067Y532833D01*
X407650Y533167D01*
X407067Y533333D01*
X406483Y533250D01*
X405983Y533000D01*
X405650Y532417D01*
X405483Y531917D01*
Y531417D01*
X405650Y530917D01*
X406067Y530417D01*
X406567Y530083D01*
X407150Y530000D01*
X407733Y530167D01*
X408317Y530667D01*
G01X414167Y530000D02*
X410833Y531667D01*
X414167Y533333D01*
G01X418100Y530000D02*
Y535000D01*
X417100Y534000D01*
G01Y530000D02*
X419100D01*
G01X422283Y530583D02*
X422867Y530167D01*
X423533Y530000D01*
X424200Y530167D01*
X424783Y530667D01*
X425200Y531417D01*
X425367Y532167D01*
Y533083D01*
X425200Y533833D01*
X424783Y534500D01*
X424283Y534833D01*
X423700Y535000D01*
X423033Y534833D01*
X422533Y534500D01*
X422200Y534000D01*
X422033Y533333D01*
X422200Y532750D01*
X422617Y532167D01*
X423117Y531833D01*
X423700Y531750D01*
X424367Y531917D01*
X424867Y532333D01*
X425367Y533083D01*
G01X429133Y530000D02*
X429300Y531083D01*
X429550Y532000D01*
X429883Y532833D01*
X430300Y533750D01*
X430967Y535000D01*
X427633D01*
G01X432400Y530000D02*
Y533333D01*
G01Y532417D02*
X432650Y532833D01*
X433067Y533167D01*
X433650Y533333D01*
X434233Y533167D01*
X434650Y532833D01*
X434900Y532417D01*
Y530000D01*
G01Y532417D02*
X435150Y532833D01*
X435567Y533167D01*
X436150Y533333D01*
X436733Y533167D01*
X437150Y532833D01*
X437400Y532333D01*
Y530000D01*
G01X440500Y533333D02*
Y530000D01*
G01Y534667D02*
X440333Y534750D01*
Y534917D01*
X440500Y535000D01*
X440667Y534917D01*
Y534750D01*
X440500Y534667D01*
G01X446100Y530000D02*
Y535000D01*
G01X455217Y533333D02*
X456217Y530000D01*
X457300Y533333D01*
X458383Y530000D01*
X459383Y533333D01*
G01X462900D02*
Y530000D01*
G01Y534667D02*
X462733Y534750D01*
Y534917D01*
X462900Y535000D01*
X463067Y534917D01*
Y534750D01*
X462900Y534667D01*
G01X468500Y535000D02*
Y530000D01*
G01X467333Y533333D02*
X469667D01*
G01X472683Y530000D02*
Y535000D01*
G01Y532583D02*
X473100Y533000D01*
X473517Y533250D01*
X474183Y533333D01*
X474683Y533250D01*
X475267Y532917D01*
X475517Y532417D01*
Y530000D01*
G01X483550D02*
Y535000D01*
G01X487050D02*
Y530000D01*
G01Y532500D02*
X483550D01*
G01X488817Y530000D02*
X490900Y535000D01*
X492983Y530000D01*
G01X492233Y531750D02*
X489567D01*
G01X494750Y530667D02*
X495417Y530250D01*
X496167Y530000D01*
X496833D01*
X497500Y530250D01*
X498000Y530667D01*
X498250Y531250D01*
X498083Y531833D01*
X497667Y532333D01*
X496917Y532667D01*
X495917Y532833D01*
X495333Y533167D01*
X495083Y533750D01*
X495250Y534333D01*
X495667Y534750D01*
X496250Y535000D01*
X496833D01*
X497417Y534833D01*
X497917Y534417D01*
G01X500433Y535000D02*
Y530000D01*
X503767D01*
G01X511800Y528333D02*
Y533333D01*
G01Y532583D02*
X512217Y533000D01*
X512633Y533250D01*
X513300Y533333D01*
X513883Y533250D01*
X514467Y532833D01*
X514717Y532250D01*
X514800Y531667D01*
X514717Y531083D01*
X514467Y530500D01*
X513967Y530167D01*
X513300Y530000D01*
X512717Y530083D01*
X512133Y530333D01*
X511800Y530667D01*
G01X517733Y530000D02*
Y533333D01*
G01Y532667D02*
X518150Y533000D01*
X518567Y533250D01*
X519150Y533333D01*
X519567Y533250D01*
X520067Y533000D01*
G01X524500Y530000D02*
X524000Y530083D01*
X523500Y530417D01*
X523167Y531000D01*
X523000Y531667D01*
X523167Y532333D01*
X523500Y532917D01*
X524000Y533250D01*
X524500Y533333D01*
X525000Y533250D01*
X525500Y532917D01*
X525833Y532333D01*
X525917Y531667D01*
X525833Y531000D01*
X525500Y530417D01*
X525000Y530083D01*
X524500Y530000D01*
G01X531600Y535000D02*
Y530000D01*
G01Y530750D02*
X531267Y530333D01*
X530767Y530083D01*
X530183Y530000D01*
X529517Y530167D01*
X529017Y530583D01*
X528683Y531083D01*
X528600Y531667D01*
X528683Y532250D01*
X529017Y532750D01*
X529517Y533167D01*
X530183Y533333D01*
X530767Y533250D01*
X531183Y533083D01*
X531600Y532750D01*
G01X534283Y533333D02*
Y531000D01*
X534617Y530417D01*
X535117Y530083D01*
X535700Y530000D01*
X536283Y530083D01*
X536783Y530417D01*
X537117Y531000D01*
G01Y530000D02*
Y533333D01*
G01X542633Y532917D02*
X542050Y533250D01*
X541550Y533333D01*
X540883Y533167D01*
X540383Y532833D01*
X540050Y532250D01*
X539967Y531667D01*
X540050Y531083D01*
X540383Y530583D01*
X540883Y530167D01*
X541550Y530000D01*
X542133Y530167D01*
X542633Y530500D01*
G01X546900Y535000D02*
Y530000D01*
G01X545733Y533333D02*
X548067D01*
G01X551250Y530583D02*
X551667Y530250D01*
X552250Y530000D01*
X552750D01*
X553250Y530167D01*
X553583Y530417D01*
X553750Y530750D01*
X553667Y531250D01*
X553333Y531500D01*
X551833Y532000D01*
X551500Y532583D01*
X551667Y533000D01*
X552000Y533250D01*
X552500Y533333D01*
X553000Y533250D01*
X553500Y533000D01*
G01X558517Y528333D02*
X559350Y529167D01*
X559767Y530000D01*
Y533333D01*
X559350Y534167D01*
X558517Y535000D01*
G01X270667Y550000D02*
Y546417D01*
X271000Y545667D01*
X271667Y545167D01*
X272500Y545000D01*
X273333Y545167D01*
X274000Y545667D01*
X274333Y546417D01*
Y550000D01*
G01X276683Y545000D02*
Y548333D01*
G01Y547500D02*
X277017Y547917D01*
X277517Y548250D01*
X278183Y548333D01*
X278767Y548250D01*
X279267Y547917D01*
X279517Y547333D01*
Y545000D01*
G01X282617Y546667D02*
X284783D01*
G01X287800Y543333D02*
Y548333D01*
G01Y547583D02*
X288217Y548000D01*
X288633Y548250D01*
X289300Y548333D01*
X289883Y548250D01*
X290467Y547833D01*
X290717Y547250D01*
X290800Y546667D01*
X290717Y546083D01*
X290467Y545500D01*
X289967Y545167D01*
X289300Y545000D01*
X288717Y545083D01*
X288133Y545333D01*
X287800Y545667D01*
G01X294900Y545000D02*
Y550000D01*
G01X299083Y548333D02*
Y546000D01*
X299417Y545417D01*
X299917Y545083D01*
X300500Y545000D01*
X301083Y545083D01*
X301583Y545417D01*
X301917Y546000D01*
G01Y545000D02*
Y548333D01*
G01X304933Y543750D02*
X305517Y543417D01*
X306183Y543333D01*
X306767Y543417D01*
X307267Y543833D01*
X307600Y544417D01*
Y548333D01*
G01Y547667D02*
X307267Y548000D01*
X306767Y548250D01*
X306183Y548333D01*
X305517Y548167D01*
X305100Y547833D01*
X304767Y547250D01*
X304600Y546667D01*
X304683Y546167D01*
X305017Y545583D01*
X305517Y545167D01*
X306183Y545000D01*
X306683Y545083D01*
X307267Y545417D01*
X307600Y545750D01*
G01X310533Y543750D02*
X311117Y543417D01*
X311783Y543333D01*
X312367Y543417D01*
X312867Y543833D01*
X313200Y544417D01*
Y548333D01*
G01Y547667D02*
X312867Y548000D01*
X312367Y548250D01*
X311783Y548333D01*
X311117Y548167D01*
X310700Y547833D01*
X310367Y547250D01*
X310200Y546667D01*
X310283Y546167D01*
X310617Y545583D01*
X311117Y545167D01*
X311783Y545000D01*
X312283Y545083D01*
X312867Y545417D01*
X313200Y545750D01*
G01X316050Y547250D02*
X318717D01*
X318467Y547833D01*
X318050Y548167D01*
X317467Y548333D01*
X316883Y548250D01*
X316383Y548000D01*
X316050Y547417D01*
X315883Y546917D01*
Y546417D01*
X316050Y545917D01*
X316467Y545417D01*
X316967Y545083D01*
X317550Y545000D01*
X318133Y545167D01*
X318717Y545667D01*
G01X324400Y550000D02*
Y545000D01*
G01Y545750D02*
X324067Y545333D01*
X323567Y545083D01*
X322983Y545000D01*
X322317Y545167D01*
X321817Y545583D01*
X321483Y546083D01*
X321400Y546667D01*
X321483Y547250D01*
X321817Y547750D01*
X322317Y548167D01*
X322983Y548333D01*
X323567Y548250D01*
X323983Y548083D01*
X324400Y547750D01*
G01X332433Y545000D02*
Y550000D01*
X334433D01*
X335100Y549750D01*
X335600Y549167D01*
X335767Y548500D01*
X335600Y547833D01*
X335183Y547333D01*
X334433Y547083D01*
X332433D01*
G01X339700Y550000D02*
Y545000D01*
G01X337783Y550000D02*
X341617D01*
G01X343550Y545000D02*
Y550000D01*
G01X347050D02*
Y545000D01*
G01Y547500D02*
X343550D01*
G01X356083Y543333D02*
X355250Y544167D01*
X354833Y545000D01*
Y548333D01*
X355250Y549167D01*
X356083Y550000D01*
G01X360350Y545000D02*
Y550000D01*
G01X363850D02*
Y545000D01*
G01Y547500D02*
X360350D01*
G01X367700Y545000D02*
X367200Y545083D01*
X366700Y545417D01*
X366367Y546000D01*
X366200Y546667D01*
X366367Y547333D01*
X366700Y547917D01*
X367200Y548250D01*
X367700Y548333D01*
X368200Y548250D01*
X368700Y547917D01*
X369033Y547333D01*
X369117Y546667D01*
X369033Y546000D01*
X368700Y545417D01*
X368200Y545083D01*
X367700Y545000D01*
G01X373300D02*
Y550000D01*
G01X377650Y547250D02*
X380317D01*
X380067Y547833D01*
X379650Y548167D01*
X379067Y548333D01*
X378483Y548250D01*
X377983Y548000D01*
X377650Y547417D01*
X377483Y546917D01*
Y546417D01*
X377650Y545917D01*
X378067Y545417D01*
X378567Y545083D01*
X379150Y545000D01*
X379733Y545167D01*
X380317Y545667D01*
G01X388350D02*
X389017Y545250D01*
X389767Y545000D01*
X390433D01*
X391100Y545250D01*
X391600Y545667D01*
X391850Y546250D01*
X391683Y546833D01*
X391267Y547333D01*
X390517Y547667D01*
X389517Y547833D01*
X388933Y548167D01*
X388683Y548750D01*
X388850Y549333D01*
X389267Y549750D01*
X389850Y550000D01*
X390433D01*
X391017Y549833D01*
X391517Y549417D01*
G01X395700Y548333D02*
Y545000D01*
G01Y549667D02*
X395533Y549750D01*
Y549917D01*
X395700Y550000D01*
X395867Y549917D01*
Y549750D01*
X395700Y549667D01*
G01X400050Y548333D02*
X402550D01*
X400050Y545000D01*
X402550D01*
G01X405650Y547250D02*
X408317D01*
X408067Y547833D01*
X407650Y548167D01*
X407067Y548333D01*
X406483Y548250D01*
X405983Y548000D01*
X405650Y547417D01*
X405483Y546917D01*
Y546417D01*
X405650Y545917D01*
X406067Y545417D01*
X406567Y545083D01*
X407150Y545000D01*
X407733Y545167D01*
X408317Y545667D01*
G01X414167Y545000D02*
X410833Y546667D01*
X414167Y548333D01*
G01X418100Y545000D02*
Y550000D01*
X417100Y549000D01*
G01Y545000D02*
X419100D01*
G01X422283Y545583D02*
X422867Y545167D01*
X423533Y545000D01*
X424200Y545167D01*
X424783Y545667D01*
X425200Y546417D01*
X425367Y547167D01*
Y548083D01*
X425200Y548833D01*
X424783Y549500D01*
X424283Y549833D01*
X423700Y550000D01*
X423033Y549833D01*
X422533Y549500D01*
X422200Y549000D01*
X422033Y548333D01*
X422200Y547750D01*
X422617Y547167D01*
X423117Y546833D01*
X423700Y546750D01*
X424367Y546917D01*
X424867Y547333D01*
X425367Y548083D01*
G01X429133Y545000D02*
X429300Y546083D01*
X429550Y547000D01*
X429883Y547833D01*
X430300Y548750D01*
X430967Y550000D01*
X427633D01*
G01X432400Y545000D02*
Y548333D01*
G01Y547417D02*
X432650Y547833D01*
X433067Y548167D01*
X433650Y548333D01*
X434233Y548167D01*
X434650Y547833D01*
X434900Y547417D01*
Y545000D01*
G01Y547417D02*
X435150Y547833D01*
X435567Y548167D01*
X436150Y548333D01*
X436733Y548167D01*
X437150Y547833D01*
X437400Y547333D01*
Y545000D01*
G01X440500Y548333D02*
Y545000D01*
G01Y549667D02*
X440333Y549750D01*
Y549917D01*
X440500Y550000D01*
X440667Y549917D01*
Y549750D01*
X440500Y549667D01*
G01X446100Y545000D02*
Y550000D01*
G01X455217Y548333D02*
X456217Y545000D01*
X457300Y548333D01*
X458383Y545000D01*
X459383Y548333D01*
G01X462900D02*
Y545000D01*
G01Y549667D02*
X462733Y549750D01*
Y549917D01*
X462900Y550000D01*
X463067Y549917D01*
Y549750D01*
X462900Y549667D01*
G01X468500Y550000D02*
Y545000D01*
G01X467333Y548333D02*
X469667D01*
G01X472683Y545000D02*
Y550000D01*
G01Y547583D02*
X473100Y548000D01*
X473517Y548250D01*
X474183Y548333D01*
X474683Y548250D01*
X475267Y547917D01*
X475517Y547417D01*
Y545000D01*
G01X483883D02*
Y548333D01*
G01Y547500D02*
X484217Y547917D01*
X484717Y548250D01*
X485383Y548333D01*
X485967Y548250D01*
X486467Y547917D01*
X486717Y547333D01*
Y545000D01*
G01X490900D02*
X490400Y545083D01*
X489900Y545417D01*
X489567Y546000D01*
X489400Y546667D01*
X489567Y547333D01*
X489900Y547917D01*
X490400Y548250D01*
X490900Y548333D01*
X491400Y548250D01*
X491900Y547917D01*
X492233Y547333D01*
X492317Y546667D01*
X492233Y546000D01*
X491900Y545417D01*
X491400Y545083D01*
X490900Y545000D01*
G01X495083D02*
Y548333D01*
G01Y547500D02*
X495417Y547917D01*
X495917Y548250D01*
X496583Y548333D01*
X497167Y548250D01*
X497667Y547917D01*
X497917Y547333D01*
Y545000D01*
G01X501017Y546667D02*
X503183D01*
G01X505950Y545000D02*
Y550000D01*
G01X509450D02*
Y545000D01*
G01Y547500D02*
X505950D01*
G01X511217Y545000D02*
X513300Y550000D01*
X515383Y545000D01*
G01X514633Y546750D02*
X511967D01*
G01X517150Y545667D02*
X517817Y545250D01*
X518567Y545000D01*
X519233D01*
X519900Y545250D01*
X520400Y545667D01*
X520650Y546250D01*
X520483Y546833D01*
X520067Y547333D01*
X519317Y547667D01*
X518317Y547833D01*
X517733Y548167D01*
X517483Y548750D01*
X517650Y549333D01*
X518067Y549750D01*
X518650Y550000D01*
X519233D01*
X519817Y549833D01*
X520317Y549417D01*
G01X522833Y550000D02*
Y545000D01*
X526167D01*
G01X534200Y543333D02*
Y548333D01*
G01Y547583D02*
X534617Y548000D01*
X535033Y548250D01*
X535700Y548333D01*
X536283Y548250D01*
X536867Y547833D01*
X537117Y547250D01*
X537200Y546667D01*
X537117Y546083D01*
X536867Y545500D01*
X536367Y545167D01*
X535700Y545000D01*
X535117Y545083D01*
X534533Y545333D01*
X534200Y545667D01*
G01X540133Y545000D02*
Y548333D01*
G01Y547667D02*
X540550Y548000D01*
X540967Y548250D01*
X541550Y548333D01*
X541967Y548250D01*
X542467Y548000D01*
G01X546900Y545000D02*
X546400Y545083D01*
X545900Y545417D01*
X545567Y546000D01*
X545400Y546667D01*
X545567Y547333D01*
X545900Y547917D01*
X546400Y548250D01*
X546900Y548333D01*
X547400Y548250D01*
X547900Y547917D01*
X548233Y547333D01*
X548317Y546667D01*
X548233Y546000D01*
X547900Y545417D01*
X547400Y545083D01*
X546900Y545000D01*
G01X554000Y550000D02*
Y545000D01*
G01Y545750D02*
X553667Y545333D01*
X553167Y545083D01*
X552583Y545000D01*
X551917Y545167D01*
X551417Y545583D01*
X551083Y546083D01*
X551000Y546667D01*
X551083Y547250D01*
X551417Y547750D01*
X551917Y548167D01*
X552583Y548333D01*
X553167Y548250D01*
X553583Y548083D01*
X554000Y547750D01*
G01X556683Y548333D02*
Y546000D01*
X557017Y545417D01*
X557517Y545083D01*
X558100Y545000D01*
X558683Y545083D01*
X559183Y545417D01*
X559517Y546000D01*
G01Y545000D02*
Y548333D01*
G01X565033Y547917D02*
X564450Y548250D01*
X563950Y548333D01*
X563283Y548167D01*
X562783Y547833D01*
X562450Y547250D01*
X562367Y546667D01*
X562450Y546083D01*
X562783Y545583D01*
X563283Y545167D01*
X563950Y545000D01*
X564533Y545167D01*
X565033Y545500D01*
G01X569300Y550000D02*
Y545000D01*
G01X568133Y548333D02*
X570467D01*
G01X573650Y545583D02*
X574067Y545250D01*
X574650Y545000D01*
X575150D01*
X575650Y545167D01*
X575983Y545417D01*
X576150Y545750D01*
X576067Y546250D01*
X575733Y546500D01*
X574233Y547000D01*
X573900Y547583D01*
X574067Y548000D01*
X574400Y548250D01*
X574900Y548333D01*
X575400Y548250D01*
X575900Y548000D01*
G01X580917Y543333D02*
X581750Y544167D01*
X582167Y545000D01*
Y548333D01*
X581750Y549167D01*
X580917Y550000D01*
G01X262500Y494000D02*
X694500D01*
G01X262500Y509000D02*
X694500D01*
G01X262500Y524000D02*
X694500D01*
G01X262500Y539000D02*
X694500D01*
G01X262500Y554000D02*
X694500D01*
G01X273000Y609000D02*
Y604000D01*
G01X271083Y609000D02*
X274917D01*
G01X277183Y604000D02*
Y609000D01*
G01Y606583D02*
X277600Y607000D01*
X278017Y607250D01*
X278683Y607333D01*
X279183Y607250D01*
X279767Y606917D01*
X280017Y606417D01*
Y604000D01*
G01X282950Y606250D02*
X285617D01*
X285367Y606833D01*
X284950Y607167D01*
X284367Y607333D01*
X283783Y607250D01*
X283283Y607000D01*
X282950Y606417D01*
X282783Y605917D01*
Y605417D01*
X282950Y604917D01*
X283367Y604417D01*
X283867Y604083D01*
X284450Y604000D01*
X285033Y604167D01*
X285617Y604667D01*
G01X288633Y604000D02*
Y607333D01*
G01Y606667D02*
X289050Y607000D01*
X289467Y607250D01*
X290050Y607333D01*
X290467Y607250D01*
X290967Y607000D01*
G01X292900Y604000D02*
Y607333D01*
G01Y606417D02*
X293150Y606833D01*
X293567Y607167D01*
X294150Y607333D01*
X294733Y607167D01*
X295150Y606833D01*
X295400Y606417D01*
Y604000D01*
G01Y606417D02*
X295650Y606833D01*
X296067Y607167D01*
X296650Y607333D01*
X297233Y607167D01*
X297650Y606833D01*
X297900Y606333D01*
Y604000D01*
G01X302500D02*
Y607333D01*
G01Y606750D02*
X302167Y607083D01*
X301667Y607250D01*
X301083Y607333D01*
X300500Y607167D01*
X300000Y606833D01*
X299667Y606333D01*
X299500Y605667D01*
X299667Y605000D01*
X300000Y604500D01*
X300500Y604167D01*
X301083Y604000D01*
X301667Y604083D01*
X302167Y604333D01*
X302500Y604667D01*
G01X306600Y604000D02*
Y609000D01*
G01X316300Y602333D02*
Y607333D01*
G01Y606583D02*
X316717Y607000D01*
X317133Y607250D01*
X317800Y607333D01*
X318383Y607250D01*
X318967Y606833D01*
X319217Y606250D01*
X319300Y605667D01*
X319217Y605083D01*
X318967Y604500D01*
X318467Y604167D01*
X317800Y604000D01*
X317217Y604083D01*
X316633Y604333D01*
X316300Y604667D01*
G01X324900Y604000D02*
Y607333D01*
G01Y606750D02*
X324567Y607083D01*
X324067Y607250D01*
X323483Y607333D01*
X322900Y607167D01*
X322400Y606833D01*
X322067Y606333D01*
X321900Y605667D01*
X322067Y605000D01*
X322400Y604500D01*
X322900Y604167D01*
X323483Y604000D01*
X324067Y604083D01*
X324567Y604333D01*
X324900Y604667D01*
G01X330500Y609000D02*
Y604000D01*
G01Y604750D02*
X330167Y604333D01*
X329667Y604083D01*
X329083Y604000D01*
X328417Y604167D01*
X327917Y604583D01*
X327583Y605083D01*
X327500Y605667D01*
X327583Y606250D01*
X327917Y606750D01*
X328417Y607167D01*
X329083Y607333D01*
X329667Y607250D01*
X330083Y607083D01*
X330500Y606750D01*
G01X341533Y606917D02*
X340950Y607250D01*
X340450Y607333D01*
X339783Y607167D01*
X339283Y606833D01*
X338950Y606250D01*
X338867Y605667D01*
X338950Y605083D01*
X339283Y604583D01*
X339783Y604167D01*
X340450Y604000D01*
X341033Y604167D01*
X341533Y604500D01*
G01X347300Y604000D02*
Y607333D01*
G01Y606750D02*
X346967Y607083D01*
X346467Y607250D01*
X345883Y607333D01*
X345300Y607167D01*
X344800Y606833D01*
X344467Y606333D01*
X344300Y605667D01*
X344467Y605000D01*
X344800Y604500D01*
X345300Y604167D01*
X345883Y604000D01*
X346467Y604083D01*
X346967Y604333D01*
X347300Y604667D01*
G01X349983Y604000D02*
Y607333D01*
G01Y606500D02*
X350317Y606917D01*
X350817Y607250D01*
X351483Y607333D01*
X352067Y607250D01*
X352567Y606917D01*
X352817Y606333D01*
Y604000D01*
G01X363933Y606917D02*
X363350Y607250D01*
X362850Y607333D01*
X362183Y607167D01*
X361683Y606833D01*
X361350Y606250D01*
X361267Y605667D01*
X361350Y605083D01*
X361683Y604583D01*
X362183Y604167D01*
X362850Y604000D01*
X363433Y604167D01*
X363933Y604500D01*
G01X366783Y604000D02*
Y609000D01*
G01Y606583D02*
X367200Y607000D01*
X367617Y607250D01*
X368283Y607333D01*
X368783Y607250D01*
X369367Y606917D01*
X369617Y606417D01*
Y604000D01*
G01X375300D02*
Y607333D01*
G01Y606750D02*
X374967Y607083D01*
X374467Y607250D01*
X373883Y607333D01*
X373300Y607167D01*
X372800Y606833D01*
X372467Y606333D01*
X372300Y605667D01*
X372467Y605000D01*
X372800Y604500D01*
X373300Y604167D01*
X373883Y604000D01*
X374467Y604083D01*
X374967Y604333D01*
X375300Y604667D01*
G01X377983Y604000D02*
Y607333D01*
G01Y606500D02*
X378317Y606917D01*
X378817Y607250D01*
X379483Y607333D01*
X380067Y607250D01*
X380567Y606917D01*
X380817Y606333D01*
Y604000D01*
G01X383833Y602750D02*
X384417Y602417D01*
X385083Y602333D01*
X385667Y602417D01*
X386167Y602833D01*
X386500Y603417D01*
Y607333D01*
G01Y606667D02*
X386167Y607000D01*
X385667Y607250D01*
X385083Y607333D01*
X384417Y607167D01*
X384000Y606833D01*
X383667Y606250D01*
X383500Y605667D01*
X383583Y605167D01*
X383917Y604583D01*
X384417Y604167D01*
X385083Y604000D01*
X385583Y604083D01*
X386167Y604417D01*
X386500Y604750D01*
G01X389350Y606250D02*
X392017D01*
X391767Y606833D01*
X391350Y607167D01*
X390767Y607333D01*
X390183Y607250D01*
X389683Y607000D01*
X389350Y606417D01*
X389183Y605917D01*
Y605417D01*
X389350Y604917D01*
X389767Y604417D01*
X390267Y604083D01*
X390850Y604000D01*
X391433Y604167D01*
X392017Y604667D01*
G01X401800Y607333D02*
Y604000D01*
G01Y608667D02*
X401633Y608750D01*
Y608917D01*
X401800Y609000D01*
X401967Y608917D01*
Y608750D01*
X401800Y608667D01*
G01X405983Y604000D02*
Y607333D01*
G01Y606500D02*
X406317Y606917D01*
X406817Y607250D01*
X407483Y607333D01*
X408067Y607250D01*
X408567Y606917D01*
X408817Y606333D01*
Y604000D01*
G01X413000Y609000D02*
Y604000D01*
G01X411833Y607333D02*
X414167D01*
G01X418600Y604000D02*
X418100Y604083D01*
X417600Y604417D01*
X417267Y605000D01*
X417100Y605667D01*
X417267Y606333D01*
X417600Y606917D01*
X418100Y607250D01*
X418600Y607333D01*
X419100Y607250D01*
X419600Y606917D01*
X419933Y606333D01*
X420017Y605667D01*
X419933Y605000D01*
X419600Y604417D01*
X419100Y604083D01*
X418600Y604000D01*
G01X429300D02*
Y608250D01*
X429467Y608667D01*
X429800Y608917D01*
X430300Y609000D01*
X430800Y608833D01*
X431050Y608417D01*
G01X430050Y607000D02*
X428383D01*
G01X433983Y607333D02*
Y605000D01*
X434317Y604417D01*
X434817Y604083D01*
X435400Y604000D01*
X435983Y604083D01*
X436483Y604417D01*
X436817Y605000D01*
G01Y604000D02*
Y607333D01*
G01X441000Y604000D02*
Y609000D01*
G01X446600Y604000D02*
Y609000D01*
G01X459133Y606917D02*
X458550Y607250D01*
X458050Y607333D01*
X457383Y607167D01*
X456883Y606833D01*
X456550Y606250D01*
X456467Y605667D01*
X456550Y605083D01*
X456883Y604583D01*
X457383Y604167D01*
X458050Y604000D01*
X458633Y604167D01*
X459133Y604500D01*
G01X463400Y604000D02*
X462900Y604083D01*
X462400Y604417D01*
X462067Y605000D01*
X461900Y605667D01*
X462067Y606333D01*
X462400Y606917D01*
X462900Y607250D01*
X463400Y607333D01*
X463900Y607250D01*
X464400Y606917D01*
X464733Y606333D01*
X464817Y605667D01*
X464733Y605000D01*
X464400Y604417D01*
X463900Y604083D01*
X463400Y604000D01*
G01X467583D02*
Y607333D01*
G01Y606500D02*
X467917Y606917D01*
X468417Y607250D01*
X469083Y607333D01*
X469667Y607250D01*
X470167Y606917D01*
X470417Y606333D01*
Y604000D01*
G01X474600Y609000D02*
Y604000D01*
G01X473433Y607333D02*
X475767D01*
G01X481700Y604000D02*
Y607333D01*
G01Y606750D02*
X481367Y607083D01*
X480867Y607250D01*
X480283Y607333D01*
X479700Y607167D01*
X479200Y606833D01*
X478867Y606333D01*
X478700Y605667D01*
X478867Y605000D01*
X479200Y604500D01*
X479700Y604167D01*
X480283Y604000D01*
X480867Y604083D01*
X481367Y604333D01*
X481700Y604667D01*
G01X487133Y606917D02*
X486550Y607250D01*
X486050Y607333D01*
X485383Y607167D01*
X484883Y606833D01*
X484550Y606250D01*
X484467Y605667D01*
X484550Y605083D01*
X484883Y604583D01*
X485383Y604167D01*
X486050Y604000D01*
X486633Y604167D01*
X487133Y604500D01*
G01X491400Y609000D02*
Y604000D01*
G01X490233Y607333D02*
X492567D01*
G01X270417Y588500D02*
X272500Y593500D01*
X274583Y588500D01*
G01X273833Y590250D02*
X271167D01*
G01X276683Y588500D02*
Y591833D01*
G01Y591000D02*
X277017Y591417D01*
X277517Y591750D01*
X278183Y591833D01*
X278767Y591750D01*
X279267Y591417D01*
X279517Y590833D01*
Y588500D01*
G01X281950Y587000D02*
X282450Y586833D01*
X283117Y587000D01*
X283533Y587333D01*
X283867Y587750D01*
X284367Y589083D01*
X285450Y591833D01*
G01X282783D02*
X284367Y589083D01*
G01X293483Y588500D02*
Y593500D01*
G01Y591083D02*
X293900Y591500D01*
X294317Y591750D01*
X294983Y591833D01*
X295483Y591750D01*
X296067Y591417D01*
X296317Y590917D01*
Y588500D01*
G01X300500D02*
X300000Y588583D01*
X299500Y588917D01*
X299167Y589500D01*
X299000Y590167D01*
X299167Y590833D01*
X299500Y591417D01*
X300000Y591750D01*
X300500Y591833D01*
X301000Y591750D01*
X301500Y591417D01*
X301833Y590833D01*
X301917Y590167D01*
X301833Y589500D01*
X301500Y588917D01*
X301000Y588583D01*
X300500Y588500D01*
G01X306100D02*
Y593500D01*
G01X310450Y590750D02*
X313117D01*
X312867Y591333D01*
X312450Y591667D01*
X311867Y591833D01*
X311283Y591750D01*
X310783Y591500D01*
X310450Y590917D01*
X310283Y590417D01*
Y589917D01*
X310450Y589417D01*
X310867Y588917D01*
X311367Y588583D01*
X311950Y588500D01*
X312533Y588667D01*
X313117Y589167D01*
G01X322900Y593500D02*
Y588500D01*
G01X321733Y591833D02*
X324067D01*
G01X328500Y588500D02*
X328000Y588583D01*
X327500Y588917D01*
X327167Y589500D01*
X327000Y590167D01*
X327167Y590833D01*
X327500Y591417D01*
X328000Y591750D01*
X328500Y591833D01*
X329000Y591750D01*
X329500Y591417D01*
X329833Y590833D01*
X329917Y590167D01*
X329833Y589500D01*
X329500Y588917D01*
X329000Y588583D01*
X328500Y588500D01*
G01X338283D02*
Y593500D01*
G01Y591083D02*
X338700Y591500D01*
X339117Y591750D01*
X339783Y591833D01*
X340283Y591750D01*
X340867Y591417D01*
X341117Y590917D01*
Y588500D01*
G01X345300D02*
X344800Y588583D01*
X344300Y588917D01*
X343967Y589500D01*
X343800Y590167D01*
X343967Y590833D01*
X344300Y591417D01*
X344800Y591750D01*
X345300Y591833D01*
X345800Y591750D01*
X346300Y591417D01*
X346633Y590833D01*
X346717Y590167D01*
X346633Y589500D01*
X346300Y588917D01*
X345800Y588583D01*
X345300Y588500D01*
G01X350900D02*
Y593500D01*
G01X355250Y590750D02*
X357917D01*
X357667Y591333D01*
X357250Y591667D01*
X356667Y591833D01*
X356083Y591750D01*
X355583Y591500D01*
X355250Y590917D01*
X355083Y590417D01*
Y589917D01*
X355250Y589417D01*
X355667Y588917D01*
X356167Y588583D01*
X356750Y588500D01*
X357333Y588667D01*
X357917Y589167D01*
G01X270917Y619000D02*
X273000Y624000D01*
X275083Y619000D01*
G01X274333Y620750D02*
X271667D01*
G01X277183Y619000D02*
Y622333D01*
G01Y621500D02*
X277517Y621917D01*
X278017Y622250D01*
X278683Y622333D01*
X279267Y622250D01*
X279767Y621917D01*
X280017Y621333D01*
Y619000D01*
G01X284200Y624000D02*
Y619000D01*
G01X283033Y622333D02*
X285367D01*
G01X289800D02*
Y619000D01*
G01Y623667D02*
X289633Y623750D01*
Y623917D01*
X289800Y624000D01*
X289967Y623917D01*
Y623750D01*
X289800Y623667D01*
G01X294317Y620667D02*
X296483D01*
G01X299500Y617333D02*
Y622333D01*
G01Y621583D02*
X299917Y622000D01*
X300333Y622250D01*
X301000Y622333D01*
X301583Y622250D01*
X302167Y621833D01*
X302417Y621250D01*
X302500Y620667D01*
X302417Y620083D01*
X302167Y619500D01*
X301667Y619167D01*
X301000Y619000D01*
X300417Y619083D01*
X299833Y619333D01*
X299500Y619667D01*
G01X308100Y619000D02*
Y622333D01*
G01Y621750D02*
X307767Y622083D01*
X307267Y622250D01*
X306683Y622333D01*
X306100Y622167D01*
X305600Y621833D01*
X305267Y621333D01*
X305100Y620667D01*
X305267Y620000D01*
X305600Y619500D01*
X306100Y619167D01*
X306683Y619000D01*
X307267Y619083D01*
X307767Y619333D01*
X308100Y619667D01*
G01X313700Y624000D02*
Y619000D01*
G01Y619750D02*
X313367Y619333D01*
X312867Y619083D01*
X312283Y619000D01*
X311617Y619167D01*
X311117Y619583D01*
X310783Y620083D01*
X310700Y620667D01*
X310783Y621250D01*
X311117Y621750D01*
X311617Y622167D01*
X312283Y622333D01*
X312867Y622250D01*
X313283Y622083D01*
X313700Y621750D01*
G01X322150Y619583D02*
X322567Y619250D01*
X323150Y619000D01*
X323650D01*
X324150Y619167D01*
X324483Y619417D01*
X324650Y619750D01*
X324567Y620250D01*
X324233Y620500D01*
X322733Y621000D01*
X322400Y621583D01*
X322567Y622000D01*
X322900Y622250D01*
X323400Y622333D01*
X323900Y622250D01*
X324400Y622000D01*
G01X329000Y622333D02*
Y619000D01*
G01Y623667D02*
X328833Y623750D01*
Y623917D01*
X329000Y624000D01*
X329167Y623917D01*
Y623750D01*
X329000Y623667D01*
G01X333350Y622333D02*
X335850D01*
X333350Y619000D01*
X335850D01*
G01X338950Y621250D02*
X341617D01*
X341367Y621833D01*
X340950Y622167D01*
X340367Y622333D01*
X339783Y622250D01*
X339283Y622000D01*
X338950Y621417D01*
X338783Y620917D01*
Y620417D01*
X338950Y619917D01*
X339367Y619417D01*
X339867Y619083D01*
X340450Y619000D01*
X341033Y619167D01*
X341617Y619667D01*
G01X270833Y575000D02*
Y580000D01*
X272833D01*
X273500Y579750D01*
X274000Y579167D01*
X274167Y578500D01*
X274000Y577833D01*
X273583Y577333D01*
X272833Y577083D01*
X270833D01*
G01X278100Y575000D02*
Y580000D01*
G01X282283Y578333D02*
Y576000D01*
X282617Y575417D01*
X283117Y575083D01*
X283700Y575000D01*
X284283Y575083D01*
X284783Y575417D01*
X285117Y576000D01*
G01Y575000D02*
Y578333D01*
G01X288133Y573750D02*
X288717Y573417D01*
X289383Y573333D01*
X289967Y573417D01*
X290467Y573833D01*
X290800Y574417D01*
Y578333D01*
G01Y577667D02*
X290467Y578000D01*
X289967Y578250D01*
X289383Y578333D01*
X288717Y578167D01*
X288300Y577833D01*
X287967Y577250D01*
X287800Y576667D01*
X287883Y576167D01*
X288217Y575583D01*
X288717Y575167D01*
X289383Y575000D01*
X289883Y575083D01*
X290467Y575417D01*
X290800Y575750D01*
G01X293733Y573750D02*
X294317Y573417D01*
X294983Y573333D01*
X295567Y573417D01*
X296067Y573833D01*
X296400Y574417D01*
Y578333D01*
G01Y577667D02*
X296067Y578000D01*
X295567Y578250D01*
X294983Y578333D01*
X294317Y578167D01*
X293900Y577833D01*
X293567Y577250D01*
X293400Y576667D01*
X293483Y576167D01*
X293817Y575583D01*
X294317Y575167D01*
X294983Y575000D01*
X295483Y575083D01*
X296067Y575417D01*
X296400Y575750D01*
G01X299250Y577250D02*
X301917D01*
X301667Y577833D01*
X301250Y578167D01*
X300667Y578333D01*
X300083Y578250D01*
X299583Y578000D01*
X299250Y577417D01*
X299083Y576917D01*
Y576417D01*
X299250Y575917D01*
X299667Y575417D01*
X300167Y575083D01*
X300750Y575000D01*
X301333Y575167D01*
X301917Y575667D01*
G01X307600Y580000D02*
Y575000D01*
G01Y575750D02*
X307267Y575333D01*
X306767Y575083D01*
X306183Y575000D01*
X305517Y575167D01*
X305017Y575583D01*
X304683Y576083D01*
X304600Y576667D01*
X304683Y577250D01*
X305017Y577750D01*
X305517Y578167D01*
X306183Y578333D01*
X306767Y578250D01*
X307183Y578083D01*
X307600Y577750D01*
G01X315217Y580000D02*
X317300Y575000D01*
X319383Y580000D01*
G01X322900Y578333D02*
Y575000D01*
G01Y579667D02*
X322733Y579750D01*
Y579917D01*
X322900Y580000D01*
X323067Y579917D01*
Y579750D01*
X322900Y579667D01*
G01X330000Y575000D02*
Y578333D01*
G01Y577750D02*
X329667Y578083D01*
X329167Y578250D01*
X328583Y578333D01*
X328000Y578167D01*
X327500Y577833D01*
X327167Y577333D01*
X327000Y576667D01*
X327167Y576000D01*
X327500Y575500D01*
X328000Y575167D01*
X328583Y575000D01*
X329167Y575083D01*
X329667Y575333D01*
X330000Y575667D01*
G01X333683Y573333D02*
X332850Y574167D01*
X332433Y575000D01*
Y578333D01*
X332850Y579167D01*
X333683Y580000D01*
G01X338283Y575000D02*
Y580000D01*
G01Y577583D02*
X338700Y578000D01*
X339117Y578250D01*
X339783Y578333D01*
X340283Y578250D01*
X340867Y577917D01*
X341117Y577417D01*
Y575000D01*
G01X345300D02*
X344800Y575083D01*
X344300Y575417D01*
X343967Y576000D01*
X343800Y576667D01*
X343967Y577333D01*
X344300Y577917D01*
X344800Y578250D01*
X345300Y578333D01*
X345800Y578250D01*
X346300Y577917D01*
X346633Y577333D01*
X346717Y576667D01*
X346633Y576000D01*
X346300Y575417D01*
X345800Y575083D01*
X345300Y575000D01*
G01X350900D02*
Y580000D01*
G01X355250Y577250D02*
X357917D01*
X357667Y577833D01*
X357250Y578167D01*
X356667Y578333D01*
X356083Y578250D01*
X355583Y578000D01*
X355250Y577417D01*
X355083Y576917D01*
Y576417D01*
X355250Y575917D01*
X355667Y575417D01*
X356167Y575083D01*
X356750Y575000D01*
X357333Y575167D01*
X357917Y575667D01*
G01X366450Y575583D02*
X366867Y575250D01*
X367450Y575000D01*
X367950D01*
X368450Y575167D01*
X368783Y575417D01*
X368950Y575750D01*
X368867Y576250D01*
X368533Y576500D01*
X367033Y577000D01*
X366700Y577583D01*
X366867Y578000D01*
X367200Y578250D01*
X367700Y578333D01*
X368200Y578250D01*
X368700Y578000D01*
G01X373300Y578333D02*
Y575000D01*
G01Y579667D02*
X373133Y579750D01*
Y579917D01*
X373300Y580000D01*
X373467Y579917D01*
Y579750D01*
X373300Y579667D01*
G01X377650Y578333D02*
X380150D01*
X377650Y575000D01*
X380150D01*
G01X383250Y577250D02*
X385917D01*
X385667Y577833D01*
X385250Y578167D01*
X384667Y578333D01*
X384083Y578250D01*
X383583Y578000D01*
X383250Y577417D01*
X383083Y576917D01*
Y576417D01*
X383250Y575917D01*
X383667Y575417D01*
X384167Y575083D01*
X384750Y575000D01*
X385333Y575167D01*
X385917Y575667D01*
G01X391767Y575000D02*
X388433Y576667D01*
X391767Y578333D01*
G01X395700Y575000D02*
Y580000D01*
X394700Y579000D01*
G01Y575000D02*
X396700D01*
G01X399717Y577083D02*
X400300Y577667D01*
X400800Y578000D01*
X401467Y578167D01*
X402050Y578000D01*
X402467Y577667D01*
X402800Y577167D01*
X402883Y576583D01*
X402800Y576083D01*
X402467Y575583D01*
X401967Y575167D01*
X401383Y575000D01*
X400717Y575167D01*
X400133Y575667D01*
X399800Y576417D01*
X399717Y577250D01*
X399883Y578333D01*
X400133Y578917D01*
X400550Y579500D01*
X401133Y579917D01*
X401717Y580000D01*
X402300Y579833D01*
X402717Y579417D01*
G01X410000Y575000D02*
Y578333D01*
G01Y577417D02*
X410250Y577833D01*
X410667Y578167D01*
X411250Y578333D01*
X411833Y578167D01*
X412250Y577833D01*
X412500Y577417D01*
Y575000D01*
G01Y577417D02*
X412750Y577833D01*
X413167Y578167D01*
X413750Y578333D01*
X414333Y578167D01*
X414750Y577833D01*
X415000Y577333D01*
Y575000D01*
G01X418100Y578333D02*
Y575000D01*
G01Y579667D02*
X417933Y579750D01*
Y579917D01*
X418100Y580000D01*
X418267Y579917D01*
Y579750D01*
X418100Y579667D01*
G01X423700Y575000D02*
Y580000D01*
G01X429717Y573333D02*
X430550Y574167D01*
X430967Y575000D01*
Y578333D01*
X430550Y579167D01*
X429717Y580000D01*
G01X270833Y560000D02*
Y565000D01*
X272833D01*
X273500Y564750D01*
X274000Y564167D01*
X274167Y563500D01*
X274000Y562833D01*
X273583Y562333D01*
X272833Y562083D01*
X270833D01*
G01X278100Y560000D02*
Y565000D01*
G01X282283Y563333D02*
Y561000D01*
X282617Y560417D01*
X283117Y560083D01*
X283700Y560000D01*
X284283Y560083D01*
X284783Y560417D01*
X285117Y561000D01*
G01Y560000D02*
Y563333D01*
G01X288133Y558750D02*
X288717Y558417D01*
X289383Y558333D01*
X289967Y558417D01*
X290467Y558833D01*
X290800Y559417D01*
Y563333D01*
G01Y562667D02*
X290467Y563000D01*
X289967Y563250D01*
X289383Y563333D01*
X288717Y563167D01*
X288300Y562833D01*
X287967Y562250D01*
X287800Y561667D01*
X287883Y561167D01*
X288217Y560583D01*
X288717Y560167D01*
X289383Y560000D01*
X289883Y560083D01*
X290467Y560417D01*
X290800Y560750D01*
G01X293733Y558750D02*
X294317Y558417D01*
X294983Y558333D01*
X295567Y558417D01*
X296067Y558833D01*
X296400Y559417D01*
Y563333D01*
G01Y562667D02*
X296067Y563000D01*
X295567Y563250D01*
X294983Y563333D01*
X294317Y563167D01*
X293900Y562833D01*
X293567Y562250D01*
X293400Y561667D01*
X293483Y561167D01*
X293817Y560583D01*
X294317Y560167D01*
X294983Y560000D01*
X295483Y560083D01*
X296067Y560417D01*
X296400Y560750D01*
G01X299250Y562250D02*
X301917D01*
X301667Y562833D01*
X301250Y563167D01*
X300667Y563333D01*
X300083Y563250D01*
X299583Y563000D01*
X299250Y562417D01*
X299083Y561917D01*
Y561417D01*
X299250Y560917D01*
X299667Y560417D01*
X300167Y560083D01*
X300750Y560000D01*
X301333Y560167D01*
X301917Y560667D01*
G01X307600Y565000D02*
Y560000D01*
G01Y560750D02*
X307267Y560333D01*
X306767Y560083D01*
X306183Y560000D01*
X305517Y560167D01*
X305017Y560583D01*
X304683Y561083D01*
X304600Y561667D01*
X304683Y562250D01*
X305017Y562750D01*
X305517Y563167D01*
X306183Y563333D01*
X306767Y563250D01*
X307183Y563083D01*
X307600Y562750D01*
G01X315633Y560000D02*
Y565000D01*
X317633D01*
X318300Y564750D01*
X318800Y564167D01*
X318967Y563500D01*
X318800Y562833D01*
X318383Y562333D01*
X317633Y562083D01*
X315633D01*
G01X322900Y565000D02*
Y560000D01*
G01X320983Y565000D02*
X324817D01*
G01X326750Y560000D02*
Y565000D01*
G01X330250D02*
Y560000D01*
G01Y562500D02*
X326750D01*
G01X333683Y558333D02*
X332850Y559167D01*
X332433Y560000D01*
Y563333D01*
X332850Y564167D01*
X333683Y565000D01*
G01X338283Y560000D02*
Y565000D01*
G01Y562583D02*
X338700Y563000D01*
X339117Y563250D01*
X339783Y563333D01*
X340283Y563250D01*
X340867Y562917D01*
X341117Y562417D01*
Y560000D01*
G01X345300D02*
X344800Y560083D01*
X344300Y560417D01*
X343967Y561000D01*
X343800Y561667D01*
X343967Y562333D01*
X344300Y562917D01*
X344800Y563250D01*
X345300Y563333D01*
X345800Y563250D01*
X346300Y562917D01*
X346633Y562333D01*
X346717Y561667D01*
X346633Y561000D01*
X346300Y560417D01*
X345800Y560083D01*
X345300Y560000D01*
G01X350900D02*
Y565000D01*
G01X355250Y562250D02*
X357917D01*
X357667Y562833D01*
X357250Y563167D01*
X356667Y563333D01*
X356083Y563250D01*
X355583Y563000D01*
X355250Y562417D01*
X355083Y561917D01*
Y561417D01*
X355250Y560917D01*
X355667Y560417D01*
X356167Y560083D01*
X356750Y560000D01*
X357333Y560167D01*
X357917Y560667D01*
G01X366450Y560583D02*
X366867Y560250D01*
X367450Y560000D01*
X367950D01*
X368450Y560167D01*
X368783Y560417D01*
X368950Y560750D01*
X368867Y561250D01*
X368533Y561500D01*
X367033Y562000D01*
X366700Y562583D01*
X366867Y563000D01*
X367200Y563250D01*
X367700Y563333D01*
X368200Y563250D01*
X368700Y563000D01*
G01X373300Y563333D02*
Y560000D01*
G01Y564667D02*
X373133Y564750D01*
Y564917D01*
X373300Y565000D01*
X373467Y564917D01*
Y564750D01*
X373300Y564667D01*
G01X377650Y563333D02*
X380150D01*
X377650Y560000D01*
X380150D01*
G01X383250Y562250D02*
X385917D01*
X385667Y562833D01*
X385250Y563167D01*
X384667Y563333D01*
X384083Y563250D01*
X383583Y563000D01*
X383250Y562417D01*
X383083Y561917D01*
Y561417D01*
X383250Y560917D01*
X383667Y560417D01*
X384167Y560083D01*
X384750Y560000D01*
X385333Y560167D01*
X385917Y560667D01*
G01X388433Y560000D02*
X391767Y561667D01*
X388433Y563333D01*
G01X394617Y560917D02*
X396783D01*
G01Y562417D02*
X394617D01*
G01X401300Y560000D02*
Y565000D01*
X400300Y564000D01*
G01Y560000D02*
X402300D01*
G01X405317Y562083D02*
X405900Y562667D01*
X406400Y563000D01*
X407067Y563167D01*
X407650Y563000D01*
X408067Y562667D01*
X408400Y562167D01*
X408483Y561583D01*
X408400Y561083D01*
X408067Y560583D01*
X407567Y560167D01*
X406983Y560000D01*
X406317Y560167D01*
X405733Y560667D01*
X405400Y561417D01*
X405317Y562250D01*
X405483Y563333D01*
X405733Y563917D01*
X406150Y564500D01*
X406733Y564917D01*
X407317Y565000D01*
X407900Y564833D01*
X408317Y564417D01*
G01X415600Y560000D02*
Y563333D01*
G01Y562417D02*
X415850Y562833D01*
X416267Y563167D01*
X416850Y563333D01*
X417433Y563167D01*
X417850Y562833D01*
X418100Y562417D01*
Y560000D01*
G01Y562417D02*
X418350Y562833D01*
X418767Y563167D01*
X419350Y563333D01*
X419933Y563167D01*
X420350Y562833D01*
X420600Y562333D01*
Y560000D01*
G01X423700Y563333D02*
Y560000D01*
G01Y564667D02*
X423533Y564750D01*
Y564917D01*
X423700Y565000D01*
X423867Y564917D01*
Y564750D01*
X423700Y564667D01*
G01X429300Y560000D02*
Y565000D01*
G01X435317Y558333D02*
X436150Y559167D01*
X436567Y560000D01*
Y563333D01*
X436150Y564167D01*
X435317Y565000D01*
G01X262500Y569000D02*
X694500D01*
G01X269717Y637573D02*
X270717Y634240D01*
X271800Y637573D01*
X272883Y634240D01*
X273883Y637573D01*
G01X277400D02*
Y634240D01*
G01Y638907D02*
X277233Y638990D01*
Y639157D01*
X277400Y639240D01*
X277567Y639157D01*
Y638990D01*
X277400Y638907D01*
G01X283000Y639240D02*
Y634240D01*
G01X281833Y637573D02*
X284167D01*
G01X287183Y634240D02*
Y639240D01*
G01Y636823D02*
X287600Y637240D01*
X288017Y637490D01*
X288683Y637573D01*
X289183Y637490D01*
X289767Y637157D01*
X290017Y636657D01*
Y634240D01*
G01X294200D02*
X293700Y634323D01*
X293200Y634657D01*
X292867Y635240D01*
X292700Y635907D01*
X292867Y636573D01*
X293200Y637157D01*
X293700Y637490D01*
X294200Y637573D01*
X294700Y637490D01*
X295200Y637157D01*
X295533Y636573D01*
X295617Y635907D01*
X295533Y635240D01*
X295200Y634657D01*
X294700Y634323D01*
X294200Y634240D01*
G01X298383Y637573D02*
Y635240D01*
X298717Y634657D01*
X299217Y634323D01*
X299800Y634240D01*
X300383Y634323D01*
X300883Y634657D01*
X301217Y635240D01*
G01Y634240D02*
Y637573D01*
G01X305400Y639240D02*
Y634240D01*
G01X304233Y637573D02*
X306567D01*
G01X317933Y637157D02*
X317350Y637490D01*
X316850Y637573D01*
X316183Y637407D01*
X315683Y637073D01*
X315350Y636490D01*
X315267Y635907D01*
X315350Y635323D01*
X315683Y634823D01*
X316183Y634407D01*
X316850Y634240D01*
X317433Y634407D01*
X317933Y634740D01*
G01X322200Y634240D02*
X321700Y634323D01*
X321200Y634657D01*
X320867Y635240D01*
X320700Y635907D01*
X320867Y636573D01*
X321200Y637157D01*
X321700Y637490D01*
X322200Y637573D01*
X322700Y637490D01*
X323200Y637157D01*
X323533Y636573D01*
X323617Y635907D01*
X323533Y635240D01*
X323200Y634657D01*
X322700Y634323D01*
X322200Y634240D01*
G01X326383D02*
Y637573D01*
G01Y636740D02*
X326717Y637157D01*
X327217Y637490D01*
X327883Y637573D01*
X328467Y637490D01*
X328967Y637157D01*
X329217Y636573D01*
Y634240D01*
G01X331983D02*
Y637573D01*
G01Y636740D02*
X332317Y637157D01*
X332817Y637490D01*
X333483Y637573D01*
X334067Y637490D01*
X334567Y637157D01*
X334817Y636573D01*
Y634240D01*
G01X337750Y636490D02*
X340417D01*
X340167Y637073D01*
X339750Y637407D01*
X339167Y637573D01*
X338583Y637490D01*
X338083Y637240D01*
X337750Y636657D01*
X337583Y636157D01*
Y635657D01*
X337750Y635157D01*
X338167Y634657D01*
X338667Y634323D01*
X339250Y634240D01*
X339833Y634407D01*
X340417Y634907D01*
G01X345933Y637157D02*
X345350Y637490D01*
X344850Y637573D01*
X344183Y637407D01*
X343683Y637073D01*
X343350Y636490D01*
X343267Y635907D01*
X343350Y635323D01*
X343683Y634823D01*
X344183Y634407D01*
X344850Y634240D01*
X345433Y634407D01*
X345933Y634740D01*
G01X350200Y639240D02*
Y634240D01*
G01X349033Y637573D02*
X351367D01*
G01X355800D02*
Y634240D01*
G01Y638907D02*
X355633Y638990D01*
Y639157D01*
X355800Y639240D01*
X355967Y639157D01*
Y638990D01*
X355800Y638907D01*
G01X359983Y634240D02*
Y637573D01*
G01Y636740D02*
X360317Y637157D01*
X360817Y637490D01*
X361483Y637573D01*
X362067Y637490D01*
X362567Y637157D01*
X362817Y636573D01*
Y634240D01*
G01X365833Y632990D02*
X366417Y632657D01*
X367083Y632573D01*
X367667Y632657D01*
X368167Y633073D01*
X368500Y633657D01*
Y637573D01*
G01Y636907D02*
X368167Y637240D01*
X367667Y637490D01*
X367083Y637573D01*
X366417Y637407D01*
X366000Y637073D01*
X365667Y636490D01*
X365500Y635907D01*
X365583Y635407D01*
X365917Y634823D01*
X366417Y634407D01*
X367083Y634240D01*
X367583Y634323D01*
X368167Y634657D01*
X368500Y634990D01*
G01X378200Y639240D02*
Y634240D01*
G01X377033Y637573D02*
X379367D01*
G01X383800Y634240D02*
X383300Y634323D01*
X382800Y634657D01*
X382467Y635240D01*
X382300Y635907D01*
X382467Y636573D01*
X382800Y637157D01*
X383300Y637490D01*
X383800Y637573D01*
X384300Y637490D01*
X384800Y637157D01*
X385133Y636573D01*
X385217Y635907D01*
X385133Y635240D01*
X384800Y634657D01*
X384300Y634323D01*
X383800Y634240D01*
G01X395000D02*
X394500Y634323D01*
X394000Y634657D01*
X393667Y635240D01*
X393500Y635907D01*
X393667Y636573D01*
X394000Y637157D01*
X394500Y637490D01*
X395000Y637573D01*
X395500Y637490D01*
X396000Y637157D01*
X396333Y636573D01*
X396417Y635907D01*
X396333Y635240D01*
X396000Y634657D01*
X395500Y634323D01*
X395000Y634240D01*
G01X400600Y639240D02*
Y634240D01*
G01X399433Y637573D02*
X401767D01*
G01X404783Y634240D02*
Y639240D01*
G01Y636823D02*
X405200Y637240D01*
X405617Y637490D01*
X406283Y637573D01*
X406783Y637490D01*
X407367Y637157D01*
X407617Y636657D01*
Y634240D01*
G01X410550Y636490D02*
X413217D01*
X412967Y637073D01*
X412550Y637407D01*
X411967Y637573D01*
X411383Y637490D01*
X410883Y637240D01*
X410550Y636657D01*
X410383Y636157D01*
Y635657D01*
X410550Y635157D01*
X410967Y634657D01*
X411467Y634323D01*
X412050Y634240D01*
X412633Y634407D01*
X413217Y634907D01*
G01X416233Y634240D02*
Y637573D01*
G01Y636907D02*
X416650Y637240D01*
X417067Y637490D01*
X417650Y637573D01*
X418067Y637490D01*
X418567Y637240D01*
G01X428600Y634240D02*
Y639240D01*
G01X435700Y634240D02*
Y637573D01*
G01Y636990D02*
X435367Y637323D01*
X434867Y637490D01*
X434283Y637573D01*
X433700Y637407D01*
X433200Y637073D01*
X432867Y636573D01*
X432700Y635907D01*
X432867Y635240D01*
X433200Y634740D01*
X433700Y634407D01*
X434283Y634240D01*
X434867Y634323D01*
X435367Y634573D01*
X435700Y634907D01*
G01X438050Y632740D02*
X438550Y632573D01*
X439217Y632740D01*
X439633Y633073D01*
X439967Y633490D01*
X440467Y634823D01*
X441550Y637573D01*
G01X438883D02*
X440467Y634823D01*
G01X444150Y636490D02*
X446817D01*
X446567Y637073D01*
X446150Y637407D01*
X445567Y637573D01*
X444983Y637490D01*
X444483Y637240D01*
X444150Y636657D01*
X443983Y636157D01*
Y635657D01*
X444150Y635157D01*
X444567Y634657D01*
X445067Y634323D01*
X445650Y634240D01*
X446233Y634407D01*
X446817Y634907D01*
G01X449833Y634240D02*
Y637573D01*
G01Y636907D02*
X450250Y637240D01*
X450667Y637490D01*
X451250Y637573D01*
X451667Y637490D01*
X452167Y637240D01*
G01X455350Y634823D02*
X455767Y634490D01*
X456350Y634240D01*
X456850D01*
X457350Y634407D01*
X457683Y634657D01*
X457850Y634990D01*
X457767Y635490D01*
X457433Y635740D01*
X455933Y636240D01*
X455600Y636823D01*
X455767Y637240D01*
X456100Y637490D01*
X456600Y637573D01*
X457100Y637490D01*
X457600Y637240D01*
G01X462617Y632573D02*
X463450Y633407D01*
X463867Y634240D01*
Y637573D01*
X463450Y638407D01*
X462617Y639240D01*
G01X270257Y644950D02*
Y649950D01*
X271923D01*
X272590Y649700D01*
X273090Y649367D01*
X273507Y648867D01*
X273840Y648283D01*
X273923Y647450D01*
X273840Y646617D01*
X273507Y646033D01*
X273090Y645533D01*
X272590Y645200D01*
X271923Y644950D01*
X270257D01*
G01X276440Y647200D02*
X279107D01*
X278857Y647783D01*
X278440Y648117D01*
X277857Y648283D01*
X277273Y648200D01*
X276773Y647950D01*
X276440Y647367D01*
X276273Y646867D01*
Y646367D01*
X276440Y645867D01*
X276857Y645367D01*
X277357Y645033D01*
X277940Y644950D01*
X278523Y645117D01*
X279107Y645617D01*
G01X283290Y644950D02*
Y649950D01*
G01X287640Y647200D02*
X290307D01*
X290057Y647783D01*
X289640Y648117D01*
X289057Y648283D01*
X288473Y648200D01*
X287973Y647950D01*
X287640Y647367D01*
X287473Y646867D01*
Y646367D01*
X287640Y645867D01*
X288057Y645367D01*
X288557Y645033D01*
X289140Y644950D01*
X289723Y645117D01*
X290307Y645617D01*
G01X294490Y649950D02*
Y644950D01*
G01X293323Y648283D02*
X295657D01*
G01X298840Y647200D02*
X301507D01*
X301257Y647783D01*
X300840Y648117D01*
X300257Y648283D01*
X299673Y648200D01*
X299173Y647950D01*
X298840Y647367D01*
X298673Y646867D01*
Y646367D01*
X298840Y645867D01*
X299257Y645367D01*
X299757Y645033D01*
X300340Y644950D01*
X300923Y645117D01*
X301507Y645617D01*
G01X309873Y644950D02*
Y648283D01*
G01Y647450D02*
X310207Y647867D01*
X310707Y648200D01*
X311373Y648283D01*
X311957Y648200D01*
X312457Y647867D01*
X312707Y647283D01*
Y644950D01*
G01X316890D02*
X316390Y645033D01*
X315890Y645367D01*
X315557Y645950D01*
X315390Y646617D01*
X315557Y647283D01*
X315890Y647867D01*
X316390Y648200D01*
X316890Y648283D01*
X317390Y648200D01*
X317890Y647867D01*
X318223Y647283D01*
X318307Y646617D01*
X318223Y645950D01*
X317890Y645367D01*
X317390Y645033D01*
X316890Y644950D01*
G01X321073D02*
Y648283D01*
G01Y647450D02*
X321407Y647867D01*
X321907Y648200D01*
X322573Y648283D01*
X323157Y648200D01*
X323657Y647867D01*
X323907Y647283D01*
Y644950D01*
G01X327007Y646617D02*
X329173D01*
G01X333190Y644950D02*
Y649200D01*
X333357Y649617D01*
X333690Y649867D01*
X334190Y649950D01*
X334690Y649783D01*
X334940Y649367D01*
G01X333940Y647950D02*
X332273D01*
G01X337873Y648283D02*
Y645950D01*
X338207Y645367D01*
X338707Y645033D01*
X339290Y644950D01*
X339873Y645033D01*
X340373Y645367D01*
X340707Y645950D01*
G01Y644950D02*
Y648283D01*
G01X343473Y644950D02*
Y648283D01*
G01Y647450D02*
X343807Y647867D01*
X344307Y648200D01*
X344973Y648283D01*
X345557Y648200D01*
X346057Y647867D01*
X346307Y647283D01*
Y644950D01*
G01X351823Y647867D02*
X351240Y648200D01*
X350740Y648283D01*
X350073Y648117D01*
X349573Y647783D01*
X349240Y647200D01*
X349157Y646617D01*
X349240Y646033D01*
X349573Y645533D01*
X350073Y645117D01*
X350740Y644950D01*
X351323Y645117D01*
X351823Y645450D01*
G01X356090Y649950D02*
Y644950D01*
G01X354923Y648283D02*
X357257D01*
G01X361690D02*
Y644950D01*
G01Y649617D02*
X361523Y649700D01*
Y649867D01*
X361690Y649950D01*
X361857Y649867D01*
Y649700D01*
X361690Y649617D01*
G01X367290Y644950D02*
X366790Y645033D01*
X366290Y645367D01*
X365957Y645950D01*
X365790Y646617D01*
X365957Y647283D01*
X366290Y647867D01*
X366790Y648200D01*
X367290Y648283D01*
X367790Y648200D01*
X368290Y647867D01*
X368623Y647283D01*
X368707Y646617D01*
X368623Y645950D01*
X368290Y645367D01*
X367790Y645033D01*
X367290Y644950D01*
G01X371473D02*
Y648283D01*
G01Y647450D02*
X371807Y647867D01*
X372307Y648200D01*
X372973Y648283D01*
X373557Y648200D01*
X374057Y647867D01*
X374307Y647283D01*
Y644950D01*
G01X379990D02*
Y648283D01*
G01Y647700D02*
X379657Y648033D01*
X379157Y648200D01*
X378573Y648283D01*
X377990Y648117D01*
X377490Y647783D01*
X377157Y647283D01*
X376990Y646617D01*
X377157Y645950D01*
X377490Y645450D01*
X377990Y645117D01*
X378573Y644950D01*
X379157Y645033D01*
X379657Y645283D01*
X379990Y645617D01*
G01X384090Y644950D02*
Y649950D01*
G01X393790Y643283D02*
Y648283D01*
G01Y647533D02*
X394207Y647950D01*
X394623Y648200D01*
X395290Y648283D01*
X395873Y648200D01*
X396457Y647783D01*
X396707Y647200D01*
X396790Y646617D01*
X396707Y646033D01*
X396457Y645450D01*
X395957Y645117D01*
X395290Y644950D01*
X394707Y645033D01*
X394123Y645283D01*
X393790Y645617D01*
G01X402390Y644950D02*
Y648283D01*
G01Y647700D02*
X402057Y648033D01*
X401557Y648200D01*
X400973Y648283D01*
X400390Y648117D01*
X399890Y647783D01*
X399557Y647283D01*
X399390Y646617D01*
X399557Y645950D01*
X399890Y645450D01*
X400390Y645117D01*
X400973Y644950D01*
X401557Y645033D01*
X402057Y645283D01*
X402390Y645617D01*
G01X407990Y649950D02*
Y644950D01*
G01Y645700D02*
X407657Y645283D01*
X407157Y645033D01*
X406573Y644950D01*
X405907Y645117D01*
X405407Y645533D01*
X405073Y646033D01*
X404990Y646617D01*
X405073Y647200D01*
X405407Y647700D01*
X405907Y648117D01*
X406573Y648283D01*
X407157Y648200D01*
X407573Y648033D01*
X407990Y647700D01*
G01X417690Y648283D02*
Y644950D01*
G01Y649617D02*
X417523Y649700D01*
Y649867D01*
X417690Y649950D01*
X417857Y649867D01*
Y649700D01*
X417690Y649617D01*
G01X421873Y644950D02*
Y648283D01*
G01Y647450D02*
X422207Y647867D01*
X422707Y648200D01*
X423373Y648283D01*
X423957Y648200D01*
X424457Y647867D01*
X424707Y647283D01*
Y644950D01*
G01X435990D02*
Y648283D01*
G01Y647700D02*
X435657Y648033D01*
X435157Y648200D01*
X434573Y648283D01*
X433990Y648117D01*
X433490Y647783D01*
X433157Y647283D01*
X432990Y646617D01*
X433157Y645950D01*
X433490Y645450D01*
X433990Y645117D01*
X434573Y644950D01*
X435157Y645033D01*
X435657Y645283D01*
X435990Y645617D01*
G01X440090Y644950D02*
Y649950D01*
G01X445690Y644950D02*
Y649950D01*
G01X455390Y643283D02*
Y648283D01*
G01Y647533D02*
X455807Y647950D01*
X456223Y648200D01*
X456890Y648283D01*
X457473Y648200D01*
X458057Y647783D01*
X458307Y647200D01*
X458390Y646617D01*
X458307Y646033D01*
X458057Y645450D01*
X457557Y645117D01*
X456890Y644950D01*
X456307Y645033D01*
X455723Y645283D01*
X455390Y645617D01*
G01X461323Y644950D02*
Y648283D01*
G01Y647617D02*
X461740Y647950D01*
X462157Y648200D01*
X462740Y648283D01*
X463157Y648200D01*
X463657Y647950D01*
G01X468090Y644950D02*
X467590Y645033D01*
X467090Y645367D01*
X466757Y645950D01*
X466590Y646617D01*
X466757Y647283D01*
X467090Y647867D01*
X467590Y648200D01*
X468090Y648283D01*
X468590Y648200D01*
X469090Y647867D01*
X469423Y647283D01*
X469507Y646617D01*
X469423Y645950D01*
X469090Y645367D01*
X468590Y645033D01*
X468090Y644950D01*
G01X475190Y649950D02*
Y644950D01*
G01Y645700D02*
X474857Y645283D01*
X474357Y645033D01*
X473773Y644950D01*
X473107Y645117D01*
X472607Y645533D01*
X472273Y646033D01*
X472190Y646617D01*
X472273Y647200D01*
X472607Y647700D01*
X473107Y648117D01*
X473773Y648283D01*
X474357Y648200D01*
X474773Y648033D01*
X475190Y647700D01*
G01X477873Y648283D02*
Y645950D01*
X478207Y645367D01*
X478707Y645033D01*
X479290Y644950D01*
X479873Y645033D01*
X480373Y645367D01*
X480707Y645950D01*
G01Y644950D02*
Y648283D01*
G01X486223Y647867D02*
X485640Y648200D01*
X485140Y648283D01*
X484473Y648117D01*
X483973Y647783D01*
X483640Y647200D01*
X483557Y646617D01*
X483640Y646033D01*
X483973Y645533D01*
X484473Y645117D01*
X485140Y644950D01*
X485723Y645117D01*
X486223Y645450D01*
G01X490490Y649950D02*
Y644950D01*
G01X489323Y648283D02*
X491657D01*
G01X494840Y645533D02*
X495257Y645200D01*
X495840Y644950D01*
X496340D01*
X496840Y645117D01*
X497173Y645367D01*
X497340Y645700D01*
X497257Y646200D01*
X496923Y646450D01*
X495423Y646950D01*
X495090Y647533D01*
X495257Y647950D01*
X495590Y648200D01*
X496090Y648283D01*
X496590Y648200D01*
X497090Y647950D01*
G01X501690Y644783D02*
X501523Y644867D01*
Y645033D01*
X501690Y645117D01*
X501857Y645033D01*
Y644867D01*
X501690Y644783D01*
G01X506873Y643283D02*
X506040Y644117D01*
X505623Y644950D01*
Y648283D01*
X506040Y649117D01*
X506873Y649950D01*
G01X511890D02*
X513890D01*
G01X512890D02*
Y644950D01*
G01X511890D02*
X513890D01*
G01X517240Y645533D02*
X517657Y645200D01*
X518240Y644950D01*
X518740D01*
X519240Y645117D01*
X519573Y645367D01*
X519740Y645700D01*
X519657Y646200D01*
X519323Y646450D01*
X517823Y646950D01*
X517490Y647533D01*
X517657Y647950D01*
X517990Y648200D01*
X518490Y648283D01*
X518990Y648200D01*
X519490Y647950D01*
G01X524090Y644950D02*
X523590Y645033D01*
X523090Y645367D01*
X522757Y645950D01*
X522590Y646617D01*
X522757Y647283D01*
X523090Y647867D01*
X523590Y648200D01*
X524090Y648283D01*
X524590Y648200D01*
X525090Y647867D01*
X525423Y647283D01*
X525507Y646617D01*
X525423Y645950D01*
X525090Y645367D01*
X524590Y645033D01*
X524090Y644950D01*
G01X529690D02*
Y649950D01*
G01X536790Y644950D02*
Y648283D01*
G01Y647700D02*
X536457Y648033D01*
X535957Y648200D01*
X535373Y648283D01*
X534790Y648117D01*
X534290Y647783D01*
X533957Y647283D01*
X533790Y646617D01*
X533957Y645950D01*
X534290Y645450D01*
X534790Y645117D01*
X535373Y644950D01*
X535957Y645033D01*
X536457Y645283D01*
X536790Y645617D01*
G01X540890Y649950D02*
Y644950D01*
G01X539723Y648283D02*
X542057D01*
G01X545240Y647200D02*
X547907D01*
X547657Y647783D01*
X547240Y648117D01*
X546657Y648283D01*
X546073Y648200D01*
X545573Y647950D01*
X545240Y647367D01*
X545073Y646867D01*
Y646367D01*
X545240Y645867D01*
X545657Y645367D01*
X546157Y645033D01*
X546740Y644950D01*
X547323Y645117D01*
X547907Y645617D01*
G01X556190Y643283D02*
Y648283D01*
G01Y647533D02*
X556607Y647950D01*
X557023Y648200D01*
X557690Y648283D01*
X558273Y648200D01*
X558857Y647783D01*
X559107Y647200D01*
X559190Y646617D01*
X559107Y646033D01*
X558857Y645450D01*
X558357Y645117D01*
X557690Y644950D01*
X557107Y645033D01*
X556523Y645283D01*
X556190Y645617D01*
G01X564790Y644950D02*
Y648283D01*
G01Y647700D02*
X564457Y648033D01*
X563957Y648200D01*
X563373Y648283D01*
X562790Y648117D01*
X562290Y647783D01*
X561957Y647283D01*
X561790Y646617D01*
X561957Y645950D01*
X562290Y645450D01*
X562790Y645117D01*
X563373Y644950D01*
X563957Y645033D01*
X564457Y645283D01*
X564790Y645617D01*
G01X570390Y649950D02*
Y644950D01*
G01Y645700D02*
X570057Y645283D01*
X569557Y645033D01*
X568973Y644950D01*
X568307Y645117D01*
X567807Y645533D01*
X567473Y646033D01*
X567390Y646617D01*
X567473Y647200D01*
X567807Y647700D01*
X568307Y648117D01*
X568973Y648283D01*
X569557Y648200D01*
X569973Y648033D01*
X570390Y647700D01*
G01X395000Y364500D02*
Y175500D01*
G01X402977Y229887D02*
X403310Y230137D01*
X403560Y230553D01*
X403727Y231137D01*
X403560Y231637D01*
X403227Y231970D01*
X402643Y232220D01*
X400393D01*
Y227220D01*
X403143D01*
X403727Y227553D01*
X404060Y228053D01*
X404227Y228637D01*
X404060Y229220D01*
X403560Y229720D01*
X402977Y229887D01*
X400393D01*
G01X406493Y230553D02*
Y228220D01*
X406827Y227637D01*
X407327Y227303D01*
X407910Y227220D01*
X408493Y227303D01*
X408993Y227637D01*
X409327Y228220D01*
G01Y227220D02*
Y230553D01*
G01X411010Y227220D02*
Y230553D01*
G01Y229637D02*
X411260Y230053D01*
X411677Y230387D01*
X412260Y230553D01*
X412843Y230387D01*
X413260Y230053D01*
X413510Y229637D01*
Y227220D01*
G01Y229637D02*
X413760Y230053D01*
X414177Y230387D01*
X414760Y230553D01*
X415343Y230387D01*
X415760Y230053D01*
X416010Y229553D01*
Y227220D01*
G01X417610Y225553D02*
Y230553D01*
G01Y229803D02*
X418027Y230220D01*
X418443Y230470D01*
X419110Y230553D01*
X419693Y230470D01*
X420277Y230053D01*
X420527Y229470D01*
X420610Y228887D01*
X420527Y228303D01*
X420277Y227720D01*
X419777Y227387D01*
X419110Y227220D01*
X418527Y227303D01*
X417943Y227553D01*
X417610Y227887D01*
G01X401520Y268213D02*
X403020Y264880D01*
X404520Y268213D01*
G01X408620D02*
Y264880D01*
G01Y269547D02*
X408453Y269630D01*
Y269797D01*
X408620Y269880D01*
X408787Y269797D01*
Y269630D01*
X408620Y269547D01*
G01X415720Y264880D02*
Y268213D01*
G01Y267630D02*
X415387Y267963D01*
X414887Y268130D01*
X414303Y268213D01*
X413720Y268047D01*
X413220Y267713D01*
X412887Y267213D01*
X412720Y266547D01*
X412887Y265880D01*
X413220Y265380D01*
X413720Y265047D01*
X414303Y264880D01*
X414887Y264963D01*
X415387Y265213D01*
X415720Y265547D01*
G01X401067Y277360D02*
Y282360D01*
X402733D01*
X403400Y282110D01*
X403900Y281777D01*
X404317Y281277D01*
X404650Y280693D01*
X404733Y279860D01*
X404650Y279027D01*
X404317Y278443D01*
X403900Y277943D01*
X403400Y277610D01*
X402733Y277360D01*
X401067D01*
G01X408500Y280693D02*
Y277360D01*
G01Y282027D02*
X408333Y282110D01*
Y282277D01*
X408500Y282360D01*
X408667Y282277D01*
Y282110D01*
X408500Y282027D01*
G01X411600Y277360D02*
Y280693D01*
G01Y279777D02*
X411850Y280193D01*
X412267Y280527D01*
X412850Y280693D01*
X413433Y280527D01*
X413850Y280193D01*
X414100Y279777D01*
Y277360D01*
G01Y279777D02*
X414350Y280193D01*
X414767Y280527D01*
X415350Y280693D01*
X415933Y280527D01*
X416350Y280193D01*
X416600Y279693D01*
Y277360D01*
G01X418200Y275693D02*
Y280693D01*
G01Y279943D02*
X418617Y280360D01*
X419033Y280610D01*
X419700Y280693D01*
X420283Y280610D01*
X420867Y280193D01*
X421117Y279610D01*
X421200Y279027D01*
X421117Y278443D01*
X420867Y277860D01*
X420367Y277527D01*
X419700Y277360D01*
X419117Y277443D01*
X418533Y277693D01*
X418200Y278027D01*
G01X425300Y277360D02*
Y282360D01*
G01X429650Y279610D02*
X432317D01*
X432067Y280193D01*
X431650Y280527D01*
X431067Y280693D01*
X430483Y280610D01*
X429983Y280360D01*
X429650Y279777D01*
X429483Y279277D01*
Y278777D01*
X429650Y278277D01*
X430067Y277777D01*
X430567Y277443D01*
X431150Y277360D01*
X431733Y277527D01*
X432317Y278027D01*
G01X441600Y277360D02*
Y281610D01*
X441767Y282027D01*
X442100Y282277D01*
X442600Y282360D01*
X443100Y282193D01*
X443350Y281777D01*
G01X442350Y280360D02*
X440683D01*
G01X447700Y277360D02*
X447200Y277443D01*
X446700Y277777D01*
X446367Y278360D01*
X446200Y279027D01*
X446367Y279693D01*
X446700Y280277D01*
X447200Y280610D01*
X447700Y280693D01*
X448200Y280610D01*
X448700Y280277D01*
X449033Y279693D01*
X449117Y279027D01*
X449033Y278360D01*
X448700Y277777D01*
X448200Y277443D01*
X447700Y277360D01*
G01X452133D02*
Y280693D01*
G01Y280027D02*
X452550Y280360D01*
X452967Y280610D01*
X453550Y280693D01*
X453967Y280610D01*
X454467Y280360D01*
G01X464500Y277360D02*
X464000Y277443D01*
X463500Y277777D01*
X463167Y278360D01*
X463000Y279027D01*
X463167Y279693D01*
X463500Y280277D01*
X464000Y280610D01*
X464500Y280693D01*
X465000Y280610D01*
X465500Y280277D01*
X465833Y279693D01*
X465917Y279027D01*
X465833Y278360D01*
X465500Y277777D01*
X465000Y277443D01*
X464500Y277360D01*
G01X468683Y280693D02*
Y278360D01*
X469017Y277777D01*
X469517Y277443D01*
X470100Y277360D01*
X470683Y277443D01*
X471183Y277777D01*
X471517Y278360D01*
G01Y277360D02*
Y280693D01*
G01X475700Y282360D02*
Y277360D01*
G01X474533Y280693D02*
X476867D01*
G01X480050Y279610D02*
X482717D01*
X482467Y280193D01*
X482050Y280527D01*
X481467Y280693D01*
X480883Y280610D01*
X480383Y280360D01*
X480050Y279777D01*
X479883Y279277D01*
Y278777D01*
X480050Y278277D01*
X480467Y277777D01*
X480967Y277443D01*
X481550Y277360D01*
X482133Y277527D01*
X482717Y278027D01*
G01X485733Y277360D02*
Y280693D01*
G01Y280027D02*
X486150Y280360D01*
X486567Y280610D01*
X487150Y280693D01*
X487567Y280610D01*
X488067Y280360D01*
G01X499600Y277360D02*
Y280693D01*
G01Y280110D02*
X499267Y280443D01*
X498767Y280610D01*
X498183Y280693D01*
X497600Y280527D01*
X497100Y280193D01*
X496767Y279693D01*
X496600Y279027D01*
X496767Y278360D01*
X497100Y277860D01*
X497600Y277527D01*
X498183Y277360D01*
X498767Y277443D01*
X499267Y277693D01*
X499600Y278027D01*
G01X502283Y277360D02*
Y280693D01*
G01Y279860D02*
X502617Y280277D01*
X503117Y280610D01*
X503783Y280693D01*
X504367Y280610D01*
X504867Y280277D01*
X505117Y279693D01*
Y277360D01*
G01X510800Y282360D02*
Y277360D01*
G01Y278110D02*
X510467Y277693D01*
X509967Y277443D01*
X509383Y277360D01*
X508717Y277527D01*
X508217Y277943D01*
X507883Y278443D01*
X507800Y279027D01*
X507883Y279610D01*
X508217Y280110D01*
X508717Y280527D01*
X509383Y280693D01*
X509967Y280610D01*
X510383Y280443D01*
X510800Y280110D01*
G01X520500Y280693D02*
Y277360D01*
G01Y282027D02*
X520333Y282110D01*
Y282277D01*
X520500Y282360D01*
X520667Y282277D01*
Y282110D01*
X520500Y282027D01*
G01X524683Y277360D02*
Y280693D01*
G01Y279860D02*
X525017Y280277D01*
X525517Y280610D01*
X526183Y280693D01*
X526767Y280610D01*
X527267Y280277D01*
X527517Y279693D01*
Y277360D01*
G01X530283D02*
Y280693D01*
G01Y279860D02*
X530617Y280277D01*
X531117Y280610D01*
X531783Y280693D01*
X532367Y280610D01*
X532867Y280277D01*
X533117Y279693D01*
Y277360D01*
G01X536050Y279610D02*
X538717D01*
X538467Y280193D01*
X538050Y280527D01*
X537467Y280693D01*
X536883Y280610D01*
X536383Y280360D01*
X536050Y279777D01*
X535883Y279277D01*
Y278777D01*
X536050Y278277D01*
X536467Y277777D01*
X536967Y277443D01*
X537550Y277360D01*
X538133Y277527D01*
X538717Y278027D01*
G01X541733Y277360D02*
Y280693D01*
G01Y280027D02*
X542150Y280360D01*
X542567Y280610D01*
X543150Y280693D01*
X543567Y280610D01*
X544067Y280360D01*
G01X554100Y277360D02*
Y282360D01*
G01X561200Y277360D02*
Y280693D01*
G01Y280110D02*
X560867Y280443D01*
X560367Y280610D01*
X559783Y280693D01*
X559200Y280527D01*
X558700Y280193D01*
X558367Y279693D01*
X558200Y279027D01*
X558367Y278360D01*
X558700Y277860D01*
X559200Y277527D01*
X559783Y277360D01*
X560367Y277443D01*
X560867Y277693D01*
X561200Y278027D01*
G01X564050Y277943D02*
X564467Y277610D01*
X565050Y277360D01*
X565550D01*
X566050Y277527D01*
X566383Y277777D01*
X566550Y278110D01*
X566467Y278610D01*
X566133Y278860D01*
X564633Y279360D01*
X564300Y279943D01*
X564467Y280360D01*
X564800Y280610D01*
X565300Y280693D01*
X565800Y280610D01*
X566300Y280360D01*
G01X569650Y279610D02*
X572317D01*
X572067Y280193D01*
X571650Y280527D01*
X571067Y280693D01*
X570483Y280610D01*
X569983Y280360D01*
X569650Y279777D01*
X569483Y279277D01*
Y278777D01*
X569650Y278277D01*
X570067Y277777D01*
X570567Y277443D01*
X571150Y277360D01*
X571733Y277527D01*
X572317Y278027D01*
G01X575333Y277360D02*
Y280693D01*
G01Y280027D02*
X575750Y280360D01*
X576167Y280610D01*
X576750Y280693D01*
X577167Y280610D01*
X577667Y280360D01*
G01X361117Y328537D02*
X360717Y328737D01*
X360250Y328870D01*
X359717D01*
X359117Y328670D01*
X358650Y328337D01*
X358317Y327937D01*
X358050Y327270D01*
X357983Y326670D01*
X358117Y326070D01*
X358317Y325670D01*
X358717Y325270D01*
X359183Y325003D01*
X359650Y324870D01*
X360117D01*
X360583Y325003D01*
X360983Y325203D01*
X361317Y325470D01*
G01X401827Y295540D02*
X403910Y300540D01*
X405993Y295540D01*
G01X405243Y297290D02*
X402577D01*
G01X408093Y295540D02*
Y298873D01*
G01Y298040D02*
X408427Y298457D01*
X408927Y298790D01*
X409593Y298873D01*
X410177Y298790D01*
X410677Y298457D01*
X410927Y297873D01*
Y295540D01*
G01X413943Y294290D02*
X414527Y293957D01*
X415193Y293873D01*
X415777Y293957D01*
X416277Y294373D01*
X416610Y294957D01*
Y298873D01*
G01Y298207D02*
X416277Y298540D01*
X415777Y298790D01*
X415193Y298873D01*
X414527Y298707D01*
X414110Y298373D01*
X413777Y297790D01*
X413610Y297207D01*
X413693Y296707D01*
X414027Y296123D01*
X414527Y295707D01*
X415193Y295540D01*
X415693Y295623D01*
X416277Y295957D01*
X416610Y296290D01*
G01X420710Y295540D02*
Y300540D01*
G01X425060Y297790D02*
X427727D01*
X427477Y298373D01*
X427060Y298707D01*
X426477Y298873D01*
X425893Y298790D01*
X425393Y298540D01*
X425060Y297957D01*
X424893Y297457D01*
Y296957D01*
X425060Y296457D01*
X425477Y295957D01*
X425977Y295623D01*
X426560Y295540D01*
X427143Y295707D01*
X427727Y296207D01*
G01X431493Y293873D02*
X430660Y294707D01*
X430243Y295540D01*
Y298873D01*
X430660Y299707D01*
X431493Y300540D01*
G01X449127Y293873D02*
X449960Y294707D01*
X450377Y295540D01*
Y298873D01*
X449960Y299707D01*
X449127Y300540D01*
G01X401777Y331927D02*
X402110Y332177D01*
X402360Y332593D01*
X402527Y333177D01*
X402360Y333677D01*
X402027Y334010D01*
X401443Y334260D01*
X399193D01*
Y329260D01*
X401943D01*
X402527Y329593D01*
X402860Y330093D01*
X403027Y330677D01*
X402860Y331260D01*
X402360Y331760D01*
X401777Y331927D01*
X399193D01*
G01X405210Y329093D02*
X408210Y334260D01*
G01X410227Y329260D02*
X412310Y334260D01*
X414393Y329260D01*
G01X413643Y331010D02*
X410977D01*
G01X395000Y305500D02*
X694500D01*
G01X395000Y337500D02*
X694500D01*
G01X400633Y358960D02*
Y353960D01*
X403967D01*
G01X409400D02*
Y357293D01*
G01Y356710D02*
X409067Y357043D01*
X408567Y357210D01*
X407983Y357293D01*
X407400Y357127D01*
X406900Y356793D01*
X406567Y356293D01*
X406400Y355627D01*
X406567Y354960D01*
X406900Y354460D01*
X407400Y354127D01*
X407983Y353960D01*
X408567Y354043D01*
X409067Y354293D01*
X409400Y354627D01*
G01X412250Y354543D02*
X412667Y354210D01*
X413250Y353960D01*
X413750D01*
X414250Y354127D01*
X414583Y354377D01*
X414750Y354710D01*
X414667Y355210D01*
X414333Y355460D01*
X412833Y355960D01*
X412500Y356543D01*
X412667Y356960D01*
X413000Y357210D01*
X413500Y357293D01*
X414000Y357210D01*
X414500Y356960D01*
G01X417850Y356210D02*
X420517D01*
X420267Y356793D01*
X419850Y357127D01*
X419267Y357293D01*
X418683Y357210D01*
X418183Y356960D01*
X417850Y356377D01*
X417683Y355877D01*
Y355377D01*
X417850Y354877D01*
X418267Y354377D01*
X418767Y354043D01*
X419350Y353960D01*
X419933Y354127D01*
X420517Y354627D01*
G01X423533Y353960D02*
Y357293D01*
G01Y356627D02*
X423950Y356960D01*
X424367Y357210D01*
X424950Y357293D01*
X425367Y357210D01*
X425867Y356960D01*
G01X434400Y357293D02*
X435900Y353960D01*
X437400Y357293D01*
G01X441500D02*
Y353960D01*
G01Y358627D02*
X441333Y358710D01*
Y358877D01*
X441500Y358960D01*
X441667Y358877D01*
Y358710D01*
X441500Y358627D01*
G01X448600Y353960D02*
Y357293D01*
G01Y356710D02*
X448267Y357043D01*
X447767Y357210D01*
X447183Y357293D01*
X446600Y357127D01*
X446100Y356793D01*
X445767Y356293D01*
X445600Y355627D01*
X445767Y354960D01*
X446100Y354460D01*
X446600Y354127D01*
X447183Y353960D01*
X447767Y354043D01*
X448267Y354293D01*
X448600Y354627D01*
G01X457050Y354543D02*
X457467Y354210D01*
X458050Y353960D01*
X458550D01*
X459050Y354127D01*
X459383Y354377D01*
X459550Y354710D01*
X459467Y355210D01*
X459133Y355460D01*
X457633Y355960D01*
X457300Y356543D01*
X457467Y356960D01*
X457800Y357210D01*
X458300Y357293D01*
X458800Y357210D01*
X459300Y356960D01*
G01X463900Y357293D02*
Y353960D01*
G01Y358627D02*
X463733Y358710D01*
Y358877D01*
X463900Y358960D01*
X464067Y358877D01*
Y358710D01*
X463900Y358627D01*
G01X468250Y357293D02*
X470750D01*
X468250Y353960D01*
X470750D01*
G01X473850Y356210D02*
X476517D01*
X476267Y356793D01*
X475850Y357127D01*
X475267Y357293D01*
X474683Y357210D01*
X474183Y356960D01*
X473850Y356377D01*
X473683Y355877D01*
Y355377D01*
X473850Y354877D01*
X474267Y354377D01*
X474767Y354043D01*
X475350Y353960D01*
X475933Y354127D01*
X476517Y354627D01*
G01X484217Y357293D02*
X485217Y353960D01*
X486300Y357293D01*
X487383Y353960D01*
X488383Y357293D01*
G01X491900D02*
Y353960D01*
G01Y358627D02*
X491733Y358710D01*
Y358877D01*
X491900Y358960D01*
X492067Y358877D01*
Y358710D01*
X491900Y358627D01*
G01X497500Y358960D02*
Y353960D01*
G01X496333Y357293D02*
X498667D01*
G01X501683Y353960D02*
Y358960D01*
G01Y356543D02*
X502100Y356960D01*
X502517Y357210D01*
X503183Y357293D01*
X503683Y357210D01*
X504267Y356877D01*
X504517Y356377D01*
Y353960D01*
G01X508700D02*
X508200Y354043D01*
X507700Y354377D01*
X507367Y354960D01*
X507200Y355627D01*
X507367Y356293D01*
X507700Y356877D01*
X508200Y357210D01*
X508700Y357293D01*
X509200Y357210D01*
X509700Y356877D01*
X510033Y356293D01*
X510117Y355627D01*
X510033Y354960D01*
X509700Y354377D01*
X509200Y354043D01*
X508700Y353960D01*
G01X512883Y357293D02*
Y354960D01*
X513217Y354377D01*
X513717Y354043D01*
X514300Y353960D01*
X514883Y354043D01*
X515383Y354377D01*
X515717Y354960D01*
G01Y353960D02*
Y357293D01*
G01X519900Y358960D02*
Y353960D01*
G01X518733Y357293D02*
X521067D01*
G01X529600Y352293D02*
Y357293D01*
G01Y356543D02*
X530017Y356960D01*
X530433Y357210D01*
X531100Y357293D01*
X531683Y357210D01*
X532267Y356793D01*
X532517Y356210D01*
X532600Y355627D01*
X532517Y355043D01*
X532267Y354460D01*
X531767Y354127D01*
X531100Y353960D01*
X530517Y354043D01*
X529933Y354293D01*
X529600Y354627D01*
G01X536700Y353960D02*
Y358960D01*
G01X543800Y353960D02*
Y357293D01*
G01Y356710D02*
X543467Y357043D01*
X542967Y357210D01*
X542383Y357293D01*
X541800Y357127D01*
X541300Y356793D01*
X540967Y356293D01*
X540800Y355627D01*
X540967Y354960D01*
X541300Y354460D01*
X541800Y354127D01*
X542383Y353960D01*
X542967Y354043D01*
X543467Y354293D01*
X543800Y354627D01*
G01X547900Y358960D02*
Y353960D01*
G01X546733Y357293D02*
X549067D01*
G01X553500D02*
Y353960D01*
G01Y358627D02*
X553333Y358710D01*
Y358877D01*
X553500Y358960D01*
X553667Y358877D01*
Y358710D01*
X553500Y358627D01*
G01X557683Y353960D02*
Y357293D01*
G01Y356460D02*
X558017Y356877D01*
X558517Y357210D01*
X559183Y357293D01*
X559767Y357210D01*
X560267Y356877D01*
X560517Y356293D01*
Y353960D01*
G01X563533Y352710D02*
X564117Y352377D01*
X564783Y352293D01*
X565367Y352377D01*
X565867Y352793D01*
X566200Y353377D01*
Y357293D01*
G01Y356627D02*
X565867Y356960D01*
X565367Y357210D01*
X564783Y357293D01*
X564117Y357127D01*
X563700Y356793D01*
X563367Y356210D01*
X563200Y355627D01*
X563283Y355127D01*
X563617Y354543D01*
X564117Y354127D01*
X564783Y353960D01*
X565283Y354043D01*
X565867Y354377D01*
X566200Y354710D01*
G01X575483Y352293D02*
X574650Y353127D01*
X574233Y353960D01*
Y357293D01*
X574650Y358127D01*
X575483Y358960D01*
G01X582167Y356627D02*
X582500Y356877D01*
X582750Y357293D01*
X582917Y357877D01*
X582750Y358377D01*
X582417Y358710D01*
X581833Y358960D01*
X579583D01*
Y353960D01*
X582333D01*
X582917Y354293D01*
X583250Y354793D01*
X583417Y355377D01*
X583250Y355960D01*
X582750Y356460D01*
X582167Y356627D01*
X579583D01*
G01X587517Y352293D02*
X588350Y353127D01*
X588767Y353960D01*
Y357293D01*
X588350Y358127D01*
X587517Y358960D01*
G01X404500Y666833D02*
Y663500D01*
G01Y668167D02*
X404333Y668250D01*
Y668417D01*
X404500Y668500D01*
X404667Y668417D01*
Y668250D01*
X404500Y668167D01*
G01X410100Y668500D02*
Y663500D01*
G01X408933Y666833D02*
X411267D01*
G01X414450Y665750D02*
X417117D01*
X416867Y666333D01*
X416450Y666667D01*
X415867Y666833D01*
X415283Y666750D01*
X414783Y666500D01*
X414450Y665917D01*
X414283Y665417D01*
Y664917D01*
X414450Y664417D01*
X414867Y663917D01*
X415367Y663583D01*
X415950Y663500D01*
X416533Y663667D01*
X417117Y664167D01*
G01X418800Y663500D02*
Y666833D01*
G01Y665917D02*
X419050Y666333D01*
X419467Y666667D01*
X420050Y666833D01*
X420633Y666667D01*
X421050Y666333D01*
X421300Y665917D01*
Y663500D01*
G01Y665917D02*
X421550Y666333D01*
X421967Y666667D01*
X422550Y666833D01*
X423133Y666667D01*
X423550Y666333D01*
X423800Y665833D01*
Y663500D01*
G01X444197Y299927D02*
X443797Y300127D01*
X443330Y300260D01*
X442797D01*
X442197Y300060D01*
X441730Y299727D01*
X441397Y299327D01*
X441130Y298660D01*
X441063Y298060D01*
X441197Y297460D01*
X441397Y297060D01*
X441797Y296660D01*
X442263Y296393D01*
X442730Y296260D01*
X443197D01*
X443663Y296393D01*
X444063Y296593D01*
X444397Y296860D01*
G01X607500Y-28500D02*
X606833Y-28667D01*
X606333Y-29083D01*
X606000Y-29583D01*
X605750Y-30250D01*
X605667Y-31000D01*
X605750Y-31750D01*
X606000Y-32417D01*
X606333Y-32917D01*
X606833Y-33333D01*
X607500Y-33500D01*
X608167Y-33333D01*
X608667Y-32917D01*
X609000Y-32417D01*
X609250Y-31750D01*
X609333Y-31000D01*
X609250Y-30250D01*
X609000Y-29583D01*
X608667Y-29083D01*
X608167Y-28667D01*
X607500Y-28500D01*
G01X613100Y-33667D02*
X612933Y-33583D01*
Y-33417D01*
X613100Y-33333D01*
X613267Y-33417D01*
Y-33583D01*
X613100Y-33667D01*
G01X616867Y-32500D02*
X617367Y-33083D01*
X618033Y-33417D01*
X618783Y-33500D01*
X619450Y-33417D01*
X620117Y-33000D01*
X620533Y-32500D01*
X620617Y-32000D01*
X620450Y-31417D01*
X619867Y-31000D01*
X619283Y-30833D01*
X618533D01*
G01X619283D02*
X619783Y-30583D01*
X620200Y-30167D01*
X620367Y-29667D01*
X620200Y-29167D01*
X619783Y-28750D01*
X619033Y-28500D01*
X618283Y-28583D01*
X617533Y-28917D01*
G01X621800Y-31833D02*
X622633Y-30167D01*
X623467D01*
X625133Y-33500D01*
X625967D01*
X626800Y-31833D01*
G01X629900Y-28500D02*
X629233Y-28667D01*
X628733Y-29083D01*
X628400Y-29583D01*
X628150Y-30250D01*
X628067Y-31000D01*
X628150Y-31750D01*
X628400Y-32417D01*
X628733Y-32917D01*
X629233Y-33333D01*
X629900Y-33500D01*
X630567Y-33333D01*
X631067Y-32917D01*
X631400Y-32417D01*
X631650Y-31750D01*
X631733Y-31000D01*
X631650Y-30250D01*
X631400Y-29583D01*
X631067Y-29083D01*
X630567Y-28667D01*
X629900Y-28500D01*
G01X635500Y-33667D02*
X635333Y-33583D01*
Y-33417D01*
X635500Y-33333D01*
X635667Y-33417D01*
Y-33583D01*
X635500Y-33667D01*
G01X640933Y-33500D02*
X641100Y-32417D01*
X641350Y-31500D01*
X641683Y-30667D01*
X642100Y-29750D01*
X642767Y-28500D01*
X639433D01*
G01X644200Y-33500D02*
Y-30167D01*
G01Y-31083D02*
X644450Y-30667D01*
X644867Y-30333D01*
X645450Y-30167D01*
X646033Y-30333D01*
X646450Y-30667D01*
X646700Y-31083D01*
Y-33500D01*
G01Y-31083D02*
X646950Y-30667D01*
X647367Y-30333D01*
X647950Y-30167D01*
X648533Y-30333D01*
X648950Y-30667D01*
X649200Y-31167D01*
Y-33500D01*
G01X652300Y-30167D02*
Y-33500D01*
G01Y-28833D02*
X652133Y-28750D01*
Y-28583D01*
X652300Y-28500D01*
X652467Y-28583D01*
Y-28750D01*
X652300Y-28833D01*
G01X657900Y-33500D02*
Y-28500D01*
G01X609167Y-48500D02*
X605833Y-46833D01*
X609167Y-45167D01*
G01X612017Y-47583D02*
X614183D01*
G01Y-46083D02*
X612017D01*
G01X618700Y-48500D02*
Y-43500D01*
X617700Y-44500D01*
G01Y-48500D02*
X619700D01*
G01X624300Y-48667D02*
X624133Y-48583D01*
Y-48417D01*
X624300Y-48333D01*
X624467Y-48417D01*
Y-48583D01*
X624300Y-48667D01*
G01X630900Y-48500D02*
Y-43500D01*
X627817Y-47083D01*
X631983D01*
G01X633000Y-48500D02*
Y-45167D01*
G01Y-46083D02*
X633250Y-45667D01*
X633667Y-45333D01*
X634250Y-45167D01*
X634833Y-45333D01*
X635250Y-45667D01*
X635500Y-46083D01*
Y-48500D01*
G01Y-46083D02*
X635750Y-45667D01*
X636167Y-45333D01*
X636750Y-45167D01*
X637333Y-45333D01*
X637750Y-45667D01*
X638000Y-46167D01*
Y-48500D01*
G01X641100Y-45167D02*
Y-48500D01*
G01Y-43833D02*
X640933Y-43750D01*
Y-43583D01*
X641100Y-43500D01*
X641267Y-43583D01*
Y-43750D01*
X641100Y-43833D01*
G01X646700Y-48500D02*
Y-43500D01*
G01X605333Y-65000D02*
Y-60000D01*
X607500Y-64167D01*
X609667Y-60000D01*
Y-65000D01*
G01X611683Y-61667D02*
Y-64000D01*
X612017Y-64583D01*
X612517Y-64917D01*
X613100Y-65000D01*
X613683Y-64917D01*
X614183Y-64583D01*
X614517Y-64000D01*
G01Y-65000D02*
Y-61667D01*
G01X617450Y-64417D02*
X617867Y-64750D01*
X618450Y-65000D01*
X618950D01*
X619450Y-64833D01*
X619783Y-64583D01*
X619950Y-64250D01*
X619867Y-63750D01*
X619533Y-63500D01*
X618033Y-63000D01*
X617700Y-62417D01*
X617867Y-62000D01*
X618200Y-61750D01*
X618700Y-61667D01*
X619200Y-61750D01*
X619700Y-62000D01*
G01X624300Y-60000D02*
Y-65000D01*
G01X623133Y-61667D02*
X625467D01*
G01X635000Y-65000D02*
Y-60750D01*
X635167Y-60333D01*
X635500Y-60083D01*
X636000Y-60000D01*
X636500Y-60167D01*
X636750Y-60583D01*
G01X635750Y-62000D02*
X634083D01*
G01X641100Y-65000D02*
X640600Y-64917D01*
X640100Y-64583D01*
X639767Y-64000D01*
X639600Y-63333D01*
X639767Y-62667D01*
X640100Y-62083D01*
X640600Y-61750D01*
X641100Y-61667D01*
X641600Y-61750D01*
X642100Y-62083D01*
X642433Y-62667D01*
X642517Y-63333D01*
X642433Y-64000D01*
X642100Y-64583D01*
X641600Y-64917D01*
X641100Y-65000D01*
G01X646700D02*
Y-60000D01*
G01X652300Y-65000D02*
Y-60000D01*
G01X657900Y-65000D02*
X657400Y-64917D01*
X656900Y-64583D01*
X656567Y-64000D01*
X656400Y-63333D01*
X656567Y-62667D01*
X656900Y-62083D01*
X657400Y-61750D01*
X657900Y-61667D01*
X658400Y-61750D01*
X658900Y-62083D01*
X659233Y-62667D01*
X659317Y-63333D01*
X659233Y-64000D01*
X658900Y-64583D01*
X658400Y-64917D01*
X657900Y-65000D01*
G01X661417Y-61667D02*
X662417Y-65000D01*
X663500Y-61667D01*
X664583Y-65000D01*
X665583Y-61667D01*
G01X595500Y-69500D02*
Y438000D01*
G01X606583Y-1833D02*
X608583D01*
G01X607500Y-750D02*
Y-2917D01*
G01X611600Y-3667D02*
X614600Y1500D01*
G01X617617Y-1833D02*
X619783D01*
G01X624300Y-3500D02*
Y1500D01*
X623300Y500D01*
G01Y-3500D02*
X625300D01*
G01X627400D02*
Y-167D01*
G01Y-1083D02*
X627650Y-667D01*
X628067Y-333D01*
X628650Y-167D01*
X629233Y-333D01*
X629650Y-667D01*
X629900Y-1083D01*
Y-3500D01*
G01Y-1083D02*
X630150Y-667D01*
X630567Y-333D01*
X631150Y-167D01*
X631733Y-333D01*
X632150Y-667D01*
X632400Y-1167D01*
Y-3500D01*
G01X635500Y-167D02*
Y-3500D01*
G01Y1167D02*
X635333Y1250D01*
Y1417D01*
X635500Y1500D01*
X635667Y1417D01*
Y1250D01*
X635500Y1167D01*
G01X641100Y-3500D02*
Y1500D01*
G01X607500Y-15000D02*
X606833Y-15167D01*
X606333Y-15583D01*
X606000Y-16083D01*
X605750Y-16750D01*
X605667Y-17500D01*
X605750Y-18250D01*
X606000Y-18917D01*
X606333Y-19417D01*
X606833Y-19833D01*
X607500Y-20000D01*
X608167Y-19833D01*
X608667Y-19417D01*
X609000Y-18917D01*
X609250Y-18250D01*
X609333Y-17500D01*
X609250Y-16750D01*
X609000Y-16083D01*
X608667Y-15583D01*
X608167Y-15167D01*
X607500Y-15000D01*
G01X613100Y-20167D02*
X612933Y-20083D01*
Y-19917D01*
X613100Y-19833D01*
X613267Y-19917D01*
Y-20083D01*
X613100Y-20167D01*
G01X616867Y-19000D02*
X617367Y-19583D01*
X618033Y-19917D01*
X618783Y-20000D01*
X619450Y-19917D01*
X620117Y-19500D01*
X620533Y-19000D01*
X620617Y-18500D01*
X620450Y-17917D01*
X619867Y-17500D01*
X619283Y-17333D01*
X618533D01*
G01X619283D02*
X619783Y-17083D01*
X620200Y-16667D01*
X620367Y-16167D01*
X620200Y-15667D01*
X619783Y-15250D01*
X619033Y-15000D01*
X618283Y-15083D01*
X617533Y-15417D01*
G01X621800Y-18333D02*
X622633Y-16667D01*
X623467D01*
X625133Y-20000D01*
X625967D01*
X626800Y-18333D01*
G01X629900Y-15000D02*
X629233Y-15167D01*
X628733Y-15583D01*
X628400Y-16083D01*
X628150Y-16750D01*
X628067Y-17500D01*
X628150Y-18250D01*
X628400Y-18917D01*
X628733Y-19417D01*
X629233Y-19833D01*
X629900Y-20000D01*
X630567Y-19833D01*
X631067Y-19417D01*
X631400Y-18917D01*
X631650Y-18250D01*
X631733Y-17500D01*
X631650Y-16750D01*
X631400Y-16083D01*
X631067Y-15583D01*
X630567Y-15167D01*
X629900Y-15000D01*
G01X635500Y-20167D02*
X635333Y-20083D01*
Y-19917D01*
X635500Y-19833D01*
X635667Y-19917D01*
Y-20083D01*
X635500Y-20167D01*
G01X640933Y-20000D02*
X641100Y-18917D01*
X641350Y-18000D01*
X641683Y-17167D01*
X642100Y-16250D01*
X642767Y-15000D01*
X639433D01*
G01X644200Y-20000D02*
Y-16667D01*
G01Y-17583D02*
X644450Y-17167D01*
X644867Y-16833D01*
X645450Y-16667D01*
X646033Y-16833D01*
X646450Y-17167D01*
X646700Y-17583D01*
Y-20000D01*
G01Y-17583D02*
X646950Y-17167D01*
X647367Y-16833D01*
X647950Y-16667D01*
X648533Y-16833D01*
X648950Y-17167D01*
X649200Y-17667D01*
Y-20000D01*
G01X652300Y-16667D02*
Y-20000D01*
G01Y-15333D02*
X652133Y-15250D01*
Y-15083D01*
X652300Y-15000D01*
X652467Y-15083D01*
Y-15250D01*
X652300Y-15333D01*
G01X657900Y-20000D02*
Y-15000D01*
G01X606583Y48667D02*
X608583D01*
G01X607500Y49750D02*
Y47583D01*
G01X611600Y46833D02*
X614600Y52000D01*
G01X617617Y48667D02*
X619783D01*
G01X622717Y51167D02*
X623217Y51667D01*
X623800Y51917D01*
X624467Y52000D01*
X625300Y51833D01*
X625883Y51417D01*
X626050Y50917D01*
X625967Y50417D01*
X625633Y50000D01*
X623967Y49167D01*
X623217Y48583D01*
X622717Y47750D01*
X622550Y47000D01*
X626050D01*
G01X627400D02*
Y50333D01*
G01Y49417D02*
X627650Y49833D01*
X628067Y50167D01*
X628650Y50333D01*
X629233Y50167D01*
X629650Y49833D01*
X629900Y49417D01*
Y47000D01*
G01Y49417D02*
X630150Y49833D01*
X630567Y50167D01*
X631150Y50333D01*
X631733Y50167D01*
X632150Y49833D01*
X632400Y49333D01*
Y47000D01*
G01X635500Y50333D02*
Y47000D01*
G01Y51667D02*
X635333Y51750D01*
Y51917D01*
X635500Y52000D01*
X635667Y51917D01*
Y51750D01*
X635500Y51667D01*
G01X641100Y47000D02*
Y52000D01*
G01X606583Y24667D02*
X608583D01*
G01X607500Y25750D02*
Y23583D01*
G01X611600Y22833D02*
X614600Y28000D01*
G01X617617Y24667D02*
X619783D01*
G01X624300Y23000D02*
Y28000D01*
X623300Y27000D01*
G01Y23000D02*
X625300D01*
G01X627400D02*
Y26333D01*
G01Y25417D02*
X627650Y25833D01*
X628067Y26167D01*
X628650Y26333D01*
X629233Y26167D01*
X629650Y25833D01*
X629900Y25417D01*
Y23000D01*
G01Y25417D02*
X630150Y25833D01*
X630567Y26167D01*
X631150Y26333D01*
X631733Y26167D01*
X632150Y25833D01*
X632400Y25333D01*
Y23000D01*
G01X635500Y26333D02*
Y23000D01*
G01Y27667D02*
X635333Y27750D01*
Y27917D01*
X635500Y28000D01*
X635667Y27917D01*
Y27750D01*
X635500Y27667D01*
G01X641100Y23000D02*
Y28000D01*
G01X606583Y13167D02*
X608583D01*
G01X607500Y14250D02*
Y12083D01*
G01X611600Y11333D02*
X614600Y16500D01*
G01X617617Y13167D02*
X619783D01*
G01X622717Y15667D02*
X623217Y16167D01*
X623800Y16417D01*
X624467Y16500D01*
X625300Y16333D01*
X625883Y15917D01*
X626050Y15417D01*
X625967Y14917D01*
X625633Y14500D01*
X623967Y13667D01*
X623217Y13083D01*
X622717Y12250D01*
X622550Y11500D01*
X626050D01*
G01X627400D02*
Y14833D01*
G01Y13917D02*
X627650Y14333D01*
X628067Y14667D01*
X628650Y14833D01*
X629233Y14667D01*
X629650Y14333D01*
X629900Y13917D01*
Y11500D01*
G01Y13917D02*
X630150Y14333D01*
X630567Y14667D01*
X631150Y14833D01*
X631733Y14667D01*
X632150Y14333D01*
X632400Y13833D01*
Y11500D01*
G01X635500Y14833D02*
Y11500D01*
G01Y16167D02*
X635333Y16250D01*
Y16417D01*
X635500Y16500D01*
X635667Y16417D01*
Y16250D01*
X635500Y16167D01*
G01X641100Y11500D02*
Y16500D01*
G01X606583Y98167D02*
X608583D01*
G01X607500Y99250D02*
Y97083D01*
G01X611600Y96333D02*
X614600Y101500D01*
G01X617617Y98167D02*
X619783D01*
G01X622717Y100667D02*
X623217Y101167D01*
X623800Y101417D01*
X624467Y101500D01*
X625300Y101333D01*
X625883Y100917D01*
X626050Y100417D01*
X625967Y99917D01*
X625633Y99500D01*
X623967Y98667D01*
X623217Y98083D01*
X622717Y97250D01*
X622550Y96500D01*
X626050D01*
G01X629900Y101500D02*
X629233Y101333D01*
X628733Y100917D01*
X628400Y100417D01*
X628150Y99750D01*
X628067Y99000D01*
X628150Y98250D01*
X628400Y97583D01*
X628733Y97083D01*
X629233Y96667D01*
X629900Y96500D01*
X630567Y96667D01*
X631067Y97083D01*
X631400Y97583D01*
X631650Y98250D01*
X631733Y99000D01*
X631650Y99750D01*
X631400Y100417D01*
X631067Y100917D01*
X630567Y101333D01*
X629900Y101500D01*
G01X634000Y96333D02*
X637000Y101500D01*
G01X634000D02*
X633500Y101333D01*
X633250Y101083D01*
X633083Y100583D01*
X633250Y100083D01*
X633500Y99833D01*
X634000Y99667D01*
X634500Y99833D01*
X634750Y100083D01*
X634917Y100583D01*
X634750Y101083D01*
X634500Y101333D01*
X634000Y101500D01*
G01X637000Y98167D02*
X636500Y98000D01*
X636250Y97750D01*
X636083Y97250D01*
X636250Y96750D01*
X636500Y96500D01*
X637000Y96333D01*
X637500Y96500D01*
X637750Y96750D01*
X637917Y97250D01*
X637750Y97750D01*
X637500Y98000D01*
X637000Y98167D01*
G01X606583Y68167D02*
X608583D01*
G01X607500Y69250D02*
Y67083D01*
G01X611600Y66333D02*
X614600Y71500D01*
G01X617617Y68167D02*
X619783D01*
G01X624300Y66500D02*
Y71500D01*
X623300Y70500D01*
G01Y66500D02*
X625300D01*
G01X628067Y67250D02*
X628567Y66833D01*
X629150Y66583D01*
X629900Y66500D01*
X630650Y66667D01*
X631233Y67000D01*
X631650Y67583D01*
X631733Y68250D01*
X631567Y68917D01*
X631150Y69333D01*
X630567Y69667D01*
X629983Y69750D01*
X629400Y69667D01*
X628650Y69333D01*
X628900Y71500D01*
X631150D01*
G01X634000Y66333D02*
X637000Y71500D01*
G01X634000D02*
X633500Y71333D01*
X633250Y71083D01*
X633083Y70583D01*
X633250Y70083D01*
X633500Y69833D01*
X634000Y69667D01*
X634500Y69833D01*
X634750Y70083D01*
X634917Y70583D01*
X634750Y71083D01*
X634500Y71333D01*
X634000Y71500D01*
G01X637000Y68167D02*
X636500Y68000D01*
X636250Y67750D01*
X636083Y67250D01*
X636250Y66750D01*
X636500Y66500D01*
X637000Y66333D01*
X637500Y66500D01*
X637750Y66750D01*
X637917Y67250D01*
X637750Y67750D01*
X637500Y68000D01*
X637000Y68167D01*
G01X606583Y113167D02*
X608583D01*
G01X607500Y114250D02*
Y112083D01*
G01X611600Y111333D02*
X614600Y116500D01*
G01X617617Y113167D02*
X619783D01*
G01X622467Y112500D02*
X622967Y111917D01*
X623633Y111583D01*
X624383Y111500D01*
X625050Y111583D01*
X625717Y112000D01*
X626133Y112500D01*
X626217Y113000D01*
X626050Y113583D01*
X625467Y114000D01*
X624883Y114167D01*
X624133D01*
G01X624883D02*
X625383Y114417D01*
X625800Y114833D01*
X625967Y115333D01*
X625800Y115833D01*
X625383Y116250D01*
X624633Y116500D01*
X623883Y116417D01*
X623133Y116083D01*
G01X627400Y111500D02*
Y114833D01*
G01Y113917D02*
X627650Y114333D01*
X628067Y114667D01*
X628650Y114833D01*
X629233Y114667D01*
X629650Y114333D01*
X629900Y113917D01*
Y111500D01*
G01Y113917D02*
X630150Y114333D01*
X630567Y114667D01*
X631150Y114833D01*
X631733Y114667D01*
X632150Y114333D01*
X632400Y113833D01*
Y111500D01*
G01X635500Y114833D02*
Y111500D01*
G01Y116167D02*
X635333Y116250D01*
Y116417D01*
X635500Y116500D01*
X635667Y116417D01*
Y116250D01*
X635500Y116167D01*
G01X641100Y111500D02*
Y116500D01*
G01X606583Y83167D02*
X608583D01*
G01X607500Y84250D02*
Y82083D01*
G01X611600Y81333D02*
X614600Y86500D01*
G01X617617Y83167D02*
X619783D01*
G01X624300Y81500D02*
Y86500D01*
X623300Y85500D01*
G01Y81500D02*
X625300D01*
G01X627400D02*
Y84833D01*
G01Y83917D02*
X627650Y84333D01*
X628067Y84667D01*
X628650Y84833D01*
X629233Y84667D01*
X629650Y84333D01*
X629900Y83917D01*
Y81500D01*
G01Y83917D02*
X630150Y84333D01*
X630567Y84667D01*
X631150Y84833D01*
X631733Y84667D01*
X632150Y84333D01*
X632400Y83833D01*
Y81500D01*
G01X635500Y84833D02*
Y81500D01*
G01Y86167D02*
X635333Y86250D01*
Y86417D01*
X635500Y86500D01*
X635667Y86417D01*
Y86250D01*
X635500Y86167D01*
G01X641100Y81500D02*
Y86500D01*
G01X605833Y166500D02*
X609167Y168167D01*
X605833Y169833D01*
G01X612017Y167417D02*
X614183D01*
G01Y168917D02*
X612017D01*
G01X618700Y166500D02*
Y171500D01*
X617700Y170500D01*
G01Y166500D02*
X619700D01*
G01X624300Y166333D02*
X624133Y166417D01*
Y166583D01*
X624300Y166667D01*
X624467Y166583D01*
Y166417D01*
X624300Y166333D01*
G01X628067Y167500D02*
X628567Y166917D01*
X629233Y166583D01*
X629983Y166500D01*
X630650Y166583D01*
X631317Y167000D01*
X631733Y167500D01*
X631817Y168000D01*
X631650Y168583D01*
X631067Y169000D01*
X630483Y169167D01*
X629733D01*
G01X630483D02*
X630983Y169417D01*
X631400Y169833D01*
X631567Y170333D01*
X631400Y170833D01*
X630983Y171250D01*
X630233Y171500D01*
X629483Y171417D01*
X628733Y171083D01*
G01X633000Y166500D02*
Y169833D01*
G01Y168917D02*
X633250Y169333D01*
X633667Y169667D01*
X634250Y169833D01*
X634833Y169667D01*
X635250Y169333D01*
X635500Y168917D01*
Y166500D01*
G01Y168917D02*
X635750Y169333D01*
X636167Y169667D01*
X636750Y169833D01*
X637333Y169667D01*
X637750Y169333D01*
X638000Y168833D01*
Y166500D01*
G01X641100Y169833D02*
Y166500D01*
G01Y171167D02*
X640933Y171250D01*
Y171417D01*
X641100Y171500D01*
X641267Y171417D01*
Y171250D01*
X641100Y171167D01*
G01X646700Y166500D02*
Y171500D01*
G01X605833Y144000D02*
X609167Y145667D01*
X605833Y147333D01*
G01X612017Y144917D02*
X614183D01*
G01Y146417D02*
X612017D01*
G01X618700Y144000D02*
Y149000D01*
X617700Y148000D01*
G01Y144000D02*
X619700D01*
G01X624300Y143833D02*
X624133Y143917D01*
Y144083D01*
X624300Y144167D01*
X624467Y144083D01*
Y143917D01*
X624300Y143833D01*
G01X628067Y144750D02*
X628567Y144333D01*
X629150Y144083D01*
X629900Y144000D01*
X630650Y144167D01*
X631233Y144500D01*
X631650Y145083D01*
X631733Y145750D01*
X631567Y146417D01*
X631150Y146833D01*
X630567Y147167D01*
X629983Y147250D01*
X629400Y147167D01*
X628650Y146833D01*
X628900Y149000D01*
X631150D01*
G01X633000Y144000D02*
Y147333D01*
G01Y146417D02*
X633250Y146833D01*
X633667Y147167D01*
X634250Y147333D01*
X634833Y147167D01*
X635250Y146833D01*
X635500Y146417D01*
Y144000D01*
G01Y146417D02*
X635750Y146833D01*
X636167Y147167D01*
X636750Y147333D01*
X637333Y147167D01*
X637750Y146833D01*
X638000Y146333D01*
Y144000D01*
G01X641100Y147333D02*
Y144000D01*
G01Y148667D02*
X640933Y148750D01*
Y148917D01*
X641100Y149000D01*
X641267Y148917D01*
Y148750D01*
X641100Y148667D01*
G01X646700Y144000D02*
Y149000D01*
G01X605833Y126500D02*
X609167Y128167D01*
X605833Y129833D01*
G01X612017Y127417D02*
X614183D01*
G01Y128917D02*
X612017D01*
G01X618700Y126500D02*
Y131500D01*
X617700Y130500D01*
G01Y126500D02*
X619700D01*
G01X624300Y126333D02*
X624133Y126417D01*
Y126583D01*
X624300Y126667D01*
X624467Y126583D01*
Y126417D01*
X624300Y126333D01*
G01X629900Y131500D02*
X629233Y131333D01*
X628733Y130917D01*
X628400Y130417D01*
X628150Y129750D01*
X628067Y129000D01*
X628150Y128250D01*
X628400Y127583D01*
X628733Y127083D01*
X629233Y126667D01*
X629900Y126500D01*
X630567Y126667D01*
X631067Y127083D01*
X631400Y127583D01*
X631650Y128250D01*
X631733Y129000D01*
X631650Y129750D01*
X631400Y130417D01*
X631067Y130917D01*
X630567Y131333D01*
X629900Y131500D01*
G01X633000Y126500D02*
Y129833D01*
G01Y128917D02*
X633250Y129333D01*
X633667Y129667D01*
X634250Y129833D01*
X634833Y129667D01*
X635250Y129333D01*
X635500Y128917D01*
Y126500D01*
G01Y128917D02*
X635750Y129333D01*
X636167Y129667D01*
X636750Y129833D01*
X637333Y129667D01*
X637750Y129333D01*
X638000Y128833D01*
Y126500D01*
G01X641100Y129833D02*
Y126500D01*
G01Y131167D02*
X640933Y131250D01*
Y131417D01*
X641100Y131500D01*
X641267Y131417D01*
Y131250D01*
X641100Y131167D01*
G01X646700Y126500D02*
Y131500D01*
G01X612977Y200490D02*
X609643Y202157D01*
X612977Y203823D01*
G01X616910Y205490D02*
X616243Y205323D01*
X615743Y204907D01*
X615410Y204407D01*
X615160Y203740D01*
X615077Y202990D01*
X615160Y202240D01*
X615410Y201573D01*
X615743Y201073D01*
X616243Y200657D01*
X616910Y200490D01*
X617577Y200657D01*
X618077Y201073D01*
X618410Y201573D01*
X618660Y202240D01*
X618743Y202990D01*
X618660Y203740D01*
X618410Y204407D01*
X618077Y204907D01*
X617577Y205323D01*
X616910Y205490D01*
G01X622510Y200323D02*
X622343Y200407D01*
Y200573D01*
X622510Y200657D01*
X622677Y200573D01*
Y200407D01*
X622510Y200323D01*
G01X626277Y201490D02*
X626777Y200907D01*
X627443Y200573D01*
X628193Y200490D01*
X628860Y200573D01*
X629527Y200990D01*
X629943Y201490D01*
X630027Y201990D01*
X629860Y202573D01*
X629277Y202990D01*
X628693Y203157D01*
X627943D01*
G01X628693D02*
X629193Y203407D01*
X629610Y203823D01*
X629777Y204323D01*
X629610Y204823D01*
X629193Y205240D01*
X628443Y205490D01*
X627693Y205407D01*
X626943Y205073D01*
G01X631210Y200490D02*
Y203823D01*
G01Y202907D02*
X631460Y203323D01*
X631877Y203657D01*
X632460Y203823D01*
X633043Y203657D01*
X633460Y203323D01*
X633710Y202907D01*
Y200490D01*
G01Y202907D02*
X633960Y203323D01*
X634377Y203657D01*
X634960Y203823D01*
X635543Y203657D01*
X635960Y203323D01*
X636210Y202823D01*
Y200490D01*
G01X639310Y203823D02*
Y200490D01*
G01Y205157D02*
X639143Y205240D01*
Y205407D01*
X639310Y205490D01*
X639477Y205407D01*
Y205240D01*
X639310Y205157D01*
G01X644910Y200490D02*
Y205490D01*
G01X612377Y255680D02*
X609043Y257347D01*
X612377Y259013D01*
G01X616310Y255680D02*
Y260680D01*
X615310Y259680D01*
G01Y255680D02*
X617310D01*
G01X619410D02*
Y259013D01*
G01Y258097D02*
X619660Y258513D01*
X620077Y258847D01*
X620660Y259013D01*
X621243Y258847D01*
X621660Y258513D01*
X621910Y258097D01*
Y255680D01*
G01Y258097D02*
X622160Y258513D01*
X622577Y258847D01*
X623160Y259013D01*
X623743Y258847D01*
X624160Y258513D01*
X624410Y258013D01*
Y255680D01*
G01X627510Y259013D02*
Y255680D01*
G01Y260347D02*
X627343Y260430D01*
Y260597D01*
X627510Y260680D01*
X627677Y260597D01*
Y260430D01*
X627510Y260347D01*
G01X633110Y255680D02*
Y260680D01*
G01X602120Y310470D02*
Y313803D01*
G01Y312887D02*
X602370Y313303D01*
X602787Y313637D01*
X603370Y313803D01*
X603953Y313637D01*
X604370Y313303D01*
X604620Y312887D01*
Y310470D01*
G01Y312887D02*
X604870Y313303D01*
X605287Y313637D01*
X605870Y313803D01*
X606453Y313637D01*
X606870Y313303D01*
X607120Y312803D01*
Y310470D01*
G01X608803Y313803D02*
Y311470D01*
X609137Y310887D01*
X609637Y310553D01*
X610220Y310470D01*
X610803Y310553D01*
X611303Y310887D01*
X611637Y311470D01*
G01Y310470D02*
Y313803D01*
G01X614570Y311053D02*
X614987Y310720D01*
X615570Y310470D01*
X616070D01*
X616570Y310637D01*
X616903Y310887D01*
X617070Y311220D01*
X616987Y311720D01*
X616653Y311970D01*
X615153Y312470D01*
X614820Y313053D01*
X614987Y313470D01*
X615320Y313720D01*
X615820Y313803D01*
X616320Y313720D01*
X616820Y313470D01*
G01X621420Y315470D02*
Y310470D01*
G01X620253Y313803D02*
X622587D01*
G01X628687Y310470D02*
X625353Y312137D01*
X628687Y313803D01*
G01X630537Y310470D02*
X632620Y315470D01*
X634703Y310470D01*
G01X633953Y312220D02*
X631287D01*
G01X645320Y315470D02*
Y310470D01*
G01Y311220D02*
X644987Y310803D01*
X644487Y310553D01*
X643903Y310470D01*
X643237Y310637D01*
X642737Y311053D01*
X642403Y311553D01*
X642320Y312137D01*
X642403Y312720D01*
X642737Y313220D01*
X643237Y313637D01*
X643903Y313803D01*
X644487Y313720D01*
X644903Y313553D01*
X645320Y313220D01*
G01X649420Y313803D02*
Y310470D01*
G01Y315137D02*
X649253Y315220D01*
Y315387D01*
X649420Y315470D01*
X649587Y315387D01*
Y315220D01*
X649420Y315137D01*
G01X656520Y310470D02*
Y313803D01*
G01Y313220D02*
X656187Y313553D01*
X655687Y313720D01*
X655103Y313803D01*
X654520Y313637D01*
X654020Y313303D01*
X653687Y312803D01*
X653520Y312137D01*
X653687Y311470D01*
X654020Y310970D01*
X654520Y310637D01*
X655103Y310470D01*
X655687Y310553D01*
X656187Y310803D01*
X656520Y311137D01*
G01X658120Y310470D02*
Y313803D01*
G01Y312887D02*
X658370Y313303D01*
X658787Y313637D01*
X659370Y313803D01*
X659953Y313637D01*
X660370Y313303D01*
X660620Y312887D01*
Y310470D01*
G01Y312887D02*
X660870Y313303D01*
X661287Y313637D01*
X661870Y313803D01*
X662453Y313637D01*
X662870Y313303D01*
X663120Y312803D01*
Y310470D01*
G01X664970Y312720D02*
X667637D01*
X667387Y313303D01*
X666970Y313637D01*
X666387Y313803D01*
X665803Y313720D01*
X665303Y313470D01*
X664970Y312887D01*
X664803Y312387D01*
Y311887D01*
X664970Y311387D01*
X665387Y310887D01*
X665887Y310553D01*
X666470Y310470D01*
X667053Y310637D01*
X667637Y311137D01*
G01X671820Y315470D02*
Y310470D01*
G01X670653Y313803D02*
X672987D01*
G01X676170Y312720D02*
X678837D01*
X678587Y313303D01*
X678170Y313637D01*
X677587Y313803D01*
X677003Y313720D01*
X676503Y313470D01*
X676170Y312887D01*
X676003Y312387D01*
Y311887D01*
X676170Y311387D01*
X676587Y310887D01*
X677087Y310553D01*
X677670Y310470D01*
X678253Y310637D01*
X678837Y311137D01*
G01X681853Y310470D02*
Y313803D01*
G01Y313137D02*
X682270Y313470D01*
X682687Y313720D01*
X683270Y313803D01*
X683687Y313720D01*
X684187Y313470D01*
G01X602700Y319240D02*
Y324240D01*
G01Y321740D02*
X603117Y322240D01*
X603617Y322490D01*
X604117Y322573D01*
X604867Y322407D01*
X605367Y322073D01*
X605700Y321490D01*
Y320823D01*
X605533Y320157D01*
X605200Y319657D01*
X604617Y319323D01*
X604117Y319240D01*
X603617Y319323D01*
X603117Y319573D01*
X602700Y319990D01*
G01X608383Y322573D02*
Y320240D01*
X608717Y319657D01*
X609217Y319323D01*
X609800Y319240D01*
X610383Y319323D01*
X610883Y319657D01*
X611217Y320240D01*
G01Y319240D02*
Y322573D01*
G01X615400Y324240D02*
Y319240D01*
G01X614233Y322573D02*
X616567D01*
G01X627267Y321907D02*
X627600Y322157D01*
X627850Y322573D01*
X628017Y323157D01*
X627850Y323657D01*
X627517Y323990D01*
X626933Y324240D01*
X624683D01*
Y319240D01*
X627433D01*
X628017Y319573D01*
X628350Y320073D01*
X628517Y320657D01*
X628350Y321240D01*
X627850Y321740D01*
X627267Y321907D01*
X624683D01*
G01X639300Y324240D02*
Y319240D01*
G01Y319990D02*
X638967Y319573D01*
X638467Y319323D01*
X637883Y319240D01*
X637217Y319407D01*
X636717Y319823D01*
X636383Y320323D01*
X636300Y320907D01*
X636383Y321490D01*
X636717Y321990D01*
X637217Y322407D01*
X637883Y322573D01*
X638467Y322490D01*
X638883Y322323D01*
X639300Y321990D01*
G01X643400Y322573D02*
Y319240D01*
G01Y323907D02*
X643233Y323990D01*
Y324157D01*
X643400Y324240D01*
X643567Y324157D01*
Y323990D01*
X643400Y323907D01*
G01X650500Y319240D02*
Y322573D01*
G01Y321990D02*
X650167Y322323D01*
X649667Y322490D01*
X649083Y322573D01*
X648500Y322407D01*
X648000Y322073D01*
X647667Y321573D01*
X647500Y320907D01*
X647667Y320240D01*
X648000Y319740D01*
X648500Y319407D01*
X649083Y319240D01*
X649667Y319323D01*
X650167Y319573D01*
X650500Y319907D01*
G01X652100Y319240D02*
Y322573D01*
G01Y321657D02*
X652350Y322073D01*
X652767Y322407D01*
X653350Y322573D01*
X653933Y322407D01*
X654350Y322073D01*
X654600Y321657D01*
Y319240D01*
G01Y321657D02*
X654850Y322073D01*
X655267Y322407D01*
X655850Y322573D01*
X656433Y322407D01*
X656850Y322073D01*
X657100Y321573D01*
Y319240D01*
G01X658950Y321490D02*
X661617D01*
X661367Y322073D01*
X660950Y322407D01*
X660367Y322573D01*
X659783Y322490D01*
X659283Y322240D01*
X658950Y321657D01*
X658783Y321157D01*
Y320657D01*
X658950Y320157D01*
X659367Y319657D01*
X659867Y319323D01*
X660450Y319240D01*
X661033Y319407D01*
X661617Y319907D01*
G01X665800Y324240D02*
Y319240D01*
G01X664633Y322573D02*
X666967D01*
G01X670150Y321490D02*
X672817D01*
X672567Y322073D01*
X672150Y322407D01*
X671567Y322573D01*
X670983Y322490D01*
X670483Y322240D01*
X670150Y321657D01*
X669983Y321157D01*
Y320657D01*
X670150Y320157D01*
X670567Y319657D01*
X671067Y319323D01*
X671650Y319240D01*
X672233Y319407D01*
X672817Y319907D01*
G01X675833Y319240D02*
Y322573D01*
G01Y321907D02*
X676250Y322240D01*
X676667Y322490D01*
X677250Y322573D01*
X677667Y322490D01*
X678167Y322240D01*
G01X608397Y295230D02*
X605063Y296897D01*
X608397Y298563D01*
G01X610913Y295813D02*
X611497Y295397D01*
X612163Y295230D01*
X612830Y295397D01*
X613413Y295897D01*
X613830Y296647D01*
X613997Y297397D01*
Y298313D01*
X613830Y299063D01*
X613413Y299730D01*
X612913Y300063D01*
X612330Y300230D01*
X611663Y300063D01*
X611163Y299730D01*
X610830Y299230D01*
X610663Y298563D01*
X610830Y297980D01*
X611247Y297397D01*
X611747Y297063D01*
X612330Y296980D01*
X612997Y297147D01*
X613497Y297563D01*
X613997Y298313D01*
G01X617930Y300230D02*
X617263Y300063D01*
X616763Y299647D01*
X616430Y299147D01*
X616180Y298480D01*
X616097Y297730D01*
X616180Y296980D01*
X616430Y296313D01*
X616763Y295813D01*
X617263Y295397D01*
X617930Y295230D01*
X618597Y295397D01*
X619097Y295813D01*
X619430Y296313D01*
X619680Y296980D01*
X619763Y297730D01*
X619680Y298480D01*
X619430Y299147D01*
X619097Y299647D01*
X618597Y300063D01*
X617930Y300230D01*
G01X630630D02*
Y295230D01*
G01Y295980D02*
X630297Y295563D01*
X629797Y295313D01*
X629213Y295230D01*
X628547Y295397D01*
X628047Y295813D01*
X627713Y296313D01*
X627630Y296897D01*
X627713Y297480D01*
X628047Y297980D01*
X628547Y298397D01*
X629213Y298563D01*
X629797Y298480D01*
X630213Y298313D01*
X630630Y297980D01*
G01X633480Y297480D02*
X636147D01*
X635897Y298063D01*
X635480Y298397D01*
X634897Y298563D01*
X634313Y298480D01*
X633813Y298230D01*
X633480Y297647D01*
X633313Y297147D01*
Y296647D01*
X633480Y296147D01*
X633897Y295647D01*
X634397Y295313D01*
X634980Y295230D01*
X635563Y295397D01*
X636147Y295897D01*
G01X639163Y293980D02*
X639747Y293647D01*
X640413Y293563D01*
X640997Y293647D01*
X641497Y294063D01*
X641830Y294647D01*
Y298563D01*
G01Y297897D02*
X641497Y298230D01*
X640997Y298480D01*
X640413Y298563D01*
X639747Y298397D01*
X639330Y298063D01*
X638997Y297480D01*
X638830Y296897D01*
X638913Y296397D01*
X639247Y295813D01*
X639747Y295397D01*
X640413Y295230D01*
X640913Y295313D01*
X641497Y295647D01*
X641830Y295980D01*
G01X644763Y295230D02*
Y298563D01*
G01Y297897D02*
X645180Y298230D01*
X645597Y298480D01*
X646180Y298563D01*
X646597Y298480D01*
X647097Y298230D01*
G01X650280Y297480D02*
X652947D01*
X652697Y298063D01*
X652280Y298397D01*
X651697Y298563D01*
X651113Y298480D01*
X650613Y298230D01*
X650280Y297647D01*
X650113Y297147D01*
Y296647D01*
X650280Y296147D01*
X650697Y295647D01*
X651197Y295313D01*
X651780Y295230D01*
X652363Y295397D01*
X652947Y295897D01*
G01X655880Y297480D02*
X658547D01*
X658297Y298063D01*
X657880Y298397D01*
X657297Y298563D01*
X656713Y298480D01*
X656213Y298230D01*
X655880Y297647D01*
X655713Y297147D01*
Y296647D01*
X655880Y296147D01*
X656297Y295647D01*
X656797Y295313D01*
X657380Y295230D01*
X657963Y295397D01*
X658547Y295897D01*
G01X603783Y329260D02*
X607117Y330927D01*
X603783Y332593D01*
G01X609967Y330177D02*
X612133D01*
G01Y331677D02*
X609967D01*
G01X616483Y329260D02*
X616650Y330343D01*
X616900Y331260D01*
X617233Y332093D01*
X617650Y333010D01*
X618317Y334260D01*
X614983D01*
G01X622250D02*
X621583Y334093D01*
X621083Y333677D01*
X620750Y333177D01*
X620500Y332510D01*
X620417Y331760D01*
X620500Y331010D01*
X620750Y330343D01*
X621083Y329843D01*
X621583Y329427D01*
X622250Y329260D01*
X622917Y329427D01*
X623417Y329843D01*
X623750Y330343D01*
X624000Y331010D01*
X624083Y331760D01*
X624000Y332510D01*
X623750Y333177D01*
X623417Y333677D01*
X622917Y334093D01*
X622250Y334260D01*
G01X626350Y329093D02*
X629350Y334260D01*
G01X626350D02*
X625850Y334093D01*
X625600Y333843D01*
X625433Y333343D01*
X625600Y332843D01*
X625850Y332593D01*
X626350Y332427D01*
X626850Y332593D01*
X627100Y332843D01*
X627267Y333343D01*
X627100Y333843D01*
X626850Y334093D01*
X626350Y334260D01*
G01X629350Y330927D02*
X628850Y330760D01*
X628600Y330510D01*
X628433Y330010D01*
X628600Y329510D01*
X628850Y329260D01*
X629350Y329093D01*
X629850Y329260D01*
X630100Y329510D01*
X630267Y330010D01*
X630100Y330510D01*
X629850Y330760D01*
X629350Y330927D01*
G01X633283Y328343D02*
X633617Y329427D01*
G01X605763Y349687D02*
X607763D01*
G01X606680Y350770D02*
Y348603D01*
G01X610780Y347853D02*
X613780Y353020D01*
G01X616797Y349687D02*
X618963D01*
G01X623480Y348020D02*
Y353020D01*
X622480Y352020D01*
G01Y348020D02*
X624480D01*
G01X626580D02*
Y351353D01*
G01Y350437D02*
X626830Y350853D01*
X627247Y351187D01*
X627830Y351353D01*
X628413Y351187D01*
X628830Y350853D01*
X629080Y350437D01*
Y348020D01*
G01Y350437D02*
X629330Y350853D01*
X629747Y351187D01*
X630330Y351353D01*
X630913Y351187D01*
X631330Y350853D01*
X631580Y350353D01*
Y348020D01*
G01X634680Y351353D02*
Y348020D01*
G01Y352687D02*
X634513Y352770D01*
Y352937D01*
X634680Y353020D01*
X634847Y352937D01*
Y352770D01*
X634680Y352687D01*
G01X640280Y348020D02*
Y353020D01*
G01X608333Y393000D02*
Y398000D01*
X610500Y393833D01*
X612667Y398000D01*
Y393000D01*
G01X614683Y396333D02*
Y394000D01*
X615017Y393417D01*
X615517Y393083D01*
X616100Y393000D01*
X616683Y393083D01*
X617183Y393417D01*
X617517Y394000D01*
G01Y393000D02*
Y396333D01*
G01X620450Y393583D02*
X620867Y393250D01*
X621450Y393000D01*
X621950D01*
X622450Y393167D01*
X622783Y393417D01*
X622950Y393750D01*
X622867Y394250D01*
X622533Y394500D01*
X621033Y395000D01*
X620700Y395583D01*
X620867Y396000D01*
X621200Y396250D01*
X621700Y396333D01*
X622200Y396250D01*
X622700Y396000D01*
G01X627300Y398000D02*
Y393000D01*
G01X626133Y396333D02*
X628467D01*
G01X638000Y393000D02*
Y397250D01*
X638167Y397667D01*
X638500Y397917D01*
X639000Y398000D01*
X639500Y397833D01*
X639750Y397417D01*
G01X638750Y396000D02*
X637083D01*
G01X644100Y393000D02*
X643600Y393083D01*
X643100Y393417D01*
X642767Y394000D01*
X642600Y394667D01*
X642767Y395333D01*
X643100Y395917D01*
X643600Y396250D01*
X644100Y396333D01*
X644600Y396250D01*
X645100Y395917D01*
X645433Y395333D01*
X645517Y394667D01*
X645433Y394000D01*
X645100Y393417D01*
X644600Y393083D01*
X644100Y393000D01*
G01X649700D02*
Y398000D01*
G01X655300Y393000D02*
Y398000D01*
G01X660900Y393000D02*
X660400Y393083D01*
X659900Y393417D01*
X659567Y394000D01*
X659400Y394667D01*
X659567Y395333D01*
X659900Y395917D01*
X660400Y396250D01*
X660900Y396333D01*
X661400Y396250D01*
X661900Y395917D01*
X662233Y395333D01*
X662317Y394667D01*
X662233Y394000D01*
X661900Y393417D01*
X661400Y393083D01*
X660900Y393000D01*
G01X664417Y396333D02*
X665417Y393000D01*
X666500Y396333D01*
X667583Y393000D01*
X668583Y396333D01*
G01X595500Y679000D02*
Y396000D01*
G01X605810Y429990D02*
Y434240D01*
X605977Y434657D01*
X606310Y434907D01*
X606810Y434990D01*
X607310Y434823D01*
X607560Y434407D01*
G01X606560Y432990D02*
X604893D01*
G01X611910Y429990D02*
X611410Y430073D01*
X610910Y430407D01*
X610577Y430990D01*
X610410Y431657D01*
X610577Y432323D01*
X610910Y432907D01*
X611410Y433240D01*
X611910Y433323D01*
X612410Y433240D01*
X612910Y432907D01*
X613243Y432323D01*
X613327Y431657D01*
X613243Y430990D01*
X612910Y430407D01*
X612410Y430073D01*
X611910Y429990D01*
G01X617510D02*
Y434990D01*
G01X623110Y429990D02*
Y434990D01*
G01X628710Y429990D02*
X628210Y430073D01*
X627710Y430407D01*
X627377Y430990D01*
X627210Y431657D01*
X627377Y432323D01*
X627710Y432907D01*
X628210Y433240D01*
X628710Y433323D01*
X629210Y433240D01*
X629710Y432907D01*
X630043Y432323D01*
X630127Y431657D01*
X630043Y430990D01*
X629710Y430407D01*
X629210Y430073D01*
X628710Y429990D01*
G01X632227Y433323D02*
X633227Y429990D01*
X634310Y433323D01*
X635393Y429990D01*
X636393Y433323D01*
G01X647010Y434990D02*
Y429990D01*
G01Y430740D02*
X646677Y430323D01*
X646177Y430073D01*
X645593Y429990D01*
X644927Y430157D01*
X644427Y430573D01*
X644093Y431073D01*
X644010Y431657D01*
X644093Y432240D01*
X644427Y432740D01*
X644927Y433157D01*
X645593Y433323D01*
X646177Y433240D01*
X646593Y433073D01*
X647010Y432740D01*
G01X649943Y429990D02*
Y433323D01*
G01Y432657D02*
X650360Y432990D01*
X650777Y433240D01*
X651360Y433323D01*
X651777Y433240D01*
X652277Y432990D01*
G01X658210Y429990D02*
Y433323D01*
G01Y432740D02*
X657877Y433073D01*
X657377Y433240D01*
X656793Y433323D01*
X656210Y433157D01*
X655710Y432823D01*
X655377Y432323D01*
X655210Y431657D01*
X655377Y430990D01*
X655710Y430490D01*
X656210Y430157D01*
X656793Y429990D01*
X657377Y430073D01*
X657877Y430323D01*
X658210Y430657D01*
G01X660227Y433323D02*
X661227Y429990D01*
X662310Y433323D01*
X663393Y429990D01*
X664393Y433323D01*
G01X667910D02*
Y429990D01*
G01Y434657D02*
X667743Y434740D01*
Y434907D01*
X667910Y434990D01*
X668077Y434907D01*
Y434740D01*
X667910Y434657D01*
G01X672093Y429990D02*
Y433323D01*
G01Y432490D02*
X672427Y432907D01*
X672927Y433240D01*
X673593Y433323D01*
X674177Y433240D01*
X674677Y432907D01*
X674927Y432323D01*
Y429990D01*
G01X677943Y428740D02*
X678527Y428407D01*
X679193Y428323D01*
X679777Y428407D01*
X680277Y428823D01*
X680610Y429407D01*
Y433323D01*
G01Y432657D02*
X680277Y432990D01*
X679777Y433240D01*
X679193Y433323D01*
X678527Y433157D01*
X678110Y432823D01*
X677777Y432240D01*
X677610Y431657D01*
X677693Y431157D01*
X678027Y430573D01*
X678527Y430157D01*
X679193Y429990D01*
X679693Y430073D01*
X680277Y430407D01*
X680610Y430740D01*
G01X685127Y428323D02*
X685960Y429157D01*
X686377Y429990D01*
Y433323D01*
X685960Y434157D01*
X685127Y434990D01*
G01X606903Y440587D02*
X608903D01*
G01X607820Y441670D02*
Y439503D01*
G01X611920Y438753D02*
X614920Y443920D01*
G01X617937Y440587D02*
X620103D01*
G01X622787Y439670D02*
X623287Y439253D01*
X623870Y439003D01*
X624620Y438920D01*
X625370Y439087D01*
X625953Y439420D01*
X626370Y440003D01*
X626453Y440670D01*
X626287Y441337D01*
X625870Y441753D01*
X625287Y442087D01*
X624703Y442170D01*
X624120Y442087D01*
X623370Y441753D01*
X623620Y443920D01*
X625870D01*
G01X627720Y438920D02*
Y442253D01*
G01Y441337D02*
X627970Y441753D01*
X628387Y442087D01*
X628970Y442253D01*
X629553Y442087D01*
X629970Y441753D01*
X630220Y441337D01*
Y438920D01*
G01Y441337D02*
X630470Y441753D01*
X630887Y442087D01*
X631470Y442253D01*
X632053Y442087D01*
X632470Y441753D01*
X632720Y441253D01*
Y438920D01*
G01X635820Y442253D02*
Y438920D01*
G01Y443587D02*
X635653Y443670D01*
Y443837D01*
X635820Y443920D01*
X635987Y443837D01*
Y443670D01*
X635820Y443587D01*
G01X641420Y438920D02*
Y443920D01*
G01X607500Y452000D02*
Y457000D01*
X606500Y456000D01*
G01Y452000D02*
X608500D01*
G01X613100Y451833D02*
X612933Y451917D01*
Y452083D01*
X613100Y452167D01*
X613267Y452083D01*
Y451917D01*
X613100Y451833D01*
G01X618700Y457000D02*
X618033Y456833D01*
X617533Y456417D01*
X617200Y455917D01*
X616950Y455250D01*
X616867Y454500D01*
X616950Y453750D01*
X617200Y453083D01*
X617533Y452583D01*
X618033Y452167D01*
X618700Y452000D01*
X619367Y452167D01*
X619867Y452583D01*
X620200Y453083D01*
X620450Y453750D01*
X620533Y454500D01*
X620450Y455250D01*
X620200Y455917D01*
X619867Y456417D01*
X619367Y456833D01*
X618700Y457000D01*
G01X621800Y452000D02*
Y455333D01*
G01Y454417D02*
X622050Y454833D01*
X622467Y455167D01*
X623050Y455333D01*
X623633Y455167D01*
X624050Y454833D01*
X624300Y454417D01*
Y452000D01*
G01Y454417D02*
X624550Y454833D01*
X624967Y455167D01*
X625550Y455333D01*
X626133Y455167D01*
X626550Y454833D01*
X626800Y454333D01*
Y452000D01*
G01X629900Y455333D02*
Y452000D01*
G01Y456667D02*
X629733Y456750D01*
Y456917D01*
X629900Y457000D01*
X630067Y456917D01*
Y456750D01*
X629900Y456667D01*
G01X635500Y452000D02*
Y457000D01*
G01X644200Y452000D02*
Y455333D01*
G01Y454417D02*
X644450Y454833D01*
X644867Y455167D01*
X645450Y455333D01*
X646033Y455167D01*
X646450Y454833D01*
X646700Y454417D01*
Y452000D01*
G01Y454417D02*
X646950Y454833D01*
X647367Y455167D01*
X647950Y455333D01*
X648533Y455167D01*
X648950Y454833D01*
X649200Y454333D01*
Y452000D01*
G01X653800D02*
Y455333D01*
G01Y454750D02*
X653467Y455083D01*
X652967Y455250D01*
X652383Y455333D01*
X651800Y455167D01*
X651300Y454833D01*
X650967Y454333D01*
X650800Y453667D01*
X650967Y453000D01*
X651300Y452500D01*
X651800Y452167D01*
X652383Y452000D01*
X652967Y452083D01*
X653467Y452333D01*
X653800Y452667D01*
G01X656650Y455333D02*
X659150Y452000D01*
G01Y455333D02*
X656650Y452000D01*
G01X606583Y471667D02*
X608583D01*
G01X607500Y472750D02*
Y470583D01*
G01X611600Y469833D02*
X614600Y475000D01*
G01X617617Y471667D02*
X619783D01*
G01X622467Y470750D02*
X622967Y470333D01*
X623550Y470083D01*
X624300Y470000D01*
X625050Y470167D01*
X625633Y470500D01*
X626050Y471083D01*
X626133Y471750D01*
X625967Y472417D01*
X625550Y472833D01*
X624967Y473167D01*
X624383Y473250D01*
X623800Y473167D01*
X623050Y472833D01*
X623300Y475000D01*
X625550D01*
G01X627400Y470000D02*
Y473333D01*
G01Y472417D02*
X627650Y472833D01*
X628067Y473167D01*
X628650Y473333D01*
X629233Y473167D01*
X629650Y472833D01*
X629900Y472417D01*
Y470000D01*
G01Y472417D02*
X630150Y472833D01*
X630567Y473167D01*
X631150Y473333D01*
X631733Y473167D01*
X632150Y472833D01*
X632400Y472333D01*
Y470000D01*
G01X635500Y473333D02*
Y470000D01*
G01Y474667D02*
X635333Y474750D01*
Y474917D01*
X635500Y475000D01*
X635667Y474917D01*
Y474750D01*
X635500Y474667D01*
G01X641100Y470000D02*
Y475000D01*
G01X606583Y486667D02*
X608583D01*
G01X607500Y487750D02*
Y485583D01*
G01X611600Y484833D02*
X614600Y490000D01*
G01X617617Y486667D02*
X619783D01*
G01X622467Y485750D02*
X622967Y485333D01*
X623550Y485083D01*
X624300Y485000D01*
X625050Y485167D01*
X625633Y485500D01*
X626050Y486083D01*
X626133Y486750D01*
X625967Y487417D01*
X625550Y487833D01*
X624967Y488167D01*
X624383Y488250D01*
X623800Y488167D01*
X623050Y487833D01*
X623300Y490000D01*
X625550D01*
G01X627400Y485000D02*
Y488333D01*
G01Y487417D02*
X627650Y487833D01*
X628067Y488167D01*
X628650Y488333D01*
X629233Y488167D01*
X629650Y487833D01*
X629900Y487417D01*
Y485000D01*
G01Y487417D02*
X630150Y487833D01*
X630567Y488167D01*
X631150Y488333D01*
X631733Y488167D01*
X632150Y487833D01*
X632400Y487333D01*
Y485000D01*
G01X635500Y488333D02*
Y485000D01*
G01Y489667D02*
X635333Y489750D01*
Y489917D01*
X635500Y490000D01*
X635667Y489917D01*
Y489750D01*
X635500Y489667D01*
G01X641100Y485000D02*
Y490000D01*
G01X606583Y546667D02*
X608583D01*
G01X607500Y547750D02*
Y545583D01*
G01X611600Y544833D02*
X614600Y550000D01*
G01X617617Y546667D02*
X619783D01*
G01X622717Y549167D02*
X623217Y549667D01*
X623800Y549917D01*
X624467Y550000D01*
X625300Y549833D01*
X625883Y549417D01*
X626050Y548917D01*
X625967Y548417D01*
X625633Y548000D01*
X623967Y547167D01*
X623217Y546583D01*
X622717Y545750D01*
X622550Y545000D01*
X626050D01*
G01X627400D02*
Y548333D01*
G01Y547417D02*
X627650Y547833D01*
X628067Y548167D01*
X628650Y548333D01*
X629233Y548167D01*
X629650Y547833D01*
X629900Y547417D01*
Y545000D01*
G01Y547417D02*
X630150Y547833D01*
X630567Y548167D01*
X631150Y548333D01*
X631733Y548167D01*
X632150Y547833D01*
X632400Y547333D01*
Y545000D01*
G01X635500Y548333D02*
Y545000D01*
G01Y549667D02*
X635333Y549750D01*
Y549917D01*
X635500Y550000D01*
X635667Y549917D01*
Y549750D01*
X635500Y549667D01*
G01X641100Y545000D02*
Y550000D01*
G01X606583Y501667D02*
X608583D01*
G01X607500Y502750D02*
Y500583D01*
G01X611267Y501000D02*
X611767Y500417D01*
X612433Y500083D01*
X613183Y500000D01*
X613850Y500083D01*
X614517Y500500D01*
X614933Y501000D01*
X615017Y501500D01*
X614850Y502083D01*
X614267Y502500D01*
X613683Y502667D01*
X612933D01*
G01X613683D02*
X614183Y502917D01*
X614600Y503333D01*
X614767Y503833D01*
X614600Y504333D01*
X614183Y504750D01*
X613433Y505000D01*
X612683Y504917D01*
X611933Y504583D01*
G01X617200Y499833D02*
X620200Y505000D01*
G01X623217Y501667D02*
X625383D01*
G01X629900Y505000D02*
X629233Y504833D01*
X628733Y504417D01*
X628400Y503917D01*
X628150Y503250D01*
X628067Y502500D01*
X628150Y501750D01*
X628400Y501083D01*
X628733Y500583D01*
X629233Y500167D01*
X629900Y500000D01*
X630567Y500167D01*
X631067Y500583D01*
X631400Y501083D01*
X631650Y501750D01*
X631733Y502500D01*
X631650Y503250D01*
X631400Y503917D01*
X631067Y504417D01*
X630567Y504833D01*
X629900Y505000D01*
G01X633000Y500000D02*
Y503333D01*
G01Y502417D02*
X633250Y502833D01*
X633667Y503167D01*
X634250Y503333D01*
X634833Y503167D01*
X635250Y502833D01*
X635500Y502417D01*
Y500000D01*
G01Y502417D02*
X635750Y502833D01*
X636167Y503167D01*
X636750Y503333D01*
X637333Y503167D01*
X637750Y502833D01*
X638000Y502333D01*
Y500000D01*
G01X641100Y503333D02*
Y500000D01*
G01Y504667D02*
X640933Y504750D01*
Y504917D01*
X641100Y505000D01*
X641267Y504917D01*
Y504750D01*
X641100Y504667D01*
G01X646700Y500000D02*
Y505000D01*
G01X606583Y516667D02*
X608583D01*
G01X607500Y517750D02*
Y515583D01*
G01X611600Y514833D02*
X614600Y520000D01*
G01X617617Y516667D02*
X619783D01*
G01X622717Y519167D02*
X623217Y519667D01*
X623800Y519917D01*
X624467Y520000D01*
X625300Y519833D01*
X625883Y519417D01*
X626050Y518917D01*
X625967Y518417D01*
X625633Y518000D01*
X623967Y517167D01*
X623217Y516583D01*
X622717Y515750D01*
X622550Y515000D01*
X626050D01*
G01X627400D02*
Y518333D01*
G01Y517417D02*
X627650Y517833D01*
X628067Y518167D01*
X628650Y518333D01*
X629233Y518167D01*
X629650Y517833D01*
X629900Y517417D01*
Y515000D01*
G01Y517417D02*
X630150Y517833D01*
X630567Y518167D01*
X631150Y518333D01*
X631733Y518167D01*
X632150Y517833D01*
X632400Y517333D01*
Y515000D01*
G01X635500Y518333D02*
Y515000D01*
G01Y519667D02*
X635333Y519750D01*
Y519917D01*
X635500Y520000D01*
X635667Y519917D01*
Y519750D01*
X635500Y519667D01*
G01X641100Y515000D02*
Y520000D01*
G01X606583Y530167D02*
X608583D01*
G01X607500Y531250D02*
Y529083D01*
G01X611600Y528333D02*
X614600Y533500D01*
G01X617617Y530167D02*
X619783D01*
G01X622467Y529500D02*
X622967Y528917D01*
X623633Y528583D01*
X624383Y528500D01*
X625050Y528583D01*
X625717Y529000D01*
X626133Y529500D01*
X626217Y530000D01*
X626050Y530583D01*
X625467Y531000D01*
X624883Y531167D01*
X624133D01*
G01X624883D02*
X625383Y531417D01*
X625800Y531833D01*
X625967Y532333D01*
X625800Y532833D01*
X625383Y533250D01*
X624633Y533500D01*
X623883Y533417D01*
X623133Y533083D01*
G01X627400Y528500D02*
Y531833D01*
G01Y530917D02*
X627650Y531333D01*
X628067Y531667D01*
X628650Y531833D01*
X629233Y531667D01*
X629650Y531333D01*
X629900Y530917D01*
Y528500D01*
G01Y530917D02*
X630150Y531333D01*
X630567Y531667D01*
X631150Y531833D01*
X631733Y531667D01*
X632150Y531333D01*
X632400Y530833D01*
Y528500D01*
G01X635500Y531833D02*
Y528500D01*
G01Y533167D02*
X635333Y533250D01*
Y533417D01*
X635500Y533500D01*
X635667Y533417D01*
Y533250D01*
X635500Y533167D01*
G01X641100Y528500D02*
Y533500D01*
G01X606583Y620167D02*
X608583D01*
G01X607500Y621250D02*
Y619083D01*
G01X611600Y618333D02*
X614600Y623500D01*
G01X617617Y620167D02*
X619783D01*
G01X622717Y622667D02*
X623217Y623167D01*
X623800Y623417D01*
X624467Y623500D01*
X625300Y623333D01*
X625883Y622917D01*
X626050Y622417D01*
X625967Y621917D01*
X625633Y621500D01*
X623967Y620667D01*
X623217Y620083D01*
X622717Y619250D01*
X622550Y618500D01*
X626050D01*
G01X627400D02*
Y621833D01*
G01Y620917D02*
X627650Y621333D01*
X628067Y621667D01*
X628650Y621833D01*
X629233Y621667D01*
X629650Y621333D01*
X629900Y620917D01*
Y618500D01*
G01Y620917D02*
X630150Y621333D01*
X630567Y621667D01*
X631150Y621833D01*
X631733Y621667D01*
X632150Y621333D01*
X632400Y620833D01*
Y618500D01*
G01X635500Y621833D02*
Y618500D01*
G01Y623167D02*
X635333Y623250D01*
Y623417D01*
X635500Y623500D01*
X635667Y623417D01*
Y623250D01*
X635500Y623167D01*
G01X641100Y618500D02*
Y623500D01*
G01X606583Y591667D02*
X608583D01*
G01X607500Y592750D02*
Y590583D01*
G01X611600Y589833D02*
X614600Y595000D01*
G01X617617Y591667D02*
X619783D01*
G01X622467Y591000D02*
X622967Y590417D01*
X623633Y590083D01*
X624383Y590000D01*
X625050Y590083D01*
X625717Y590500D01*
X626133Y591000D01*
X626217Y591500D01*
X626050Y592083D01*
X625467Y592500D01*
X624883Y592667D01*
X624133D01*
G01X624883D02*
X625383Y592917D01*
X625800Y593333D01*
X625967Y593833D01*
X625800Y594333D01*
X625383Y594750D01*
X624633Y595000D01*
X623883Y594917D01*
X623133Y594583D01*
G01X627400Y590000D02*
Y593333D01*
G01Y592417D02*
X627650Y592833D01*
X628067Y593167D01*
X628650Y593333D01*
X629233Y593167D01*
X629650Y592833D01*
X629900Y592417D01*
Y590000D01*
G01Y592417D02*
X630150Y592833D01*
X630567Y593167D01*
X631150Y593333D01*
X631733Y593167D01*
X632150Y592833D01*
X632400Y592333D01*
Y590000D01*
G01X635500Y593333D02*
Y590000D01*
G01Y594667D02*
X635333Y594750D01*
Y594917D01*
X635500Y595000D01*
X635667Y594917D01*
Y594750D01*
X635500Y594667D01*
G01X641100Y590000D02*
Y595000D01*
G01X605417Y603500D02*
X607500Y608500D01*
X609583Y603500D01*
G01X608833Y605250D02*
X606167D01*
G01X613100Y603500D02*
Y608500D01*
G01X618700Y603500D02*
Y608500D01*
G01X624300Y603500D02*
X623800Y603583D01*
X623300Y603917D01*
X622967Y604500D01*
X622800Y605167D01*
X622967Y605833D01*
X623300Y606417D01*
X623800Y606750D01*
X624300Y606833D01*
X624800Y606750D01*
X625300Y606417D01*
X625633Y605833D01*
X625717Y605167D01*
X625633Y604500D01*
X625300Y603917D01*
X624800Y603583D01*
X624300Y603500D01*
G01X627817Y606833D02*
X628817Y603500D01*
X629900Y606833D01*
X630983Y603500D01*
X631983Y606833D01*
G01X606583Y575167D02*
X608583D01*
G01X607500Y576250D02*
Y574083D01*
G01X611517Y577667D02*
X612017Y578167D01*
X612600Y578417D01*
X613267Y578500D01*
X614100Y578333D01*
X614683Y577917D01*
X614850Y577417D01*
X614767Y576917D01*
X614433Y576500D01*
X612767Y575667D01*
X612017Y575083D01*
X611517Y574250D01*
X611350Y573500D01*
X614850D01*
G01X617200Y573333D02*
X620200Y578500D01*
G01X623217Y575167D02*
X625383D01*
G01X630900Y573500D02*
Y578500D01*
X627817Y574917D01*
X631983D01*
G01X633000Y573500D02*
Y576833D01*
G01Y575917D02*
X633250Y576333D01*
X633667Y576667D01*
X634250Y576833D01*
X634833Y576667D01*
X635250Y576333D01*
X635500Y575917D01*
Y573500D01*
G01Y575917D02*
X635750Y576333D01*
X636167Y576667D01*
X636750Y576833D01*
X637333Y576667D01*
X637750Y576333D01*
X638000Y575833D01*
Y573500D01*
G01X641100Y576833D02*
Y573500D01*
G01Y578167D02*
X640933Y578250D01*
Y578417D01*
X641100Y578500D01*
X641267Y578417D01*
Y578250D01*
X641100Y578167D01*
G01X646700Y573500D02*
Y578500D01*
G01X606583Y561667D02*
X608583D01*
G01X607500Y562750D02*
Y560583D01*
G01X611600Y559833D02*
X614600Y565000D01*
G01X617617Y561667D02*
X619783D01*
G01X622717Y564167D02*
X623217Y564667D01*
X623800Y564917D01*
X624467Y565000D01*
X625300Y564833D01*
X625883Y564417D01*
X626050Y563917D01*
X625967Y563417D01*
X625633Y563000D01*
X623967Y562167D01*
X623217Y561583D01*
X622717Y560750D01*
X622550Y560000D01*
X626050D01*
G01X627400D02*
Y563333D01*
G01Y562417D02*
X627650Y562833D01*
X628067Y563167D01*
X628650Y563333D01*
X629233Y563167D01*
X629650Y562833D01*
X629900Y562417D01*
Y560000D01*
G01Y562417D02*
X630150Y562833D01*
X630567Y563167D01*
X631150Y563333D01*
X631733Y563167D01*
X632150Y562833D01*
X632400Y562333D01*
Y560000D01*
G01X635500Y563333D02*
Y560000D01*
G01Y564667D02*
X635333Y564750D01*
Y564917D01*
X635500Y565000D01*
X635667Y564917D01*
Y564750D01*
X635500Y564667D01*
G01X641100Y560000D02*
Y565000D01*
G01X617500Y668500D02*
Y663500D01*
G01X615583Y668500D02*
X619417D01*
G01X623100Y663500D02*
X622600Y663583D01*
X622100Y663917D01*
X621767Y664500D01*
X621600Y665167D01*
X621767Y665833D01*
X622100Y666417D01*
X622600Y666750D01*
X623100Y666833D01*
X623600Y666750D01*
X624100Y666417D01*
X624433Y665833D01*
X624517Y665167D01*
X624433Y664500D01*
X624100Y663917D01*
X623600Y663583D01*
X623100Y663500D01*
G01X628700D02*
Y668500D01*
G01X633050Y665750D02*
X635717D01*
X635467Y666333D01*
X635050Y666667D01*
X634467Y666833D01*
X633883Y666750D01*
X633383Y666500D01*
X633050Y665917D01*
X632883Y665417D01*
Y664917D01*
X633050Y664417D01*
X633467Y663917D01*
X633967Y663583D01*
X634550Y663500D01*
X635133Y663667D01*
X635717Y664167D01*
G01X638733Y663500D02*
Y666833D01*
G01Y666167D02*
X639150Y666500D01*
X639567Y666750D01*
X640150Y666833D01*
X640567Y666750D01*
X641067Y666500D01*
G01X647000Y663500D02*
Y666833D01*
G01Y666250D02*
X646667Y666583D01*
X646167Y666750D01*
X645583Y666833D01*
X645000Y666667D01*
X644500Y666333D01*
X644167Y665833D01*
X644000Y665167D01*
X644167Y664500D01*
X644500Y664000D01*
X645000Y663667D01*
X645583Y663500D01*
X646167Y663583D01*
X646667Y663833D01*
X647000Y664167D01*
G01X649683Y663500D02*
Y666833D01*
G01Y666000D02*
X650017Y666417D01*
X650517Y666750D01*
X651183Y666833D01*
X651767Y666750D01*
X652267Y666417D01*
X652517Y665833D01*
Y663500D01*
G01X658033Y666417D02*
X657450Y666750D01*
X656950Y666833D01*
X656283Y666667D01*
X655783Y666333D01*
X655450Y665750D01*
X655367Y665167D01*
X655450Y664583D01*
X655783Y664083D01*
X656283Y663667D01*
X656950Y663500D01*
X657533Y663667D01*
X658033Y664000D01*
G01X661050Y665750D02*
X663717D01*
X663467Y666333D01*
X663050Y666667D01*
X662467Y666833D01*
X661883Y666750D01*
X661383Y666500D01*
X661050Y665917D01*
X660883Y665417D01*
Y664917D01*
X661050Y664417D01*
X661467Y663917D01*
X661967Y663583D01*
X662550Y663500D01*
X663133Y663667D01*
X663717Y664167D01*
G01X605353Y638700D02*
Y643700D01*
X607520Y639533D01*
X609687Y643700D01*
Y638700D01*
G01X611703Y642033D02*
Y639700D01*
X612037Y639117D01*
X612537Y638783D01*
X613120Y638700D01*
X613703Y638783D01*
X614203Y639117D01*
X614537Y639700D01*
G01Y638700D02*
Y642033D01*
G01X617470Y639283D02*
X617887Y638950D01*
X618470Y638700D01*
X618970D01*
X619470Y638867D01*
X619803Y639117D01*
X619970Y639450D01*
X619887Y639950D01*
X619553Y640200D01*
X618053Y640700D01*
X617720Y641283D01*
X617887Y641700D01*
X618220Y641950D01*
X618720Y642033D01*
X619220Y641950D01*
X619720Y641700D01*
G01X624320Y643700D02*
Y638700D01*
G01X623153Y642033D02*
X625487D01*
G01X635020Y638700D02*
Y642950D01*
X635187Y643367D01*
X635520Y643617D01*
X636020Y643700D01*
X636520Y643533D01*
X636770Y643117D01*
G01X635770Y641700D02*
X634103D01*
G01X641120Y638700D02*
X640620Y638783D01*
X640120Y639117D01*
X639787Y639700D01*
X639620Y640367D01*
X639787Y641033D01*
X640120Y641617D01*
X640620Y641950D01*
X641120Y642033D01*
X641620Y641950D01*
X642120Y641617D01*
X642453Y641033D01*
X642537Y640367D01*
X642453Y639700D01*
X642120Y639117D01*
X641620Y638783D01*
X641120Y638700D01*
G01X646720D02*
Y643700D01*
G01X652320Y638700D02*
Y643700D01*
G01X657920Y638700D02*
X657420Y638783D01*
X656920Y639117D01*
X656587Y639700D01*
X656420Y640367D01*
X656587Y641033D01*
X656920Y641617D01*
X657420Y641950D01*
X657920Y642033D01*
X658420Y641950D01*
X658920Y641617D01*
X659253Y641033D01*
X659337Y640367D01*
X659253Y639700D01*
X658920Y639117D01*
X658420Y638783D01*
X657920Y638700D01*
G01X661437Y642033D02*
X662437Y638700D01*
X663520Y642033D01*
X664603Y638700D01*
X665603Y642033D01*
G01X590417Y860000D02*
X592500Y855000D01*
X594583Y860000D01*
G01X596267Y856000D02*
X596767Y855417D01*
X597433Y855083D01*
X598183Y855000D01*
X598850Y855083D01*
X599517Y855500D01*
X599933Y856000D01*
X600017Y856500D01*
X599850Y857083D01*
X599267Y857500D01*
X598683Y857667D01*
X597933D01*
G01X598683D02*
X599183Y857917D01*
X599600Y858333D01*
X599767Y858833D01*
X599600Y859333D01*
X599183Y859750D01*
X598433Y860000D01*
X597683Y859917D01*
X596933Y859583D01*
G01X603700Y854833D02*
X603533Y854917D01*
Y855083D01*
X603700Y855167D01*
X603867Y855083D01*
Y854917D01*
X603700Y854833D01*
G01X610300Y855000D02*
Y860000D01*
X607217Y856417D01*
X611383D01*
G01X614900Y854833D02*
X614733Y854917D01*
Y855083D01*
X614900Y855167D01*
X615067Y855083D01*
Y854917D01*
X614900Y854833D01*
G01X620500Y855000D02*
Y860000D01*
X619500Y859000D01*
G01Y855000D02*
X621500D01*
G01X641317Y859167D02*
X641817Y859667D01*
X642400Y859917D01*
X643067Y860000D01*
X643900Y859833D01*
X644483Y859417D01*
X644650Y858917D01*
X644567Y858417D01*
X644233Y858000D01*
X642567Y857167D01*
X641817Y856583D01*
X641317Y855750D01*
X641150Y855000D01*
X644650D01*
G01X648500Y860000D02*
X647833Y859833D01*
X647333Y859417D01*
X647000Y858917D01*
X646750Y858250D01*
X646667Y857500D01*
X646750Y856750D01*
X647000Y856083D01*
X647333Y855583D01*
X647833Y855167D01*
X648500Y855000D01*
X649167Y855167D01*
X649667Y855583D01*
X650000Y856083D01*
X650250Y856750D01*
X650333Y857500D01*
X650250Y858250D01*
X650000Y858917D01*
X649667Y859417D01*
X649167Y859833D01*
X648500Y860000D01*
G01X654100Y855000D02*
Y860000D01*
X653100Y859000D01*
G01Y855000D02*
X655100D01*
G01X657867Y855750D02*
X658367Y855333D01*
X658950Y855083D01*
X659700Y855000D01*
X660450Y855167D01*
X661033Y855500D01*
X661450Y856083D01*
X661533Y856750D01*
X661367Y857417D01*
X660950Y857833D01*
X660367Y858167D01*
X659783Y858250D01*
X659200Y858167D01*
X658450Y857833D01*
X658700Y860000D01*
X660950D01*
G01X663800Y854833D02*
X666800Y860000D01*
G01X670900D02*
X670233Y859833D01*
X669733Y859417D01*
X669400Y858917D01*
X669150Y858250D01*
X669067Y857500D01*
X669150Y856750D01*
X669400Y856083D01*
X669733Y855583D01*
X670233Y855167D01*
X670900Y855000D01*
X671567Y855167D01*
X672067Y855583D01*
X672400Y856083D01*
X672650Y856750D01*
X672733Y857500D01*
X672650Y858250D01*
X672400Y858917D01*
X672067Y859417D01*
X671567Y859833D01*
X670900Y860000D01*
G01X674917Y857083D02*
X675500Y857667D01*
X676000Y858000D01*
X676667Y858167D01*
X677250Y858000D01*
X677667Y857667D01*
X678000Y857167D01*
X678083Y856583D01*
X678000Y856083D01*
X677667Y855583D01*
X677167Y855167D01*
X676583Y855000D01*
X675917Y855167D01*
X675333Y855667D01*
X675000Y856417D01*
X674917Y857250D01*
X675083Y858333D01*
X675333Y858917D01*
X675750Y859500D01*
X676333Y859917D01*
X676917Y860000D01*
X677500Y859833D01*
X677917Y859417D01*
G01X650853Y438153D02*
X650020Y438987D01*
X649603Y439820D01*
Y443153D01*
X650020Y443987D01*
X650853Y444820D01*
G01X656870Y439820D02*
X656370Y439903D01*
X655870Y440237D01*
X655537Y440820D01*
X655370Y441487D01*
X655537Y442153D01*
X655870Y442737D01*
X656370Y443070D01*
X656870Y443153D01*
X657370Y443070D01*
X657870Y442737D01*
X658203Y442153D01*
X658287Y441487D01*
X658203Y440820D01*
X657870Y440237D01*
X657370Y439903D01*
X656870Y439820D01*
G01X661303D02*
Y443153D01*
G01Y442487D02*
X661720Y442820D01*
X662137Y443070D01*
X662720Y443153D01*
X663137Y443070D01*
X663637Y442820D01*
G01X736937Y-65320D02*
X737437Y-65737D01*
X738020Y-65987D01*
X738770Y-66070D01*
X739520Y-65903D01*
X740103Y-65570D01*
X740520Y-64987D01*
X740603Y-64320D01*
X740437Y-63653D01*
X740020Y-63237D01*
X739437Y-62903D01*
X738853Y-62820D01*
X738270Y-62903D01*
X737520Y-63237D01*
X737770Y-61070D01*
X740020D01*
G01X744370Y-66237D02*
X744203Y-66153D01*
Y-65987D01*
X744370Y-65903D01*
X744537Y-65987D01*
Y-66153D01*
X744370Y-66237D01*
G01X749970Y-66070D02*
Y-61070D01*
X748970Y-62070D01*
G01Y-66070D02*
X750970D01*
G01X760170Y-61070D02*
X762170D01*
G01X761170D02*
Y-66070D01*
G01X760170D02*
X762170D01*
G01X766270D02*
Y-61820D01*
X766437Y-61403D01*
X766770Y-61153D01*
X767270Y-61070D01*
X767770Y-61237D01*
X768020Y-61653D01*
G01X767020Y-63070D02*
X765353D01*
G01X778470Y-63570D02*
X780137D01*
Y-65070D01*
X779637Y-65570D01*
X779053Y-65903D01*
X778220Y-66070D01*
X777387Y-65903D01*
X776803Y-65570D01*
X776303Y-65070D01*
X775970Y-64487D01*
X775803Y-63820D01*
Y-63237D01*
X775970Y-62737D01*
X776303Y-62153D01*
X776803Y-61653D01*
X777303Y-61320D01*
X777970Y-61070D01*
X778553D01*
X779220Y-61237D01*
X779720Y-61570D01*
G01X782320Y-63820D02*
X784987D01*
X784737Y-63237D01*
X784320Y-62903D01*
X783737Y-62737D01*
X783153Y-62820D01*
X782653Y-63070D01*
X782320Y-63653D01*
X782153Y-64153D01*
Y-64653D01*
X782320Y-65153D01*
X782737Y-65653D01*
X783237Y-65987D01*
X783820Y-66070D01*
X784403Y-65903D01*
X784987Y-65403D01*
G01X788003Y-66070D02*
Y-62737D01*
G01Y-63403D02*
X788420Y-63070D01*
X788837Y-62820D01*
X789420Y-62737D01*
X789837Y-62820D01*
X790337Y-63070D01*
G01X793270Y-66070D02*
Y-61070D01*
G01Y-63570D02*
X793687Y-63070D01*
X794187Y-62820D01*
X794687Y-62737D01*
X795437Y-62903D01*
X795937Y-63237D01*
X796270Y-63820D01*
Y-64487D01*
X796103Y-65153D01*
X795770Y-65653D01*
X795187Y-65987D01*
X794687Y-66070D01*
X794187Y-65987D01*
X793687Y-65737D01*
X793270Y-65320D01*
G01X799120Y-63820D02*
X801787D01*
X801537Y-63237D01*
X801120Y-62903D01*
X800537Y-62737D01*
X799953Y-62820D01*
X799453Y-63070D01*
X799120Y-63653D01*
X798953Y-64153D01*
Y-64653D01*
X799120Y-65153D01*
X799537Y-65653D01*
X800037Y-65987D01*
X800620Y-66070D01*
X801203Y-65903D01*
X801787Y-65403D01*
G01X804803Y-66070D02*
Y-62737D01*
G01Y-63403D02*
X805220Y-63070D01*
X805637Y-62820D01*
X806220Y-62737D01*
X806637Y-62820D01*
X807137Y-63070D01*
G01X815753Y-66070D02*
Y-61070D01*
G01Y-63487D02*
X816170Y-63070D01*
X816587Y-62820D01*
X817253Y-62737D01*
X817753Y-62820D01*
X818337Y-63153D01*
X818587Y-63653D01*
Y-66070D01*
G01X824270D02*
Y-62737D01*
G01Y-63320D02*
X823937Y-62987D01*
X823437Y-62820D01*
X822853Y-62737D01*
X822270Y-62903D01*
X821770Y-63237D01*
X821437Y-63737D01*
X821270Y-64403D01*
X821437Y-65070D01*
X821770Y-65570D01*
X822270Y-65903D01*
X822853Y-66070D01*
X823437Y-65987D01*
X823937Y-65737D01*
X824270Y-65403D01*
G01X827120Y-65487D02*
X827537Y-65820D01*
X828120Y-66070D01*
X828620D01*
X829120Y-65903D01*
X829453Y-65653D01*
X829620Y-65320D01*
X829537Y-64820D01*
X829203Y-64570D01*
X827703Y-64070D01*
X827370Y-63487D01*
X827537Y-63070D01*
X827870Y-62820D01*
X828370Y-62737D01*
X828870Y-62820D01*
X829370Y-63070D01*
G01X839570Y-61070D02*
Y-66070D01*
G01X838403Y-62737D02*
X840737D01*
G01X843753Y-66070D02*
Y-61070D01*
G01Y-63487D02*
X844170Y-63070D01*
X844587Y-62820D01*
X845253Y-62737D01*
X845753Y-62820D01*
X846337Y-63153D01*
X846587Y-63653D01*
Y-66070D01*
G01X850770Y-62737D02*
Y-66070D01*
G01Y-61403D02*
X850603Y-61320D01*
Y-61153D01*
X850770Y-61070D01*
X850937Y-61153D01*
Y-61320D01*
X850770Y-61403D01*
G01X855120Y-65487D02*
X855537Y-65820D01*
X856120Y-66070D01*
X856620D01*
X857120Y-65903D01*
X857453Y-65653D01*
X857620Y-65320D01*
X857537Y-64820D01*
X857203Y-64570D01*
X855703Y-64070D01*
X855370Y-63487D01*
X855537Y-63070D01*
X855870Y-62820D01*
X856370Y-62737D01*
X856870Y-62820D01*
X857370Y-63070D01*
G01X866153Y-66070D02*
Y-61070D01*
G01X868820Y-62737D02*
X866153Y-64653D01*
G01X867237Y-63903D02*
X868987Y-66070D01*
G01X873170Y-62737D02*
Y-66070D01*
G01Y-61403D02*
X873003Y-61320D01*
Y-61153D01*
X873170Y-61070D01*
X873337Y-61153D01*
Y-61320D01*
X873170Y-61403D01*
G01X877353Y-66070D02*
Y-62737D01*
G01Y-63570D02*
X877687Y-63153D01*
X878187Y-62820D01*
X878853Y-62737D01*
X879437Y-62820D01*
X879937Y-63153D01*
X880187Y-63737D01*
Y-66070D01*
G01X885870Y-61070D02*
Y-66070D01*
G01Y-65320D02*
X885537Y-65737D01*
X885037Y-65987D01*
X884453Y-66070D01*
X883787Y-65903D01*
X883287Y-65487D01*
X882953Y-64987D01*
X882870Y-64403D01*
X882953Y-63820D01*
X883287Y-63320D01*
X883787Y-62903D01*
X884453Y-62737D01*
X885037Y-62820D01*
X885453Y-62987D01*
X885870Y-63320D01*
G01X895570Y-66070D02*
X895070Y-65987D01*
X894570Y-65653D01*
X894237Y-65070D01*
X894070Y-64403D01*
X894237Y-63737D01*
X894570Y-63153D01*
X895070Y-62820D01*
X895570Y-62737D01*
X896070Y-62820D01*
X896570Y-63153D01*
X896903Y-63737D01*
X896987Y-64403D01*
X896903Y-65070D01*
X896570Y-65653D01*
X896070Y-65987D01*
X895570Y-66070D01*
G01X900670D02*
Y-61820D01*
X900837Y-61403D01*
X901170Y-61153D01*
X901670Y-61070D01*
X902170Y-61237D01*
X902420Y-61653D01*
G01X901420Y-63070D02*
X899753D01*
G01X913870Y-61070D02*
Y-66070D01*
G01Y-65320D02*
X913537Y-65737D01*
X913037Y-65987D01*
X912453Y-66070D01*
X911787Y-65903D01*
X911287Y-65487D01*
X910953Y-64987D01*
X910870Y-64403D01*
X910953Y-63820D01*
X911287Y-63320D01*
X911787Y-62903D01*
X912453Y-62737D01*
X913037Y-62820D01*
X913453Y-62987D01*
X913870Y-63320D01*
G01X916720Y-63820D02*
X919387D01*
X919137Y-63237D01*
X918720Y-62903D01*
X918137Y-62737D01*
X917553Y-62820D01*
X917053Y-63070D01*
X916720Y-63653D01*
X916553Y-64153D01*
Y-64653D01*
X916720Y-65153D01*
X917137Y-65653D01*
X917637Y-65987D01*
X918220Y-66070D01*
X918803Y-65903D01*
X919387Y-65403D01*
G01X922320Y-65487D02*
X922737Y-65820D01*
X923320Y-66070D01*
X923820D01*
X924320Y-65903D01*
X924653Y-65653D01*
X924820Y-65320D01*
X924737Y-64820D01*
X924403Y-64570D01*
X922903Y-64070D01*
X922570Y-63487D01*
X922737Y-63070D01*
X923070Y-62820D01*
X923570Y-62737D01*
X924070Y-62820D01*
X924570Y-63070D01*
G01X929170Y-62737D02*
Y-66070D01*
G01Y-61403D02*
X929003Y-61320D01*
Y-61153D01*
X929170Y-61070D01*
X929337Y-61153D01*
Y-61320D01*
X929170Y-61403D01*
G01X933603Y-67320D02*
X934187Y-67653D01*
X934853Y-67737D01*
X935437Y-67653D01*
X935937Y-67237D01*
X936270Y-66653D01*
Y-62737D01*
G01Y-63403D02*
X935937Y-63070D01*
X935437Y-62820D01*
X934853Y-62737D01*
X934187Y-62903D01*
X933770Y-63237D01*
X933437Y-63820D01*
X933270Y-64403D01*
X933353Y-64903D01*
X933687Y-65487D01*
X934187Y-65903D01*
X934853Y-66070D01*
X935353Y-65987D01*
X935937Y-65653D01*
X936270Y-65320D01*
G01X938953Y-66070D02*
Y-62737D01*
G01Y-63570D02*
X939287Y-63153D01*
X939787Y-62820D01*
X940453Y-62737D01*
X941037Y-62820D01*
X941537Y-63153D01*
X941787Y-63737D01*
Y-66070D01*
G01X945803Y-66987D02*
X946137Y-65903D01*
G01X955670Y-67737D02*
Y-62737D01*
G01Y-63487D02*
X956087Y-63070D01*
X956503Y-62820D01*
X957170Y-62737D01*
X957753Y-62820D01*
X958337Y-63237D01*
X958587Y-63820D01*
X958670Y-64403D01*
X958587Y-64987D01*
X958337Y-65570D01*
X957837Y-65903D01*
X957170Y-66070D01*
X956587Y-65987D01*
X956003Y-65737D01*
X955670Y-65403D01*
G01X962770Y-66070D02*
Y-61070D01*
G01X967120Y-63820D02*
X969787D01*
X969537Y-63237D01*
X969120Y-62903D01*
X968537Y-62737D01*
X967953Y-62820D01*
X967453Y-63070D01*
X967120Y-63653D01*
X966953Y-64153D01*
Y-64653D01*
X967120Y-65153D01*
X967537Y-65653D01*
X968037Y-65987D01*
X968620Y-66070D01*
X969203Y-65903D01*
X969787Y-65403D01*
G01X975470Y-66070D02*
Y-62737D01*
G01Y-63320D02*
X975137Y-62987D01*
X974637Y-62820D01*
X974053Y-62737D01*
X973470Y-62903D01*
X972970Y-63237D01*
X972637Y-63737D01*
X972470Y-64403D01*
X972637Y-65070D01*
X972970Y-65570D01*
X973470Y-65903D01*
X974053Y-66070D01*
X974637Y-65987D01*
X975137Y-65737D01*
X975470Y-65403D01*
G01X978320Y-65487D02*
X978737Y-65820D01*
X979320Y-66070D01*
X979820D01*
X980320Y-65903D01*
X980653Y-65653D01*
X980820Y-65320D01*
X980737Y-64820D01*
X980403Y-64570D01*
X978903Y-64070D01*
X978570Y-63487D01*
X978737Y-63070D01*
X979070Y-62820D01*
X979570Y-62737D01*
X980070Y-62820D01*
X980570Y-63070D01*
G01X983920Y-63820D02*
X986587D01*
X986337Y-63237D01*
X985920Y-62903D01*
X985337Y-62737D01*
X984753Y-62820D01*
X984253Y-63070D01*
X983920Y-63653D01*
X983753Y-64153D01*
Y-64653D01*
X983920Y-65153D01*
X984337Y-65653D01*
X984837Y-65987D01*
X985420Y-66070D01*
X986003Y-65903D01*
X986587Y-65403D01*
G01X995870Y-66070D02*
Y-61820D01*
X996037Y-61403D01*
X996370Y-61153D01*
X996870Y-61070D01*
X997370Y-61237D01*
X997620Y-61653D01*
G01X996620Y-63070D02*
X994953D01*
G01X1001970Y-66070D02*
X1001470Y-65987D01*
X1000970Y-65653D01*
X1000637Y-65070D01*
X1000470Y-64403D01*
X1000637Y-63737D01*
X1000970Y-63153D01*
X1001470Y-62820D01*
X1001970Y-62737D01*
X1002470Y-62820D01*
X1002970Y-63153D01*
X1003303Y-63737D01*
X1003387Y-64403D01*
X1003303Y-65070D01*
X1002970Y-65653D01*
X1002470Y-65987D01*
X1001970Y-66070D01*
G01X1007570D02*
Y-61070D01*
G01X1013170Y-66070D02*
Y-61070D01*
G01X1018770Y-66070D02*
X1018270Y-65987D01*
X1017770Y-65653D01*
X1017437Y-65070D01*
X1017270Y-64403D01*
X1017437Y-63737D01*
X1017770Y-63153D01*
X1018270Y-62820D01*
X1018770Y-62737D01*
X1019270Y-62820D01*
X1019770Y-63153D01*
X1020103Y-63737D01*
X1020187Y-64403D01*
X1020103Y-65070D01*
X1019770Y-65653D01*
X1019270Y-65987D01*
X1018770Y-66070D01*
G01X1022287Y-62737D02*
X1023287Y-66070D01*
X1024370Y-62737D01*
X1025453Y-66070D01*
X1026453Y-62737D01*
G01X1029970Y-66237D02*
X1029803Y-66153D01*
Y-65987D01*
X1029970Y-65903D01*
X1030137Y-65987D01*
Y-66153D01*
X1029970Y-66237D01*
G01X1040170Y-61070D02*
X1042170D01*
G01X1041170D02*
Y-66070D01*
G01X1040170D02*
X1042170D01*
G01X1046270D02*
Y-61820D01*
X1046437Y-61403D01*
X1046770Y-61153D01*
X1047270Y-61070D01*
X1047770Y-61237D01*
X1048020Y-61653D01*
G01X1047020Y-63070D02*
X1045353D01*
G01X1056553Y-66070D02*
Y-62737D01*
G01Y-63570D02*
X1056887Y-63153D01*
X1057387Y-62820D01*
X1058053Y-62737D01*
X1058637Y-62820D01*
X1059137Y-63153D01*
X1059387Y-63737D01*
Y-66070D01*
G01X1063570D02*
X1063070Y-65987D01*
X1062570Y-65653D01*
X1062237Y-65070D01*
X1062070Y-64403D01*
X1062237Y-63737D01*
X1062570Y-63153D01*
X1063070Y-62820D01*
X1063570Y-62737D01*
X1064070Y-62820D01*
X1064570Y-63153D01*
X1064903Y-63737D01*
X1064987Y-64403D01*
X1064903Y-65070D01*
X1064570Y-65653D01*
X1064070Y-65987D01*
X1063570Y-66070D01*
G01X1069170Y-61070D02*
Y-66070D01*
G01X1068003Y-62737D02*
X1070337D01*
G01X1074603Y-66987D02*
X1074937Y-65903D01*
G01X1084470Y-67737D02*
Y-62737D01*
G01Y-63487D02*
X1084887Y-63070D01*
X1085303Y-62820D01*
X1085970Y-62737D01*
X1086553Y-62820D01*
X1087137Y-63237D01*
X1087387Y-63820D01*
X1087470Y-64403D01*
X1087387Y-64987D01*
X1087137Y-65570D01*
X1086637Y-65903D01*
X1085970Y-66070D01*
X1085387Y-65987D01*
X1084803Y-65737D01*
X1084470Y-65403D01*
G01X1091570Y-66070D02*
Y-61070D01*
G01X1095920Y-63820D02*
X1098587D01*
X1098337Y-63237D01*
X1097920Y-62903D01*
X1097337Y-62737D01*
X1096753Y-62820D01*
X1096253Y-63070D01*
X1095920Y-63653D01*
X1095753Y-64153D01*
Y-64653D01*
X1095920Y-65153D01*
X1096337Y-65653D01*
X1096837Y-65987D01*
X1097420Y-66070D01*
X1098003Y-65903D01*
X1098587Y-65403D01*
G01X1104270Y-66070D02*
Y-62737D01*
G01Y-63320D02*
X1103937Y-62987D01*
X1103437Y-62820D01*
X1102853Y-62737D01*
X1102270Y-62903D01*
X1101770Y-63237D01*
X1101437Y-63737D01*
X1101270Y-64403D01*
X1101437Y-65070D01*
X1101770Y-65570D01*
X1102270Y-65903D01*
X1102853Y-66070D01*
X1103437Y-65987D01*
X1103937Y-65737D01*
X1104270Y-65403D01*
G01X1107120Y-65487D02*
X1107537Y-65820D01*
X1108120Y-66070D01*
X1108620D01*
X1109120Y-65903D01*
X1109453Y-65653D01*
X1109620Y-65320D01*
X1109537Y-64820D01*
X1109203Y-64570D01*
X1107703Y-64070D01*
X1107370Y-63487D01*
X1107537Y-63070D01*
X1107870Y-62820D01*
X1108370Y-62737D01*
X1108870Y-62820D01*
X1109370Y-63070D01*
G01X1112720Y-63820D02*
X1115387D01*
X1115137Y-63237D01*
X1114720Y-62903D01*
X1114137Y-62737D01*
X1113553Y-62820D01*
X1113053Y-63070D01*
X1112720Y-63653D01*
X1112553Y-64153D01*
Y-64653D01*
X1112720Y-65153D01*
X1113137Y-65653D01*
X1113637Y-65987D01*
X1114220Y-66070D01*
X1114803Y-65903D01*
X1115387Y-65403D01*
G01X1125170Y-62737D02*
Y-66070D01*
G01Y-61403D02*
X1125003Y-61320D01*
Y-61153D01*
X1125170Y-61070D01*
X1125337Y-61153D01*
Y-61320D01*
X1125170Y-61403D01*
G01X1132270Y-67737D02*
Y-62737D01*
G01Y-63487D02*
X1131853Y-63070D01*
X1131353Y-62820D01*
X1130770Y-62737D01*
X1130270Y-62820D01*
X1129687Y-63237D01*
X1129353Y-63820D01*
X1129270Y-64403D01*
X1129353Y-64987D01*
X1129687Y-65570D01*
X1130270Y-65987D01*
X1130770Y-66070D01*
X1131353Y-65987D01*
X1131853Y-65737D01*
X1132270Y-65320D01*
G01X1134953Y-66070D02*
Y-62737D01*
G01Y-63570D02*
X1135287Y-63153D01*
X1135787Y-62820D01*
X1136453Y-62737D01*
X1137037Y-62820D01*
X1137537Y-63153D01*
X1137787Y-63737D01*
Y-66070D01*
G01X1141970D02*
X1141470Y-65987D01*
X1140970Y-65653D01*
X1140637Y-65070D01*
X1140470Y-64403D01*
X1140637Y-63737D01*
X1140970Y-63153D01*
X1141470Y-62820D01*
X1141970Y-62737D01*
X1142470Y-62820D01*
X1142970Y-63153D01*
X1143303Y-63737D01*
X1143387Y-64403D01*
X1143303Y-65070D01*
X1142970Y-65653D01*
X1142470Y-65987D01*
X1141970Y-66070D01*
G01X1146403D02*
Y-62737D01*
G01Y-63403D02*
X1146820Y-63070D01*
X1147237Y-62820D01*
X1147820Y-62737D01*
X1148237Y-62820D01*
X1148737Y-63070D01*
G01X1151920Y-63820D02*
X1154587D01*
X1154337Y-63237D01*
X1153920Y-62903D01*
X1153337Y-62737D01*
X1152753Y-62820D01*
X1152253Y-63070D01*
X1151920Y-63653D01*
X1151753Y-64153D01*
Y-64653D01*
X1151920Y-65153D01*
X1152337Y-65653D01*
X1152837Y-65987D01*
X1153420Y-66070D01*
X1154003Y-65903D01*
X1154587Y-65403D01*
G01X1164370Y-61070D02*
Y-66070D01*
G01X1163203Y-62737D02*
X1165537D01*
G01X1168553Y-66070D02*
Y-61070D01*
G01Y-63487D02*
X1168970Y-63070D01*
X1169387Y-62820D01*
X1170053Y-62737D01*
X1170553Y-62820D01*
X1171137Y-63153D01*
X1171387Y-63653D01*
Y-66070D01*
G01X1175570Y-62737D02*
Y-66070D01*
G01Y-61403D02*
X1175403Y-61320D01*
Y-61153D01*
X1175570Y-61070D01*
X1175737Y-61153D01*
Y-61320D01*
X1175570Y-61403D01*
G01X1179920Y-65487D02*
X1180337Y-65820D01*
X1180920Y-66070D01*
X1181420D01*
X1181920Y-65903D01*
X1182253Y-65653D01*
X1182420Y-65320D01*
X1182337Y-64820D01*
X1182003Y-64570D01*
X1180503Y-64070D01*
X1180170Y-63487D01*
X1180337Y-63070D01*
X1180670Y-62820D01*
X1181170Y-62737D01*
X1181670Y-62820D01*
X1182170Y-63070D01*
G01X1191203Y-66070D02*
Y-62737D01*
G01Y-63403D02*
X1191620Y-63070D01*
X1192037Y-62820D01*
X1192620Y-62737D01*
X1193037Y-62820D01*
X1193537Y-63070D01*
G01X1196720Y-63820D02*
X1199387D01*
X1199137Y-63237D01*
X1198720Y-62903D01*
X1198137Y-62737D01*
X1197553Y-62820D01*
X1197053Y-63070D01*
X1196720Y-63653D01*
X1196553Y-64153D01*
Y-64653D01*
X1196720Y-65153D01*
X1197137Y-65653D01*
X1197637Y-65987D01*
X1198220Y-66070D01*
X1198803Y-65903D01*
X1199387Y-65403D01*
G01X1205070Y-67737D02*
Y-62737D01*
G01Y-63487D02*
X1204653Y-63070D01*
X1204153Y-62820D01*
X1203570Y-62737D01*
X1203070Y-62820D01*
X1202487Y-63237D01*
X1202153Y-63820D01*
X1202070Y-64403D01*
X1202153Y-64987D01*
X1202487Y-65570D01*
X1203070Y-65987D01*
X1203570Y-66070D01*
X1204153Y-65987D01*
X1204653Y-65737D01*
X1205070Y-65320D01*
G01X1207753Y-62737D02*
Y-65070D01*
X1208087Y-65653D01*
X1208587Y-65987D01*
X1209170Y-66070D01*
X1209753Y-65987D01*
X1210253Y-65653D01*
X1210587Y-65070D01*
G01Y-66070D02*
Y-62737D01*
G01X1213520Y-63820D02*
X1216187D01*
X1215937Y-63237D01*
X1215520Y-62903D01*
X1214937Y-62737D01*
X1214353Y-62820D01*
X1213853Y-63070D01*
X1213520Y-63653D01*
X1213353Y-64153D01*
Y-64653D01*
X1213520Y-65153D01*
X1213937Y-65653D01*
X1214437Y-65987D01*
X1215020Y-66070D01*
X1215603Y-65903D01*
X1216187Y-65403D01*
G01X1219120Y-65487D02*
X1219537Y-65820D01*
X1220120Y-66070D01*
X1220620D01*
X1221120Y-65903D01*
X1221453Y-65653D01*
X1221620Y-65320D01*
X1221537Y-64820D01*
X1221203Y-64570D01*
X1219703Y-64070D01*
X1219370Y-63487D01*
X1219537Y-63070D01*
X1219870Y-62820D01*
X1220370Y-62737D01*
X1220870Y-62820D01*
X1221370Y-63070D01*
G01X1225970Y-61070D02*
Y-66070D01*
G01X1224803Y-62737D02*
X1227137D01*
G01X1231570Y-66237D02*
X1231403Y-66153D01*
Y-65987D01*
X1231570Y-65903D01*
X1231737Y-65987D01*
Y-66153D01*
X1231570Y-66237D01*
G01X722667Y-38250D02*
X723167Y-38667D01*
X723750Y-38917D01*
X724500Y-39000D01*
X725250Y-38833D01*
X725833Y-38500D01*
X726250Y-37917D01*
X726333Y-37250D01*
X726167Y-36583D01*
X725750Y-36167D01*
X725167Y-35833D01*
X724583Y-35750D01*
X724000Y-35833D01*
X723250Y-36167D01*
X723500Y-34000D01*
X725750D01*
G01X730100Y-39167D02*
X729933Y-39083D01*
Y-38917D01*
X730100Y-38833D01*
X730267Y-38917D01*
Y-39083D01*
X730100Y-39167D01*
G01X739633Y-39000D02*
Y-34000D01*
X741717D01*
X742383Y-34250D01*
X742800Y-34583D01*
X742967Y-35250D01*
X742800Y-35917D01*
X742300Y-36333D01*
X741717Y-36583D01*
X739633D01*
G01X741717D02*
X742967Y-39000D01*
G01X745650Y-36750D02*
X748317D01*
X748067Y-36167D01*
X747650Y-35833D01*
X747067Y-35667D01*
X746483Y-35750D01*
X745983Y-36000D01*
X745650Y-36583D01*
X745483Y-37083D01*
Y-37583D01*
X745650Y-38083D01*
X746067Y-38583D01*
X746567Y-38917D01*
X747150Y-39000D01*
X747733Y-38833D01*
X748317Y-38333D01*
G01X750000Y-39000D02*
Y-35667D01*
G01Y-36583D02*
X750250Y-36167D01*
X750667Y-35833D01*
X751250Y-35667D01*
X751833Y-35833D01*
X752250Y-36167D01*
X752500Y-36583D01*
Y-39000D01*
G01Y-36583D02*
X752750Y-36167D01*
X753167Y-35833D01*
X753750Y-35667D01*
X754333Y-35833D01*
X754750Y-36167D01*
X755000Y-36667D01*
Y-39000D01*
G01X759600D02*
Y-35667D01*
G01Y-36250D02*
X759267Y-35917D01*
X758767Y-35750D01*
X758183Y-35667D01*
X757600Y-35833D01*
X757100Y-36167D01*
X756767Y-36667D01*
X756600Y-37333D01*
X756767Y-38000D01*
X757100Y-38500D01*
X757600Y-38833D01*
X758183Y-39000D01*
X758767Y-38917D01*
X759267Y-38667D01*
X759600Y-38333D01*
G01X762533Y-39000D02*
Y-35667D01*
G01Y-36333D02*
X762950Y-36000D01*
X763367Y-35750D01*
X763950Y-35667D01*
X764367Y-35750D01*
X764867Y-36000D01*
G01X767883Y-39000D02*
Y-34000D01*
G01X770550Y-35667D02*
X767883Y-37583D01*
G01X768967Y-36833D02*
X770717Y-39000D01*
G01X773067Y-39167D02*
X776733Y-35500D01*
G01X774900Y-34833D02*
Y-39833D01*
G01X776733Y-39167D02*
X773067Y-35500D01*
G01X772400Y-37333D02*
X777400D01*
G01X713000Y-53000D02*
X1343000D01*
G01X713000Y850500D02*
Y-73000D01*
X1343000D01*
Y782000D01*
X713000D01*
G01X694500Y716000D02*
Y-69500D01*
G01X713000Y-23000D02*
X1343000D01*
G01X713000Y85500D02*
X1343000D01*
G01X713000Y335500D02*
X1343000D01*
G01X721407Y374673D02*
X725073Y378340D01*
G01X723240Y379007D02*
Y374007D01*
G01X725073Y374673D02*
X721407Y378340D01*
G01X720740Y376507D02*
X725740D01*
G01X728423Y373173D02*
X727590Y374007D01*
X727173Y374840D01*
Y378173D01*
X727590Y379007D01*
X728423Y379840D01*
G01X732607Y375590D02*
X733107Y375173D01*
X733690Y374923D01*
X734440Y374840D01*
X735190Y375007D01*
X735773Y375340D01*
X736190Y375923D01*
X736273Y376590D01*
X736107Y377257D01*
X735690Y377673D01*
X735107Y378007D01*
X734523Y378090D01*
X733940Y378007D01*
X733190Y377673D01*
X733440Y379840D01*
X735690D01*
G01X740040Y374673D02*
X739873Y374757D01*
Y374923D01*
X740040Y375007D01*
X740207Y374923D01*
Y374757D01*
X740040Y374673D01*
G01X745640Y374840D02*
Y379840D01*
X744640Y378840D01*
G01Y374840D02*
X746640D01*
G01X751657Y373173D02*
X752490Y374007D01*
X752907Y374840D01*
Y378173D01*
X752490Y379007D01*
X751657Y379840D01*
G01X721107Y408303D02*
X724773Y411970D01*
G01X722940Y412637D02*
Y407637D01*
G01X724773Y408303D02*
X721107Y411970D01*
G01X720440Y410137D02*
X725440D01*
G01X728123Y406803D02*
X727290Y407637D01*
X726873Y408470D01*
Y411803D01*
X727290Y412637D01*
X728123Y413470D01*
G01X732307Y409220D02*
X732807Y408803D01*
X733390Y408553D01*
X734140Y408470D01*
X734890Y408637D01*
X735473Y408970D01*
X735890Y409553D01*
X735973Y410220D01*
X735807Y410887D01*
X735390Y411303D01*
X734807Y411637D01*
X734223Y411720D01*
X733640Y411637D01*
X732890Y411303D01*
X733140Y413470D01*
X735390D01*
G01X739740Y408303D02*
X739573Y408387D01*
Y408553D01*
X739740Y408637D01*
X739907Y408553D01*
Y408387D01*
X739740Y408303D01*
G01X745340Y408470D02*
Y413470D01*
X744340Y412470D01*
G01Y408470D02*
X746340D01*
G01X751357Y406803D02*
X752190Y407637D01*
X752607Y408470D01*
Y411803D01*
X752190Y412637D01*
X751357Y413470D01*
G01X725500Y349500D02*
Y354500D01*
X722417Y350917D01*
X726583D01*
G01X730100Y349333D02*
X729933Y349417D01*
Y349583D01*
X730100Y349667D01*
X730267Y349583D01*
Y349417D01*
X730100Y349333D01*
G01X739800Y349500D02*
Y354500D01*
G01Y352000D02*
X740217Y352500D01*
X740717Y352750D01*
X741217Y352833D01*
X741967Y352667D01*
X742467Y352333D01*
X742800Y351750D01*
Y351083D01*
X742633Y350417D01*
X742300Y349917D01*
X741717Y349583D01*
X741217Y349500D01*
X740717Y349583D01*
X740217Y349833D01*
X739800Y350250D01*
G01X748400Y349500D02*
Y352833D01*
G01Y352250D02*
X748067Y352583D01*
X747567Y352750D01*
X746983Y352833D01*
X746400Y352667D01*
X745900Y352333D01*
X745567Y351833D01*
X745400Y351167D01*
X745567Y350500D01*
X745900Y350000D01*
X746400Y349667D01*
X746983Y349500D01*
X747567Y349583D01*
X748067Y349833D01*
X748400Y350167D01*
G01X753833Y352417D02*
X753250Y352750D01*
X752750Y352833D01*
X752083Y352667D01*
X751583Y352333D01*
X751250Y351750D01*
X751167Y351167D01*
X751250Y350583D01*
X751583Y350083D01*
X752083Y349667D01*
X752750Y349500D01*
X753333Y349667D01*
X753833Y350000D01*
G01X756683Y349500D02*
Y354500D01*
G01X759350Y352833D02*
X756683Y350917D01*
G01X757767Y351667D02*
X759517Y349500D01*
G01X765200Y354500D02*
Y349500D01*
G01Y350250D02*
X764867Y349833D01*
X764367Y349583D01*
X763783Y349500D01*
X763117Y349667D01*
X762617Y350083D01*
X762283Y350583D01*
X762200Y351167D01*
X762283Y351750D01*
X762617Y352250D01*
X763117Y352667D01*
X763783Y352833D01*
X764367Y352750D01*
X764783Y352583D01*
X765200Y352250D01*
G01X768133Y349500D02*
Y352833D01*
G01Y352167D02*
X768550Y352500D01*
X768967Y352750D01*
X769550Y352833D01*
X769967Y352750D01*
X770467Y352500D01*
G01X774900Y352833D02*
Y349500D01*
G01Y354167D02*
X774733Y354250D01*
Y354417D01*
X774900Y354500D01*
X775067Y354417D01*
Y354250D01*
X774900Y354167D01*
G01X780500Y349500D02*
Y354500D01*
G01X786100Y349500D02*
Y354500D01*
G01X798800Y349500D02*
Y352833D01*
G01Y352250D02*
X798467Y352583D01*
X797967Y352750D01*
X797383Y352833D01*
X796800Y352667D01*
X796300Y352333D01*
X795967Y351833D01*
X795800Y351167D01*
X795967Y350500D01*
X796300Y350000D01*
X796800Y349667D01*
X797383Y349500D01*
X797967Y349583D01*
X798467Y349833D01*
X798800Y350167D01*
G01X801483Y349500D02*
Y352833D01*
G01Y352000D02*
X801817Y352417D01*
X802317Y352750D01*
X802983Y352833D01*
X803567Y352750D01*
X804067Y352417D01*
X804317Y351833D01*
Y349500D01*
G01X810000Y354500D02*
Y349500D01*
G01Y350250D02*
X809667Y349833D01*
X809167Y349583D01*
X808583Y349500D01*
X807917Y349667D01*
X807417Y350083D01*
X807083Y350583D01*
X807000Y351167D01*
X807083Y351750D01*
X807417Y352250D01*
X807917Y352667D01*
X808583Y352833D01*
X809167Y352750D01*
X809583Y352583D01*
X810000Y352250D01*
G01X818450Y350083D02*
X818867Y349750D01*
X819450Y349500D01*
X819950D01*
X820450Y349667D01*
X820783Y349917D01*
X820950Y350250D01*
X820867Y350750D01*
X820533Y351000D01*
X819033Y351500D01*
X818700Y352083D01*
X818867Y352500D01*
X819200Y352750D01*
X819700Y352833D01*
X820200Y352750D01*
X820700Y352500D01*
G01X826800Y347833D02*
Y352833D01*
G01Y352083D02*
X826383Y352500D01*
X825883Y352750D01*
X825300Y352833D01*
X824800Y352750D01*
X824217Y352333D01*
X823883Y351750D01*
X823800Y351167D01*
X823883Y350583D01*
X824217Y350000D01*
X824800Y349583D01*
X825300Y349500D01*
X825883Y349583D01*
X826383Y349833D01*
X826800Y350250D01*
G01X829483Y352833D02*
Y350500D01*
X829817Y349917D01*
X830317Y349583D01*
X830900Y349500D01*
X831483Y349583D01*
X831983Y349917D01*
X832317Y350500D01*
G01Y349500D02*
Y352833D01*
G01X838000Y349500D02*
Y352833D01*
G01Y352250D02*
X837667Y352583D01*
X837167Y352750D01*
X836583Y352833D01*
X836000Y352667D01*
X835500Y352333D01*
X835167Y351833D01*
X835000Y351167D01*
X835167Y350500D01*
X835500Y350000D01*
X836000Y349667D01*
X836583Y349500D01*
X837167Y349583D01*
X837667Y349833D01*
X838000Y350167D01*
G01X840933Y349500D02*
Y352833D01*
G01Y352167D02*
X841350Y352500D01*
X841767Y352750D01*
X842350Y352833D01*
X842767Y352750D01*
X843267Y352500D01*
G01X846450Y351750D02*
X849117D01*
X848867Y352333D01*
X848450Y352667D01*
X847867Y352833D01*
X847283Y352750D01*
X846783Y352500D01*
X846450Y351917D01*
X846283Y351417D01*
Y350917D01*
X846450Y350417D01*
X846867Y349917D01*
X847367Y349583D01*
X847950Y349500D01*
X848533Y349667D01*
X849117Y350167D01*
G01X857483Y349500D02*
Y354500D01*
G01Y352083D02*
X857900Y352500D01*
X858317Y352750D01*
X858983Y352833D01*
X859483Y352750D01*
X860067Y352417D01*
X860317Y351917D01*
Y349500D01*
G01X864500D02*
X864000Y349583D01*
X863500Y349917D01*
X863167Y350500D01*
X863000Y351167D01*
X863167Y351833D01*
X863500Y352417D01*
X864000Y352750D01*
X864500Y352833D01*
X865000Y352750D01*
X865500Y352417D01*
X865833Y351833D01*
X865917Y351167D01*
X865833Y350500D01*
X865500Y349917D01*
X865000Y349583D01*
X864500Y349500D01*
G01X870100D02*
Y354500D01*
G01X874450Y351750D02*
X877117D01*
X876867Y352333D01*
X876450Y352667D01*
X875867Y352833D01*
X875283Y352750D01*
X874783Y352500D01*
X874450Y351917D01*
X874283Y351417D01*
Y350917D01*
X874450Y350417D01*
X874867Y349917D01*
X875367Y349583D01*
X875950Y349500D01*
X876533Y349667D01*
X877117Y350167D01*
G01X881300Y349333D02*
X881133Y349417D01*
Y349583D01*
X881300Y349667D01*
X881467Y349583D01*
Y349417D01*
X881300Y349333D01*
G01Y351583D02*
X881133Y351667D01*
Y351833D01*
X881300Y351917D01*
X881467Y351833D01*
Y351667D01*
X881300Y351583D01*
G01X721217Y391740D02*
X723300Y386740D01*
X725383Y391740D01*
G01X728900Y390073D02*
Y386740D01*
G01Y391407D02*
X728733Y391490D01*
Y391657D01*
X728900Y391740D01*
X729067Y391657D01*
Y391490D01*
X728900Y391407D01*
G01X736000Y386740D02*
Y390073D01*
G01Y389490D02*
X735667Y389823D01*
X735167Y389990D01*
X734583Y390073D01*
X734000Y389907D01*
X733500Y389573D01*
X733167Y389073D01*
X733000Y388407D01*
X733167Y387740D01*
X733500Y387240D01*
X734000Y386907D01*
X734583Y386740D01*
X735167Y386823D01*
X735667Y387073D01*
X736000Y387407D01*
G01X744700Y391740D02*
X746700D01*
G01X745700D02*
Y386740D01*
G01X744700D02*
X746700D01*
G01X749883D02*
Y390073D01*
G01Y389240D02*
X750217Y389657D01*
X750717Y389990D01*
X751383Y390073D01*
X751967Y389990D01*
X752467Y389657D01*
X752717Y389073D01*
Y386740D01*
G01X760833D02*
Y391740D01*
X762833D01*
X763500Y391490D01*
X764000Y390907D01*
X764167Y390240D01*
X764000Y389573D01*
X763583Y389073D01*
X762833Y388823D01*
X760833D01*
G01X769600Y386740D02*
Y390073D01*
G01Y389490D02*
X769267Y389823D01*
X768767Y389990D01*
X768183Y390073D01*
X767600Y389907D01*
X767100Y389573D01*
X766767Y389073D01*
X766600Y388407D01*
X766767Y387740D01*
X767100Y387240D01*
X767600Y386907D01*
X768183Y386740D01*
X768767Y386823D01*
X769267Y387073D01*
X769600Y387407D01*
G01X775200Y391740D02*
Y386740D01*
G01Y387490D02*
X774867Y387073D01*
X774367Y386823D01*
X773783Y386740D01*
X773117Y386907D01*
X772617Y387323D01*
X772283Y387823D01*
X772200Y388407D01*
X772283Y388990D01*
X772617Y389490D01*
X773117Y389907D01*
X773783Y390073D01*
X774367Y389990D01*
X774783Y389823D01*
X775200Y389490D01*
G01X778883Y385073D02*
X778050Y385907D01*
X777633Y386740D01*
Y390073D01*
X778050Y390907D01*
X778883Y391740D01*
G01X782817D02*
X784900Y386740D01*
X786983Y391740D01*
G01X789500D02*
X791500D01*
G01X790500D02*
Y386740D01*
G01X789500D02*
X791500D01*
G01X794433D02*
Y391740D01*
X796433D01*
X797100Y391490D01*
X797600Y390907D01*
X797767Y390240D01*
X797600Y389573D01*
X797183Y389073D01*
X796433Y388823D01*
X794433D01*
G01X802117Y385073D02*
X802950Y385907D01*
X803367Y386740D01*
Y390073D01*
X802950Y390907D01*
X802117Y391740D01*
G01X713000Y365500D02*
X1343000D01*
G01X713000Y400500D02*
X1343000D01*
G01X720917Y424500D02*
X723000Y419500D01*
X725083Y424500D01*
G01X728600Y422833D02*
Y419500D01*
G01Y424167D02*
X728433Y424250D01*
Y424417D01*
X728600Y424500D01*
X728767Y424417D01*
Y424250D01*
X728600Y424167D01*
G01X735700Y419500D02*
Y422833D01*
G01Y422250D02*
X735367Y422583D01*
X734867Y422750D01*
X734283Y422833D01*
X733700Y422667D01*
X733200Y422333D01*
X732867Y421833D01*
X732700Y421167D01*
X732867Y420500D01*
X733200Y420000D01*
X733700Y419667D01*
X734283Y419500D01*
X734867Y419583D01*
X735367Y419833D01*
X735700Y420167D01*
G01X745400Y419500D02*
X744733Y419583D01*
X744150Y419917D01*
X743650Y420417D01*
X743317Y421000D01*
X743150Y421667D01*
Y422333D01*
X743317Y423000D01*
X743650Y423583D01*
X744150Y424083D01*
X744733Y424417D01*
X745400Y424500D01*
X746067Y424417D01*
X746650Y424083D01*
X747150Y423583D01*
X747483Y423000D01*
X747650Y422333D01*
Y421667D01*
X747483Y421000D01*
X747150Y420417D01*
X746650Y419917D01*
X746067Y419583D01*
X745400Y419500D01*
G01X749583D02*
Y422833D01*
G01Y422000D02*
X749917Y422417D01*
X750417Y422750D01*
X751083Y422833D01*
X751667Y422750D01*
X752167Y422417D01*
X752417Y421833D01*
Y419500D01*
G01X760533D02*
Y424500D01*
X762533D01*
X763200Y424250D01*
X763700Y423667D01*
X763867Y423000D01*
X763700Y422333D01*
X763283Y421833D01*
X762533Y421583D01*
X760533D01*
G01X769300Y419500D02*
Y422833D01*
G01Y422250D02*
X768967Y422583D01*
X768467Y422750D01*
X767883Y422833D01*
X767300Y422667D01*
X766800Y422333D01*
X766467Y421833D01*
X766300Y421167D01*
X766467Y420500D01*
X766800Y420000D01*
X767300Y419667D01*
X767883Y419500D01*
X768467Y419583D01*
X768967Y419833D01*
X769300Y420167D01*
G01X774900Y424500D02*
Y419500D01*
G01Y420250D02*
X774567Y419833D01*
X774067Y419583D01*
X773483Y419500D01*
X772817Y419667D01*
X772317Y420083D01*
X771983Y420583D01*
X771900Y421167D01*
X771983Y421750D01*
X772317Y422250D01*
X772817Y422667D01*
X773483Y422833D01*
X774067Y422750D01*
X774483Y422583D01*
X774900Y422250D01*
G01X778583Y417833D02*
X777750Y418667D01*
X777333Y419500D01*
Y422833D01*
X777750Y423667D01*
X778583Y424500D01*
G01X782517D02*
X784600Y419500D01*
X786683Y424500D01*
G01X790200Y419500D02*
X789533Y419583D01*
X788950Y419917D01*
X788450Y420417D01*
X788117Y421000D01*
X787950Y421667D01*
Y422333D01*
X788117Y423000D01*
X788450Y423583D01*
X788950Y424083D01*
X789533Y424417D01*
X790200Y424500D01*
X790867Y424417D01*
X791450Y424083D01*
X791950Y423583D01*
X792283Y423000D01*
X792450Y422333D01*
Y421667D01*
X792283Y421000D01*
X791950Y420417D01*
X791450Y419917D01*
X790867Y419583D01*
X790200Y419500D01*
G01X794133D02*
Y424500D01*
X796133D01*
X796800Y424250D01*
X797300Y423667D01*
X797467Y423000D01*
X797300Y422333D01*
X796883Y421833D01*
X796133Y421583D01*
X794133D01*
G01X801817Y417833D02*
X802650Y418667D01*
X803067Y419500D01*
Y422833D01*
X802650Y423667D01*
X801817Y424500D01*
G01X723667Y443167D02*
X724000Y443417D01*
X724250Y443833D01*
X724417Y444417D01*
X724250Y444917D01*
X723917Y445250D01*
X723333Y445500D01*
X721083D01*
Y440500D01*
X723833D01*
X724417Y440833D01*
X724750Y441333D01*
X724917Y441917D01*
X724750Y442500D01*
X724250Y443000D01*
X723667Y443167D01*
X721083D01*
G01X727183Y443833D02*
Y441500D01*
X727517Y440917D01*
X728017Y440583D01*
X728600Y440500D01*
X729183Y440583D01*
X729683Y440917D01*
X730017Y441500D01*
G01Y440500D02*
Y443833D01*
G01X733033Y440500D02*
Y443833D01*
G01Y443167D02*
X733450Y443500D01*
X733867Y443750D01*
X734450Y443833D01*
X734867Y443750D01*
X735367Y443500D01*
G01X739800Y443833D02*
Y440500D01*
G01Y445167D02*
X739633Y445250D01*
Y445417D01*
X739800Y445500D01*
X739967Y445417D01*
Y445250D01*
X739800Y445167D01*
G01X744150Y442750D02*
X746817D01*
X746567Y443333D01*
X746150Y443667D01*
X745567Y443833D01*
X744983Y443750D01*
X744483Y443500D01*
X744150Y442917D01*
X743983Y442417D01*
Y441917D01*
X744150Y441417D01*
X744567Y440917D01*
X745067Y440583D01*
X745650Y440500D01*
X746233Y440667D01*
X746817Y441167D01*
G01X752500Y445500D02*
Y440500D01*
G01Y441250D02*
X752167Y440833D01*
X751667Y440583D01*
X751083Y440500D01*
X750417Y440667D01*
X749917Y441083D01*
X749583Y441583D01*
X749500Y442167D01*
X749583Y442750D01*
X749917Y443250D01*
X750417Y443667D01*
X751083Y443833D01*
X751667Y443750D01*
X752083Y443583D01*
X752500Y443250D01*
G01X760783Y440500D02*
Y445500D01*
G01Y443083D02*
X761200Y443500D01*
X761617Y443750D01*
X762283Y443833D01*
X762783Y443750D01*
X763367Y443417D01*
X763617Y442917D01*
Y440500D01*
G01X767800D02*
X767300Y440583D01*
X766800Y440917D01*
X766467Y441500D01*
X766300Y442167D01*
X766467Y442833D01*
X766800Y443417D01*
X767300Y443750D01*
X767800Y443833D01*
X768300Y443750D01*
X768800Y443417D01*
X769133Y442833D01*
X769217Y442167D01*
X769133Y441500D01*
X768800Y440917D01*
X768300Y440583D01*
X767800Y440500D01*
G01X773400D02*
Y445500D01*
G01X777750Y442750D02*
X780417D01*
X780167Y443333D01*
X779750Y443667D01*
X779167Y443833D01*
X778583Y443750D01*
X778083Y443500D01*
X777750Y442917D01*
X777583Y442417D01*
Y441917D01*
X777750Y441417D01*
X778167Y440917D01*
X778667Y440583D01*
X779250Y440500D01*
X779833Y440667D01*
X780417Y441167D01*
G01X721417Y461500D02*
Y466500D01*
X724583D01*
G01X723417Y464083D02*
X721417D01*
G01X727183Y464833D02*
Y462500D01*
X727517Y461917D01*
X728017Y461583D01*
X728600Y461500D01*
X729183Y461583D01*
X729683Y461917D01*
X730017Y462500D01*
G01Y461500D02*
Y464833D01*
G01X734200Y461500D02*
Y466500D01*
G01X739800Y461500D02*
Y466500D01*
G01X749500Y459833D02*
Y464833D01*
G01Y464083D02*
X749917Y464500D01*
X750333Y464750D01*
X751000Y464833D01*
X751583Y464750D01*
X752167Y464333D01*
X752417Y463750D01*
X752500Y463167D01*
X752417Y462583D01*
X752167Y462000D01*
X751667Y461667D01*
X751000Y461500D01*
X750417Y461583D01*
X749833Y461833D01*
X749500Y462167D01*
G01X756600Y461500D02*
Y466500D01*
G01X760783Y464833D02*
Y462500D01*
X761117Y461917D01*
X761617Y461583D01*
X762200Y461500D01*
X762783Y461583D01*
X763283Y461917D01*
X763617Y462500D01*
G01Y461500D02*
Y464833D01*
G01X766633Y460250D02*
X767217Y459917D01*
X767883Y459833D01*
X768467Y459917D01*
X768967Y460333D01*
X769300Y460917D01*
Y464833D01*
G01Y464167D02*
X768967Y464500D01*
X768467Y464750D01*
X767883Y464833D01*
X767217Y464667D01*
X766800Y464333D01*
X766467Y463750D01*
X766300Y463167D01*
X766383Y462667D01*
X766717Y462083D01*
X767217Y461667D01*
X767883Y461500D01*
X768383Y461583D01*
X768967Y461917D01*
X769300Y462250D01*
G01X772233Y460250D02*
X772817Y459917D01*
X773483Y459833D01*
X774067Y459917D01*
X774567Y460333D01*
X774900Y460917D01*
Y464833D01*
G01Y464167D02*
X774567Y464500D01*
X774067Y464750D01*
X773483Y464833D01*
X772817Y464667D01*
X772400Y464333D01*
X772067Y463750D01*
X771900Y463167D01*
X771983Y462667D01*
X772317Y462083D01*
X772817Y461667D01*
X773483Y461500D01*
X773983Y461583D01*
X774567Y461917D01*
X774900Y462250D01*
G01X779000Y464833D02*
Y461500D01*
G01Y466167D02*
X778833Y466250D01*
Y466417D01*
X779000Y466500D01*
X779167Y466417D01*
Y466250D01*
X779000Y466167D01*
G01X783183Y461500D02*
Y464833D01*
G01Y464000D02*
X783517Y464417D01*
X784017Y464750D01*
X784683Y464833D01*
X785267Y464750D01*
X785767Y464417D01*
X786017Y463833D01*
Y461500D01*
G01X789033Y460250D02*
X789617Y459917D01*
X790283Y459833D01*
X790867Y459917D01*
X791367Y460333D01*
X791700Y460917D01*
Y464833D01*
G01Y464167D02*
X791367Y464500D01*
X790867Y464750D01*
X790283Y464833D01*
X789617Y464667D01*
X789200Y464333D01*
X788867Y463750D01*
X788700Y463167D01*
X788783Y462667D01*
X789117Y462083D01*
X789617Y461667D01*
X790283Y461500D01*
X790783Y461583D01*
X791367Y461917D01*
X791700Y462250D01*
G01X713000Y435500D02*
X1343000D01*
G01X713000Y450500D02*
X1343000D01*
G01X713000Y477500D02*
X1343000D01*
G01X721250Y530000D02*
Y535000D01*
G01X724750D02*
Y530000D01*
G01Y532500D02*
X721250D01*
G01X730100Y530000D02*
Y533333D01*
G01Y532750D02*
X729767Y533083D01*
X729267Y533250D01*
X728683Y533333D01*
X728100Y533167D01*
X727600Y532833D01*
X727267Y532333D01*
X727100Y531667D01*
X727267Y531000D01*
X727600Y530500D01*
X728100Y530167D01*
X728683Y530000D01*
X729267Y530083D01*
X729767Y530333D01*
X730100Y530667D01*
G01X734200Y530000D02*
Y535000D01*
G01X739300Y530000D02*
Y534250D01*
X739467Y534667D01*
X739800Y534917D01*
X740300Y535000D01*
X740800Y534833D01*
X741050Y534417D01*
G01X740050Y533000D02*
X738383D01*
G01X749333Y530000D02*
Y535000D01*
X751333D01*
X752000Y534750D01*
X752500Y534167D01*
X752667Y533500D01*
X752500Y532833D01*
X752083Y532333D01*
X751333Y532083D01*
X749333D01*
G01X756600Y530000D02*
Y535000D01*
G01X760783Y533333D02*
Y531000D01*
X761117Y530417D01*
X761617Y530083D01*
X762200Y530000D01*
X762783Y530083D01*
X763283Y530417D01*
X763617Y531000D01*
G01Y530000D02*
Y533333D01*
G01X766633Y528750D02*
X767217Y528417D01*
X767883Y528333D01*
X768467Y528417D01*
X768967Y528833D01*
X769300Y529417D01*
Y533333D01*
G01Y532667D02*
X768967Y533000D01*
X768467Y533250D01*
X767883Y533333D01*
X767217Y533167D01*
X766800Y532833D01*
X766467Y532250D01*
X766300Y531667D01*
X766383Y531167D01*
X766717Y530583D01*
X767217Y530167D01*
X767883Y530000D01*
X768383Y530083D01*
X768967Y530417D01*
X769300Y530750D01*
G01X772233Y528750D02*
X772817Y528417D01*
X773483Y528333D01*
X774067Y528417D01*
X774567Y528833D01*
X774900Y529417D01*
Y533333D01*
G01Y532667D02*
X774567Y533000D01*
X774067Y533250D01*
X773483Y533333D01*
X772817Y533167D01*
X772400Y532833D01*
X772067Y532250D01*
X771900Y531667D01*
X771983Y531167D01*
X772317Y530583D01*
X772817Y530167D01*
X773483Y530000D01*
X773983Y530083D01*
X774567Y530417D01*
X774900Y530750D01*
G01X779000Y533333D02*
Y530000D01*
G01Y534667D02*
X778833Y534750D01*
Y534917D01*
X779000Y535000D01*
X779167Y534917D01*
Y534750D01*
X779000Y534667D01*
G01X783183Y530000D02*
Y533333D01*
G01Y532500D02*
X783517Y532917D01*
X784017Y533250D01*
X784683Y533333D01*
X785267Y533250D01*
X785767Y532917D01*
X786017Y532333D01*
Y530000D01*
G01X789033Y528750D02*
X789617Y528417D01*
X790283Y528333D01*
X790867Y528417D01*
X791367Y528833D01*
X791700Y529417D01*
Y533333D01*
G01Y532667D02*
X791367Y533000D01*
X790867Y533250D01*
X790283Y533333D01*
X789617Y533167D01*
X789200Y532833D01*
X788867Y532250D01*
X788700Y531667D01*
X788783Y531167D01*
X789117Y530583D01*
X789617Y530167D01*
X790283Y530000D01*
X790783Y530083D01*
X791367Y530417D01*
X791700Y530750D01*
G01X722833Y589000D02*
Y594000D01*
X724833D01*
X725500Y593750D01*
X726000Y593167D01*
X726167Y592500D01*
X726000Y591833D01*
X725583Y591333D01*
X724833Y591083D01*
X722833D01*
G01X730100Y589000D02*
Y594000D01*
G01X734283Y592333D02*
Y590000D01*
X734617Y589417D01*
X735117Y589083D01*
X735700Y589000D01*
X736283Y589083D01*
X736783Y589417D01*
X737117Y590000D01*
G01Y589000D02*
Y592333D01*
G01X740133Y587750D02*
X740717Y587417D01*
X741383Y587333D01*
X741967Y587417D01*
X742467Y587833D01*
X742800Y588417D01*
Y592333D01*
G01Y591667D02*
X742467Y592000D01*
X741967Y592250D01*
X741383Y592333D01*
X740717Y592167D01*
X740300Y591833D01*
X739967Y591250D01*
X739800Y590667D01*
X739883Y590167D01*
X740217Y589583D01*
X740717Y589167D01*
X741383Y589000D01*
X741883Y589083D01*
X742467Y589417D01*
X742800Y589750D01*
G01X745733Y587750D02*
X746317Y587417D01*
X746983Y587333D01*
X747567Y587417D01*
X748067Y587833D01*
X748400Y588417D01*
Y592333D01*
G01Y591667D02*
X748067Y592000D01*
X747567Y592250D01*
X746983Y592333D01*
X746317Y592167D01*
X745900Y591833D01*
X745567Y591250D01*
X745400Y590667D01*
X745483Y590167D01*
X745817Y589583D01*
X746317Y589167D01*
X746983Y589000D01*
X747483Y589083D01*
X748067Y589417D01*
X748400Y589750D01*
G01X752500Y592333D02*
Y589000D01*
G01Y593667D02*
X752333Y593750D01*
Y593917D01*
X752500Y594000D01*
X752667Y593917D01*
Y593750D01*
X752500Y593667D01*
G01X756683Y589000D02*
Y592333D01*
G01Y591500D02*
X757017Y591917D01*
X757517Y592250D01*
X758183Y592333D01*
X758767Y592250D01*
X759267Y591917D01*
X759517Y591333D01*
Y589000D01*
G01X762533Y587750D02*
X763117Y587417D01*
X763783Y587333D01*
X764367Y587417D01*
X764867Y587833D01*
X765200Y588417D01*
Y592333D01*
G01Y591667D02*
X764867Y592000D01*
X764367Y592250D01*
X763783Y592333D01*
X763117Y592167D01*
X762700Y591833D01*
X762367Y591250D01*
X762200Y590667D01*
X762283Y590167D01*
X762617Y589583D01*
X763117Y589167D01*
X763783Y589000D01*
X764283Y589083D01*
X764867Y589417D01*
X765200Y589750D01*
G01X776400Y594000D02*
Y589000D01*
G01Y589750D02*
X776067Y589333D01*
X775567Y589083D01*
X774983Y589000D01*
X774317Y589167D01*
X773817Y589583D01*
X773483Y590083D01*
X773400Y590667D01*
X773483Y591250D01*
X773817Y591750D01*
X774317Y592167D01*
X774983Y592333D01*
X775567Y592250D01*
X775983Y592083D01*
X776400Y591750D01*
G01X779250Y591250D02*
X781917D01*
X781667Y591833D01*
X781250Y592167D01*
X780667Y592333D01*
X780083Y592250D01*
X779583Y592000D01*
X779250Y591417D01*
X779083Y590917D01*
Y590417D01*
X779250Y589917D01*
X779667Y589417D01*
X780167Y589083D01*
X780750Y589000D01*
X781333Y589167D01*
X781917Y589667D01*
G01X785600Y589000D02*
Y593250D01*
X785767Y593667D01*
X786100Y593917D01*
X786600Y594000D01*
X787100Y593833D01*
X787350Y593417D01*
G01X786350Y592000D02*
X784683D01*
G01X791700Y592333D02*
Y589000D01*
G01Y593667D02*
X791533Y593750D01*
Y593917D01*
X791700Y594000D01*
X791867Y593917D01*
Y593750D01*
X791700Y593667D01*
G01X795883Y589000D02*
Y592333D01*
G01Y591500D02*
X796217Y591917D01*
X796717Y592250D01*
X797383Y592333D01*
X797967Y592250D01*
X798467Y591917D01*
X798717Y591333D01*
Y589000D01*
G01X801650Y591250D02*
X804317D01*
X804067Y591833D01*
X803650Y592167D01*
X803067Y592333D01*
X802483Y592250D01*
X801983Y592000D01*
X801650Y591417D01*
X801483Y590917D01*
Y590417D01*
X801650Y589917D01*
X802067Y589417D01*
X802567Y589083D01*
X803150Y589000D01*
X803733Y589167D01*
X804317Y589667D01*
G01X713000Y579500D02*
X1343000D01*
G01X713000Y604500D02*
X1343000D01*
G01X722667Y765000D02*
X723167Y764417D01*
X723833Y764083D01*
X724583Y764000D01*
X725250Y764083D01*
X725917Y764500D01*
X726333Y765000D01*
X726417Y765500D01*
X726250Y766083D01*
X725667Y766500D01*
X725083Y766667D01*
X724333D01*
G01X725083D02*
X725583Y766917D01*
X726000Y767333D01*
X726167Y767833D01*
X726000Y768333D01*
X725583Y768750D01*
X724833Y769000D01*
X724083Y768917D01*
X723333Y768583D01*
G01X730100Y763833D02*
X729933Y763917D01*
Y764083D01*
X730100Y764167D01*
X730267Y764083D01*
Y763917D01*
X730100Y763833D01*
G01X739633Y764000D02*
Y769000D01*
X741633D01*
X742300Y768750D01*
X742800Y768167D01*
X742967Y767500D01*
X742800Y766833D01*
X742383Y766333D01*
X741633Y766083D01*
X739633D01*
G01X746900Y764000D02*
Y769000D01*
G01X751083Y767333D02*
Y765000D01*
X751417Y764417D01*
X751917Y764083D01*
X752500Y764000D01*
X753083Y764083D01*
X753583Y764417D01*
X753917Y765000D01*
G01Y764000D02*
Y767333D01*
G01X756933Y762750D02*
X757517Y762417D01*
X758183Y762333D01*
X758767Y762417D01*
X759267Y762833D01*
X759600Y763417D01*
Y767333D01*
G01Y766667D02*
X759267Y767000D01*
X758767Y767250D01*
X758183Y767333D01*
X757517Y767167D01*
X757100Y766833D01*
X756767Y766250D01*
X756600Y765667D01*
X756683Y765167D01*
X757017Y764583D01*
X757517Y764167D01*
X758183Y764000D01*
X758683Y764083D01*
X759267Y764417D01*
X759600Y764750D01*
G01X767800Y767333D02*
X769300Y764000D01*
X770800Y767333D01*
G01X774900D02*
Y764000D01*
G01Y768667D02*
X774733Y768750D01*
Y768917D01*
X774900Y769000D01*
X775067Y768917D01*
Y768750D01*
X774900Y768667D01*
G01X782000Y764000D02*
Y767333D01*
G01Y766750D02*
X781667Y767083D01*
X781167Y767250D01*
X780583Y767333D01*
X780000Y767167D01*
X779500Y766833D01*
X779167Y766333D01*
X779000Y765667D01*
X779167Y765000D01*
X779500Y764500D01*
X780000Y764167D01*
X780583Y764000D01*
X781167Y764083D01*
X781667Y764333D01*
X782000Y764667D01*
G01X790200Y763833D02*
X793200Y769000D01*
G01X795217D02*
X797300Y764000D01*
X799383Y769000D01*
G01X802900Y764000D02*
X802233Y764083D01*
X801650Y764417D01*
X801150Y764917D01*
X800817Y765500D01*
X800650Y766167D01*
Y766833D01*
X800817Y767500D01*
X801150Y768083D01*
X801650Y768583D01*
X802233Y768917D01*
X802900Y769000D01*
X803567Y768917D01*
X804150Y768583D01*
X804650Y768083D01*
X804983Y767500D01*
X805150Y766833D01*
Y766167D01*
X804983Y765500D01*
X804650Y764917D01*
X804150Y764417D01*
X803567Y764083D01*
X802900Y764000D01*
G01X806833D02*
Y769000D01*
X808833D01*
X809500Y768750D01*
X810000Y768167D01*
X810167Y767500D01*
X810000Y766833D01*
X809583Y766333D01*
X808833Y766083D01*
X806833D01*
G01X812600Y763833D02*
X815600Y769000D01*
G01X817617D02*
X819700Y764000D01*
X821783Y769000D01*
G01X824300D02*
X826300D01*
G01X825300D02*
Y764000D01*
G01X824300D02*
X826300D01*
G01X829233D02*
Y769000D01*
X831233D01*
X831900Y768750D01*
X832400Y768167D01*
X832567Y767500D01*
X832400Y766833D01*
X831983Y766333D01*
X831233Y766083D01*
X829233D01*
G01X836500Y763833D02*
X836333Y763917D01*
Y764083D01*
X836500Y764167D01*
X836667Y764083D01*
Y763917D01*
X836500Y763833D01*
G01Y766083D02*
X836333Y766167D01*
Y766333D01*
X836500Y766417D01*
X836667Y766333D01*
Y766167D01*
X836500Y766083D01*
G01X713000Y752000D02*
X1344500D01*
G01X724813Y813000D02*
Y818000D01*
X726897D01*
X727563Y817750D01*
X727980Y817417D01*
X728147Y816750D01*
X727980Y816083D01*
X727480Y815667D01*
X726897Y815417D01*
X724813D01*
G01X726897D02*
X728147Y813000D01*
G01X732080D02*
X731580Y813083D01*
X731080Y813417D01*
X730747Y814000D01*
X730580Y814667D01*
X730747Y815333D01*
X731080Y815917D01*
X731580Y816250D01*
X732080Y816333D01*
X732580Y816250D01*
X733080Y815917D01*
X733413Y815333D01*
X733497Y814667D01*
X733413Y814000D01*
X733080Y813417D01*
X732580Y813083D01*
X732080Y813000D01*
G01X736263Y816333D02*
Y814000D01*
X736597Y813417D01*
X737097Y813083D01*
X737680Y813000D01*
X738263Y813083D01*
X738763Y813417D01*
X739097Y814000D01*
G01Y813000D02*
Y816333D01*
G01X743280Y818000D02*
Y813000D01*
G01X742113Y816333D02*
X744447D01*
G01X748880D02*
Y813000D01*
G01Y817667D02*
X748713Y817750D01*
Y817917D01*
X748880Y818000D01*
X749047Y817917D01*
Y817750D01*
X748880Y817667D01*
G01X753063Y813000D02*
Y816333D01*
G01Y815500D02*
X753397Y815917D01*
X753897Y816250D01*
X754563Y816333D01*
X755147Y816250D01*
X755647Y815917D01*
X755897Y815333D01*
Y813000D01*
G01X758913Y811750D02*
X759497Y811417D01*
X760163Y811333D01*
X760747Y811417D01*
X761247Y811833D01*
X761580Y812417D01*
Y816333D01*
G01Y815667D02*
X761247Y816000D01*
X760747Y816250D01*
X760163Y816333D01*
X759497Y816167D01*
X759080Y815833D01*
X758747Y815250D01*
X758580Y814667D01*
X758663Y814167D01*
X758997Y813583D01*
X759497Y813167D01*
X760163Y813000D01*
X760663Y813083D01*
X761247Y813417D01*
X761580Y813750D01*
G01X712980Y850500D02*
X1343000D01*
G01X802167Y-15500D02*
Y-10500D01*
X803833D01*
X804500Y-10750D01*
X805000Y-11083D01*
X805417Y-11583D01*
X805750Y-12167D01*
X805833Y-13000D01*
X805750Y-13833D01*
X805417Y-14417D01*
X805000Y-14917D01*
X804500Y-15250D01*
X803833Y-15500D01*
X802167D01*
G01X809600D02*
Y-10500D01*
X808600Y-11500D01*
G01Y-15500D02*
X810600D01*
G01X813617Y-13417D02*
X814200Y-12833D01*
X814700Y-12500D01*
X815367Y-12333D01*
X815950Y-12500D01*
X816367Y-12833D01*
X816700Y-13333D01*
X816783Y-13917D01*
X816700Y-14417D01*
X816367Y-14917D01*
X815867Y-15333D01*
X815283Y-15500D01*
X814617Y-15333D01*
X814033Y-14833D01*
X813700Y-14083D01*
X813617Y-13250D01*
X813783Y-12167D01*
X814033Y-11583D01*
X814450Y-11000D01*
X815033Y-10583D01*
X815617Y-10500D01*
X816200Y-10667D01*
X816617Y-11083D01*
G01X777583Y104700D02*
Y99700D01*
X780917D01*
G01X783600Y103033D02*
X786100Y99700D01*
G01Y103033D02*
X783600Y99700D01*
G01X790450Y99533D02*
X790283Y99617D01*
Y99783D01*
X790450Y99867D01*
X790617Y99783D01*
Y99617D01*
X790450Y99533D01*
G01Y101783D02*
X790283Y101867D01*
Y102033D01*
X790450Y102117D01*
X790617Y102033D01*
Y101867D01*
X790450Y101783D01*
G01X799150Y99700D02*
Y103033D01*
G01Y102117D02*
X799400Y102533D01*
X799817Y102867D01*
X800400Y103033D01*
X800983Y102867D01*
X801400Y102533D01*
X801650Y102117D01*
Y99700D01*
G01Y102117D02*
X801900Y102533D01*
X802317Y102867D01*
X802900Y103033D01*
X803483Y102867D01*
X803900Y102533D01*
X804150Y102033D01*
Y99700D01*
G01X805833Y103033D02*
Y100700D01*
X806167Y100117D01*
X806667Y99783D01*
X807250Y99700D01*
X807833Y99783D01*
X808333Y100117D01*
X808667Y100700D01*
G01Y99700D02*
Y103033D01*
G01X811600Y100283D02*
X812017Y99950D01*
X812600Y99700D01*
X813100D01*
X813600Y99867D01*
X813933Y100117D01*
X814100Y100450D01*
X814017Y100950D01*
X813683Y101200D01*
X812183Y101700D01*
X811850Y102283D01*
X812017Y102700D01*
X812350Y102950D01*
X812850Y103033D01*
X813350Y102950D01*
X813850Y102700D01*
G01X818450Y104700D02*
Y99700D01*
G01X817283Y103033D02*
X819617D01*
G01X828150Y99700D02*
Y104700D01*
G01Y102200D02*
X828567Y102700D01*
X829067Y102950D01*
X829567Y103033D01*
X830317Y102867D01*
X830817Y102533D01*
X831150Y101950D01*
Y101283D01*
X830983Y100617D01*
X830650Y100117D01*
X830067Y99783D01*
X829567Y99700D01*
X829067Y99783D01*
X828567Y100033D01*
X828150Y100450D01*
G01X834000Y101950D02*
X836667D01*
X836417Y102533D01*
X836000Y102867D01*
X835417Y103033D01*
X834833Y102950D01*
X834333Y102700D01*
X834000Y102117D01*
X833833Y101617D01*
Y101117D01*
X834000Y100617D01*
X834417Y100117D01*
X834917Y99783D01*
X835500Y99700D01*
X836083Y99867D01*
X836667Y100367D01*
G01X844950Y99700D02*
Y104700D01*
G01Y102200D02*
X845367Y102700D01*
X845867Y102950D01*
X846367Y103033D01*
X847117Y102867D01*
X847617Y102533D01*
X847950Y101950D01*
Y101283D01*
X847783Y100617D01*
X847450Y100117D01*
X846867Y99783D01*
X846367Y99700D01*
X845867Y99783D01*
X845367Y100033D01*
X844950Y100450D01*
G01X850883Y99700D02*
Y103033D01*
G01Y102367D02*
X851300Y102700D01*
X851717Y102950D01*
X852300Y103033D01*
X852717Y102950D01*
X853217Y102700D01*
G01X857650Y99700D02*
X857150Y99783D01*
X856650Y100117D01*
X856317Y100700D01*
X856150Y101367D01*
X856317Y102033D01*
X856650Y102617D01*
X857150Y102950D01*
X857650Y103033D01*
X858150Y102950D01*
X858650Y102617D01*
X858983Y102033D01*
X859067Y101367D01*
X858983Y100700D01*
X858650Y100117D01*
X858150Y99783D01*
X857650Y99700D01*
G01X861833D02*
Y104700D01*
G01X864500Y103033D02*
X861833Y101117D01*
G01X862917Y101867D02*
X864667Y99700D01*
G01X867600Y101950D02*
X870267D01*
X870017Y102533D01*
X869600Y102867D01*
X869017Y103033D01*
X868433Y102950D01*
X867933Y102700D01*
X867600Y102117D01*
X867433Y101617D01*
Y101117D01*
X867600Y100617D01*
X868017Y100117D01*
X868517Y99783D01*
X869100Y99700D01*
X869683Y99867D01*
X870267Y100367D01*
G01X873033Y99700D02*
Y103033D01*
G01Y102200D02*
X873367Y102617D01*
X873867Y102950D01*
X874533Y103033D01*
X875117Y102950D01*
X875617Y102617D01*
X875867Y102033D01*
Y99700D01*
G01X885650D02*
Y104700D01*
G01X892750Y99700D02*
Y103033D01*
G01Y102450D02*
X892417Y102783D01*
X891917Y102950D01*
X891333Y103033D01*
X890750Y102867D01*
X890250Y102533D01*
X889917Y102033D01*
X889750Y101367D01*
X889917Y100700D01*
X890250Y100200D01*
X890750Y99867D01*
X891333Y99700D01*
X891917Y99783D01*
X892417Y100033D01*
X892750Y100367D01*
G01X895100Y98200D02*
X895600Y98033D01*
X896267Y98200D01*
X896683Y98533D01*
X897017Y98950D01*
X897517Y100283D01*
X898600Y103033D01*
G01X895933D02*
X897517Y100283D01*
G01X901200Y101950D02*
X903867D01*
X903617Y102533D01*
X903200Y102867D01*
X902617Y103033D01*
X902033Y102950D01*
X901533Y102700D01*
X901200Y102117D01*
X901033Y101617D01*
Y101117D01*
X901200Y100617D01*
X901617Y100117D01*
X902117Y99783D01*
X902700Y99700D01*
X903283Y99867D01*
X903867Y100367D01*
G01X906883Y99700D02*
Y103033D01*
G01Y102367D02*
X907300Y102700D01*
X907717Y102950D01*
X908300Y103033D01*
X908717Y102950D01*
X909217Y102700D01*
G01X776983Y116310D02*
Y111310D01*
X780317D01*
G01X782833D02*
Y114643D01*
G01Y113810D02*
X783167Y114227D01*
X783667Y114560D01*
X784333Y114643D01*
X784917Y114560D01*
X785417Y114227D01*
X785667Y113643D01*
Y111310D01*
G01X789850Y111143D02*
X789683Y111227D01*
Y111393D01*
X789850Y111477D01*
X790017Y111393D01*
Y111227D01*
X789850Y111143D01*
G01Y113393D02*
X789683Y113477D01*
Y113643D01*
X789850Y113727D01*
X790017Y113643D01*
Y113477D01*
X789850Y113393D01*
G01X802383Y114227D02*
X801800Y114560D01*
X801300Y114643D01*
X800633Y114477D01*
X800133Y114143D01*
X799800Y113560D01*
X799717Y112977D01*
X799800Y112393D01*
X800133Y111893D01*
X800633Y111477D01*
X801300Y111310D01*
X801883Y111477D01*
X802383Y111810D01*
G01X808150Y111310D02*
Y114643D01*
G01Y114060D02*
X807817Y114393D01*
X807317Y114560D01*
X806733Y114643D01*
X806150Y114477D01*
X805650Y114143D01*
X805317Y113643D01*
X805150Y112977D01*
X805317Y112310D01*
X805650Y111810D01*
X806150Y111477D01*
X806733Y111310D01*
X807317Y111393D01*
X807817Y111643D01*
X808150Y111977D01*
G01X810833Y111310D02*
Y114643D01*
G01Y113810D02*
X811167Y114227D01*
X811667Y114560D01*
X812333Y114643D01*
X812917Y114560D01*
X813417Y114227D01*
X813667Y113643D01*
Y111310D01*
G01X817850Y114643D02*
X818683Y115685D01*
Y116310D01*
X818058D01*
Y115685D01*
X818683D01*
G01X823450Y116310D02*
Y111310D01*
G01X822283Y114643D02*
X824617D01*
G01X833150Y111310D02*
Y116310D01*
G01Y113810D02*
X833567Y114310D01*
X834067Y114560D01*
X834567Y114643D01*
X835317Y114477D01*
X835817Y114143D01*
X836150Y113560D01*
Y112893D01*
X835983Y112227D01*
X835650Y111727D01*
X835067Y111393D01*
X834567Y111310D01*
X834067Y111393D01*
X833567Y111643D01*
X833150Y112060D01*
G01X839000Y113560D02*
X841667D01*
X841417Y114143D01*
X841000Y114477D01*
X840417Y114643D01*
X839833Y114560D01*
X839333Y114310D01*
X839000Y113727D01*
X838833Y113227D01*
Y112727D01*
X839000Y112227D01*
X839417Y111727D01*
X839917Y111393D01*
X840500Y111310D01*
X841083Y111477D01*
X841667Y111977D01*
G01X849950Y111310D02*
Y116310D01*
G01Y113810D02*
X850367Y114310D01*
X850867Y114560D01*
X851367Y114643D01*
X852117Y114477D01*
X852617Y114143D01*
X852950Y113560D01*
Y112893D01*
X852783Y112227D01*
X852450Y111727D01*
X851867Y111393D01*
X851367Y111310D01*
X850867Y111393D01*
X850367Y111643D01*
X849950Y112060D01*
G01X855883Y111310D02*
Y114643D01*
G01Y113977D02*
X856300Y114310D01*
X856717Y114560D01*
X857300Y114643D01*
X857717Y114560D01*
X858217Y114310D01*
G01X862650Y111310D02*
X862150Y111393D01*
X861650Y111727D01*
X861317Y112310D01*
X861150Y112977D01*
X861317Y113643D01*
X861650Y114227D01*
X862150Y114560D01*
X862650Y114643D01*
X863150Y114560D01*
X863650Y114227D01*
X863983Y113643D01*
X864067Y112977D01*
X863983Y112310D01*
X863650Y111727D01*
X863150Y111393D01*
X862650Y111310D01*
G01X866833D02*
Y116310D01*
G01X869500Y114643D02*
X866833Y112727D01*
G01X867917Y113477D02*
X869667Y111310D01*
G01X872600Y113560D02*
X875267D01*
X875017Y114143D01*
X874600Y114477D01*
X874017Y114643D01*
X873433Y114560D01*
X872933Y114310D01*
X872600Y113727D01*
X872433Y113227D01*
Y112727D01*
X872600Y112227D01*
X873017Y111727D01*
X873517Y111393D01*
X874100Y111310D01*
X874683Y111477D01*
X875267Y111977D01*
G01X878033Y111310D02*
Y114643D01*
G01Y113810D02*
X878367Y114227D01*
X878867Y114560D01*
X879533Y114643D01*
X880117Y114560D01*
X880617Y114227D01*
X880867Y113643D01*
Y111310D01*
G01X890650D02*
Y116310D01*
G01X897750Y111310D02*
Y114643D01*
G01Y114060D02*
X897417Y114393D01*
X896917Y114560D01*
X896333Y114643D01*
X895750Y114477D01*
X895250Y114143D01*
X894917Y113643D01*
X894750Y112977D01*
X894917Y112310D01*
X895250Y111810D01*
X895750Y111477D01*
X896333Y111310D01*
X896917Y111393D01*
X897417Y111643D01*
X897750Y111977D01*
G01X900100Y109810D02*
X900600Y109643D01*
X901267Y109810D01*
X901683Y110143D01*
X902017Y110560D01*
X902517Y111893D01*
X903600Y114643D01*
G01X900933D02*
X902517Y111893D01*
G01X906200Y113560D02*
X908867D01*
X908617Y114143D01*
X908200Y114477D01*
X907617Y114643D01*
X907033Y114560D01*
X906533Y114310D01*
X906200Y113727D01*
X906033Y113227D01*
Y112727D01*
X906200Y112227D01*
X906617Y111727D01*
X907117Y111393D01*
X907700Y111310D01*
X908283Y111477D01*
X908867Y111977D01*
G01X911883Y111310D02*
Y114643D01*
G01Y113977D02*
X912300Y114310D01*
X912717Y114560D01*
X913300Y114643D01*
X913717Y114560D01*
X914217Y114310D01*
G01X777167Y123000D02*
Y128000D01*
X778833D01*
X779500Y127750D01*
X780000Y127417D01*
X780417Y126917D01*
X780750Y126333D01*
X780833Y125500D01*
X780750Y124667D01*
X780417Y124083D01*
X780000Y123583D01*
X779500Y123250D01*
X778833Y123000D01*
X777167D01*
G01X783433D02*
Y126333D01*
G01Y125667D02*
X783850Y126000D01*
X784267Y126250D01*
X784850Y126333D01*
X785267Y126250D01*
X785767Y126000D01*
G01X790200Y126333D02*
Y123000D01*
G01Y127667D02*
X790033Y127750D01*
Y127917D01*
X790200Y128000D01*
X790367Y127917D01*
Y127750D01*
X790200Y127667D01*
G01X795800Y123000D02*
Y128000D01*
G01X801400Y123000D02*
Y128000D01*
G01X811017Y123000D02*
Y128000D01*
X814183D01*
G01X813017Y125583D02*
X811017D01*
G01X817033Y123000D02*
Y126333D01*
G01Y125667D02*
X817450Y126000D01*
X817867Y126250D01*
X818450Y126333D01*
X818867Y126250D01*
X819367Y126000D01*
G01X823800Y123000D02*
X823300Y123083D01*
X822800Y123417D01*
X822467Y124000D01*
X822300Y124667D01*
X822467Y125333D01*
X822800Y125917D01*
X823300Y126250D01*
X823800Y126333D01*
X824300Y126250D01*
X824800Y125917D01*
X825133Y125333D01*
X825217Y124667D01*
X825133Y124000D01*
X824800Y123417D01*
X824300Y123083D01*
X823800Y123000D01*
G01X826900D02*
Y126333D01*
G01Y125417D02*
X827150Y125833D01*
X827567Y126167D01*
X828150Y126333D01*
X828733Y126167D01*
X829150Y125833D01*
X829400Y125417D01*
Y123000D01*
G01Y125417D02*
X829650Y125833D01*
X830067Y126167D01*
X830650Y126333D01*
X831233Y126167D01*
X831650Y125833D01*
X831900Y125333D01*
Y123000D01*
G01X838933Y128000D02*
Y123000D01*
X842267D01*
G01X846200D02*
Y128000D01*
X845200Y127000D01*
G01Y123000D02*
X847200D01*
G01X856983Y121333D02*
X856150Y122167D01*
X855733Y123000D01*
Y126333D01*
X856150Y127167D01*
X856983Y128000D01*
G01X863000D02*
Y123000D01*
G01X861083Y128000D02*
X864917D01*
G01X868600Y123000D02*
X867933Y123083D01*
X867350Y123417D01*
X866850Y123917D01*
X866517Y124500D01*
X866350Y125167D01*
Y125833D01*
X866517Y126500D01*
X866850Y127083D01*
X867350Y127583D01*
X867933Y127917D01*
X868600Y128000D01*
X869267Y127917D01*
X869850Y127583D01*
X870350Y127083D01*
X870683Y126500D01*
X870850Y125833D01*
Y125167D01*
X870683Y124500D01*
X870350Y123917D01*
X869850Y123417D01*
X869267Y123083D01*
X868600Y123000D01*
G01X872533D02*
Y128000D01*
X874533D01*
X875200Y127750D01*
X875700Y127167D01*
X875867Y126500D01*
X875700Y125833D01*
X875283Y125333D01*
X874533Y125083D01*
X872533D01*
G01X880217Y121333D02*
X881050Y122167D01*
X881467Y123000D01*
Y126333D01*
X881050Y127167D01*
X880217Y128000D01*
G01X891000D02*
Y123000D01*
G01X889833Y126333D02*
X892167D01*
G01X896600Y123000D02*
X896100Y123083D01*
X895600Y123417D01*
X895267Y124000D01*
X895100Y124667D01*
X895267Y125333D01*
X895600Y125917D01*
X896100Y126250D01*
X896600Y126333D01*
X897100Y126250D01*
X897600Y125917D01*
X897933Y125333D01*
X898017Y124667D01*
X897933Y124000D01*
X897600Y123417D01*
X897100Y123083D01*
X896600Y123000D01*
G01X906133Y128000D02*
Y123000D01*
X909467D01*
G01X912150Y126333D02*
X914650Y123000D01*
G01Y126333D02*
X912150Y123000D01*
G01X827667Y150500D02*
Y155500D01*
X829333D01*
X830000Y155250D01*
X830500Y154917D01*
X830917Y154417D01*
X831250Y153833D01*
X831333Y153000D01*
X831250Y152167D01*
X830917Y151583D01*
X830500Y151083D01*
X830000Y150750D01*
X829333Y150500D01*
X827667D01*
G01X835100D02*
Y155500D01*
X834100Y154500D01*
G01Y150500D02*
X836100D01*
G01X825667Y314500D02*
Y319500D01*
X827333D01*
X828000Y319250D01*
X828500Y318917D01*
X828917Y318417D01*
X829250Y317833D01*
X829333Y317000D01*
X829250Y316167D01*
X828917Y315583D01*
X828500Y315083D01*
X828000Y314750D01*
X827333Y314500D01*
X825667D01*
G01X831517Y318667D02*
X832017Y319167D01*
X832600Y319417D01*
X833267Y319500D01*
X834100Y319333D01*
X834683Y318917D01*
X834850Y318417D01*
X834767Y317917D01*
X834433Y317500D01*
X832767Y316667D01*
X832017Y316083D01*
X831517Y315250D01*
X831350Y314500D01*
X834850D01*
G01X821590Y376450D02*
Y379783D01*
G01Y379200D02*
X821257Y379533D01*
X820757Y379700D01*
X820173Y379783D01*
X819590Y379617D01*
X819090Y379283D01*
X818757Y378783D01*
X818590Y378117D01*
X818757Y377450D01*
X819090Y376950D01*
X819590Y376617D01*
X820173Y376450D01*
X820757Y376533D01*
X821257Y376783D01*
X821590Y377117D01*
G01X824273Y376450D02*
Y379783D01*
G01Y378950D02*
X824607Y379367D01*
X825107Y379700D01*
X825773Y379783D01*
X826357Y379700D01*
X826857Y379367D01*
X827107Y378783D01*
Y376450D01*
G01X832790Y381450D02*
Y376450D01*
G01Y377200D02*
X832457Y376783D01*
X831957Y376533D01*
X831373Y376450D01*
X830707Y376617D01*
X830207Y377033D01*
X829873Y377533D01*
X829790Y378117D01*
X829873Y378700D01*
X830207Y379200D01*
X830707Y379617D01*
X831373Y379783D01*
X831957Y379700D01*
X832373Y379533D01*
X832790Y379200D01*
G01X843823Y379367D02*
X843240Y379700D01*
X842740Y379783D01*
X842073Y379617D01*
X841573Y379283D01*
X841240Y378700D01*
X841157Y378117D01*
X841240Y377533D01*
X841573Y377033D01*
X842073Y376617D01*
X842740Y376450D01*
X843323Y376617D01*
X843823Y376950D01*
G01X848090Y376450D02*
X847590Y376533D01*
X847090Y376867D01*
X846757Y377450D01*
X846590Y378117D01*
X846757Y378783D01*
X847090Y379367D01*
X847590Y379700D01*
X848090Y379783D01*
X848590Y379700D01*
X849090Y379367D01*
X849423Y378783D01*
X849507Y378117D01*
X849423Y377450D01*
X849090Y376867D01*
X848590Y376533D01*
X848090Y376450D01*
G01X852190Y379783D02*
X853690Y376450D01*
X855190Y379783D01*
G01X858040Y378700D02*
X860707D01*
X860457Y379283D01*
X860040Y379617D01*
X859457Y379783D01*
X858873Y379700D01*
X858373Y379450D01*
X858040Y378867D01*
X857873Y378367D01*
Y377867D01*
X858040Y377367D01*
X858457Y376867D01*
X858957Y376533D01*
X859540Y376450D01*
X860123Y376617D01*
X860707Y377117D01*
G01X863723Y376450D02*
Y379783D01*
G01Y379117D02*
X864140Y379450D01*
X864557Y379700D01*
X865140Y379783D01*
X865557Y379700D01*
X866057Y379450D01*
G01X869240Y378700D02*
X871907D01*
X871657Y379283D01*
X871240Y379617D01*
X870657Y379783D01*
X870073Y379700D01*
X869573Y379450D01*
X869240Y378867D01*
X869073Y378367D01*
Y377867D01*
X869240Y377367D01*
X869657Y376867D01*
X870157Y376533D01*
X870740Y376450D01*
X871323Y376617D01*
X871907Y377117D01*
G01X877590Y381450D02*
Y376450D01*
G01Y377200D02*
X877257Y376783D01*
X876757Y376533D01*
X876173Y376450D01*
X875507Y376617D01*
X875007Y377033D01*
X874673Y377533D01*
X874590Y378117D01*
X874673Y378700D01*
X875007Y379200D01*
X875507Y379617D01*
X876173Y379783D01*
X876757Y379700D01*
X877173Y379533D01*
X877590Y379200D01*
G01X885207Y379783D02*
X886207Y376450D01*
X887290Y379783D01*
X888373Y376450D01*
X889373Y379783D01*
G01X892890D02*
Y376450D01*
G01Y381117D02*
X892723Y381200D01*
Y381367D01*
X892890Y381450D01*
X893057Y381367D01*
Y381200D01*
X892890Y381117D01*
G01X898490Y381450D02*
Y376450D01*
G01X897323Y379783D02*
X899657D01*
G01X902673Y376450D02*
Y381450D01*
G01Y379033D02*
X903090Y379450D01*
X903507Y379700D01*
X904173Y379783D01*
X904673Y379700D01*
X905257Y379367D01*
X905507Y378867D01*
Y376450D01*
G01X916623Y379367D02*
X916040Y379700D01*
X915540Y379783D01*
X914873Y379617D01*
X914373Y379283D01*
X914040Y378700D01*
X913957Y378117D01*
X914040Y377533D01*
X914373Y377033D01*
X914873Y376617D01*
X915540Y376450D01*
X916123Y376617D01*
X916623Y376950D01*
G01X920890Y376450D02*
X920390Y376533D01*
X919890Y376867D01*
X919557Y377450D01*
X919390Y378117D01*
X919557Y378783D01*
X919890Y379367D01*
X920390Y379700D01*
X920890Y379783D01*
X921390Y379700D01*
X921890Y379367D01*
X922223Y378783D01*
X922307Y378117D01*
X922223Y377450D01*
X921890Y376867D01*
X921390Y376533D01*
X920890Y376450D01*
G01X924990Y374783D02*
Y379783D01*
G01Y379033D02*
X925407Y379450D01*
X925823Y379700D01*
X926490Y379783D01*
X927073Y379700D01*
X927657Y379283D01*
X927907Y378700D01*
X927990Y378117D01*
X927907Y377533D01*
X927657Y376950D01*
X927157Y376617D01*
X926490Y376450D01*
X925907Y376533D01*
X925323Y376783D01*
X924990Y377117D01*
G01X930590Y374783D02*
Y379783D01*
G01Y379033D02*
X931007Y379450D01*
X931423Y379700D01*
X932090Y379783D01*
X932673Y379700D01*
X933257Y379283D01*
X933507Y378700D01*
X933590Y378117D01*
X933507Y377533D01*
X933257Y376950D01*
X932757Y376617D01*
X932090Y376450D01*
X931507Y376533D01*
X930923Y376783D01*
X930590Y377117D01*
G01X936440Y378700D02*
X939107D01*
X938857Y379283D01*
X938440Y379617D01*
X937857Y379783D01*
X937273Y379700D01*
X936773Y379450D01*
X936440Y378867D01*
X936273Y378367D01*
Y377867D01*
X936440Y377367D01*
X936857Y376867D01*
X937357Y376533D01*
X937940Y376450D01*
X938523Y376617D01*
X939107Y377117D01*
G01X942123Y376450D02*
Y379783D01*
G01Y379117D02*
X942540Y379450D01*
X942957Y379700D01*
X943540Y379783D01*
X943957Y379700D01*
X944457Y379450D01*
G01X819590Y389810D02*
Y394060D01*
X819757Y394477D01*
X820090Y394727D01*
X820590Y394810D01*
X821090Y394643D01*
X821340Y394227D01*
G01X820340Y392810D02*
X818673D01*
G01X825690Y389810D02*
X825190Y389893D01*
X824690Y390227D01*
X824357Y390810D01*
X824190Y391477D01*
X824357Y392143D01*
X824690Y392727D01*
X825190Y393060D01*
X825690Y393143D01*
X826190Y393060D01*
X826690Y392727D01*
X827023Y392143D01*
X827107Y391477D01*
X827023Y390810D01*
X826690Y390227D01*
X826190Y389893D01*
X825690Y389810D01*
G01X831290D02*
Y394810D01*
G01X836890Y389810D02*
Y394810D01*
G01X842490Y389810D02*
X841990Y389893D01*
X841490Y390227D01*
X841157Y390810D01*
X840990Y391477D01*
X841157Y392143D01*
X841490Y392727D01*
X841990Y393060D01*
X842490Y393143D01*
X842990Y393060D01*
X843490Y392727D01*
X843823Y392143D01*
X843907Y391477D01*
X843823Y390810D01*
X843490Y390227D01*
X842990Y389893D01*
X842490Y389810D01*
G01X846007Y393143D02*
X847007Y389810D01*
X848090Y393143D01*
X849173Y389810D01*
X850173Y393143D01*
G01X859790Y392310D02*
X861457D01*
Y390810D01*
X860957Y390310D01*
X860373Y389977D01*
X859540Y389810D01*
X858707Y389977D01*
X858123Y390310D01*
X857623Y390810D01*
X857290Y391393D01*
X857123Y392060D01*
Y392643D01*
X857290Y393143D01*
X857623Y393727D01*
X858123Y394227D01*
X858623Y394560D01*
X859290Y394810D01*
X859873D01*
X860540Y394643D01*
X861040Y394310D01*
G01X863640Y392060D02*
X866307D01*
X866057Y392643D01*
X865640Y392977D01*
X865057Y393143D01*
X864473Y393060D01*
X863973Y392810D01*
X863640Y392227D01*
X863473Y391727D01*
Y391227D01*
X863640Y390727D01*
X864057Y390227D01*
X864557Y389893D01*
X865140Y389810D01*
X865723Y389977D01*
X866307Y390477D01*
G01X869323Y389810D02*
Y393143D01*
G01Y392477D02*
X869740Y392810D01*
X870157Y393060D01*
X870740Y393143D01*
X871157Y393060D01*
X871657Y392810D01*
G01X874590Y389810D02*
Y394810D01*
G01Y392310D02*
X875007Y392810D01*
X875507Y393060D01*
X876007Y393143D01*
X876757Y392977D01*
X877257Y392643D01*
X877590Y392060D01*
Y391393D01*
X877423Y390727D01*
X877090Y390227D01*
X876507Y389893D01*
X876007Y389810D01*
X875507Y389893D01*
X875007Y390143D01*
X874590Y390560D01*
G01X880440Y392060D02*
X883107D01*
X882857Y392643D01*
X882440Y392977D01*
X881857Y393143D01*
X881273Y393060D01*
X880773Y392810D01*
X880440Y392227D01*
X880273Y391727D01*
Y391227D01*
X880440Y390727D01*
X880857Y390227D01*
X881357Y389893D01*
X881940Y389810D01*
X882523Y389977D01*
X883107Y390477D01*
G01X886123Y389810D02*
Y393143D01*
G01Y392477D02*
X886540Y392810D01*
X886957Y393060D01*
X887540Y393143D01*
X887957Y393060D01*
X888457Y392810D01*
G01X899990Y389810D02*
Y393143D01*
G01Y392560D02*
X899657Y392893D01*
X899157Y393060D01*
X898573Y393143D01*
X897990Y392977D01*
X897490Y392643D01*
X897157Y392143D01*
X896990Y391477D01*
X897157Y390810D01*
X897490Y390310D01*
X897990Y389977D01*
X898573Y389810D01*
X899157Y389893D01*
X899657Y390143D01*
X899990Y390477D01*
G01X902673Y389810D02*
Y393143D01*
G01Y392310D02*
X903007Y392727D01*
X903507Y393060D01*
X904173Y393143D01*
X904757Y393060D01*
X905257Y392727D01*
X905507Y392143D01*
Y389810D01*
G01X911190Y394810D02*
Y389810D01*
G01Y390560D02*
X910857Y390143D01*
X910357Y389893D01*
X909773Y389810D01*
X909107Y389977D01*
X908607Y390393D01*
X908273Y390893D01*
X908190Y391477D01*
X908273Y392060D01*
X908607Y392560D01*
X909107Y392977D01*
X909773Y393143D01*
X910357Y393060D01*
X910773Y392893D01*
X911190Y392560D01*
G01X919390Y388143D02*
Y393143D01*
G01Y392393D02*
X919807Y392810D01*
X920223Y393060D01*
X920890Y393143D01*
X921473Y393060D01*
X922057Y392643D01*
X922307Y392060D01*
X922390Y391477D01*
X922307Y390893D01*
X922057Y390310D01*
X921557Y389977D01*
X920890Y389810D01*
X920307Y389893D01*
X919723Y390143D01*
X919390Y390477D01*
G01X926490Y389810D02*
Y394810D01*
G01X930673Y393143D02*
Y390810D01*
X931007Y390227D01*
X931507Y389893D01*
X932090Y389810D01*
X932673Y389893D01*
X933173Y390227D01*
X933507Y390810D01*
G01Y389810D02*
Y393143D01*
G01X936523Y388560D02*
X937107Y388227D01*
X937773Y388143D01*
X938357Y388227D01*
X938857Y388643D01*
X939190Y389227D01*
Y393143D01*
G01Y392477D02*
X938857Y392810D01*
X938357Y393060D01*
X937773Y393143D01*
X937107Y392977D01*
X936690Y392643D01*
X936357Y392060D01*
X936190Y391477D01*
X936273Y390977D01*
X936607Y390393D01*
X937107Y389977D01*
X937773Y389810D01*
X938273Y389893D01*
X938857Y390227D01*
X939190Y390560D01*
G01X946807Y393143D02*
X947807Y389810D01*
X948890Y393143D01*
X949973Y389810D01*
X950973Y393143D01*
G01X954490D02*
Y389810D01*
G01Y394477D02*
X954323Y394560D01*
Y394727D01*
X954490Y394810D01*
X954657Y394727D01*
Y394560D01*
X954490Y394477D01*
G01X960090Y394810D02*
Y389810D01*
G01X958923Y393143D02*
X961257D01*
G01X964273Y389810D02*
Y394810D01*
G01Y392393D02*
X964690Y392810D01*
X965107Y393060D01*
X965773Y393143D01*
X966273Y393060D01*
X966857Y392727D01*
X967107Y392227D01*
Y389810D01*
G01X975723D02*
Y393143D01*
G01Y392477D02*
X976140Y392810D01*
X976557Y393060D01*
X977140Y393143D01*
X977557Y393060D01*
X978057Y392810D01*
G01X981240Y392060D02*
X983907D01*
X983657Y392643D01*
X983240Y392977D01*
X982657Y393143D01*
X982073Y393060D01*
X981573Y392810D01*
X981240Y392227D01*
X981073Y391727D01*
Y391227D01*
X981240Y390727D01*
X981657Y390227D01*
X982157Y389893D01*
X982740Y389810D01*
X983323Y389977D01*
X983907Y390477D01*
G01X986840Y390393D02*
X987257Y390060D01*
X987840Y389810D01*
X988340D01*
X988840Y389977D01*
X989173Y390227D01*
X989340Y390560D01*
X989257Y391060D01*
X988923Y391310D01*
X987423Y391810D01*
X987090Y392393D01*
X987257Y392810D01*
X987590Y393060D01*
X988090Y393143D01*
X988590Y393060D01*
X989090Y392810D01*
G01X993690Y393143D02*
Y389810D01*
G01Y394477D02*
X993523Y394560D01*
Y394727D01*
X993690Y394810D01*
X993857Y394727D01*
Y394560D01*
X993690Y394477D01*
G01X997873Y389810D02*
Y393143D01*
G01Y392310D02*
X998207Y392727D01*
X998707Y393060D01*
X999373Y393143D01*
X999957Y393060D01*
X1000457Y392727D01*
X1000707Y392143D01*
Y389810D01*
G01X812000Y604500D02*
Y366000D01*
G01X823500Y455500D02*
Y458833D01*
G01Y458250D02*
X823167Y458583D01*
X822667Y458750D01*
X822083Y458833D01*
X821500Y458667D01*
X821000Y458333D01*
X820667Y457833D01*
X820500Y457167D01*
X820667Y456500D01*
X821000Y456000D01*
X821500Y455667D01*
X822083Y455500D01*
X822667Y455583D01*
X823167Y455833D01*
X823500Y456167D01*
G01X826183Y455500D02*
Y458833D01*
G01Y458000D02*
X826517Y458417D01*
X827017Y458750D01*
X827683Y458833D01*
X828267Y458750D01*
X828767Y458417D01*
X829017Y457833D01*
Y455500D01*
G01X834700Y460500D02*
Y455500D01*
G01Y456250D02*
X834367Y455833D01*
X833867Y455583D01*
X833283Y455500D01*
X832617Y455667D01*
X832117Y456083D01*
X831783Y456583D01*
X831700Y457167D01*
X831783Y457750D01*
X832117Y458250D01*
X832617Y458667D01*
X833283Y458833D01*
X833867Y458750D01*
X834283Y458583D01*
X834700Y458250D01*
G01X842900Y455500D02*
Y460500D01*
G01Y458000D02*
X843317Y458500D01*
X843817Y458750D01*
X844317Y458833D01*
X845067Y458667D01*
X845567Y458333D01*
X845900Y457750D01*
Y457083D01*
X845733Y456417D01*
X845400Y455917D01*
X844817Y455583D01*
X844317Y455500D01*
X843817Y455583D01*
X843317Y455833D01*
X842900Y456250D01*
G01X850000Y455500D02*
X849500Y455583D01*
X849000Y455917D01*
X848667Y456500D01*
X848500Y457167D01*
X848667Y457833D01*
X849000Y458417D01*
X849500Y458750D01*
X850000Y458833D01*
X850500Y458750D01*
X851000Y458417D01*
X851333Y457833D01*
X851417Y457167D01*
X851333Y456500D01*
X851000Y455917D01*
X850500Y455583D01*
X850000Y455500D01*
G01X855600Y460500D02*
Y455500D01*
G01X854433Y458833D02*
X856767D01*
G01X861200Y460500D02*
Y455500D01*
G01X860033Y458833D02*
X862367D01*
G01X866800Y455500D02*
X866300Y455583D01*
X865800Y455917D01*
X865467Y456500D01*
X865300Y457167D01*
X865467Y457833D01*
X865800Y458417D01*
X866300Y458750D01*
X866800Y458833D01*
X867300Y458750D01*
X867800Y458417D01*
X868133Y457833D01*
X868217Y457167D01*
X868133Y456500D01*
X867800Y455917D01*
X867300Y455583D01*
X866800Y455500D01*
G01X869900D02*
Y458833D01*
G01Y457917D02*
X870150Y458333D01*
X870567Y458667D01*
X871150Y458833D01*
X871733Y458667D01*
X872150Y458333D01*
X872400Y457917D01*
Y455500D01*
G01Y457917D02*
X872650Y458333D01*
X873067Y458667D01*
X873650Y458833D01*
X874233Y458667D01*
X874650Y458333D01*
X874900Y457833D01*
Y455500D01*
G01X882350Y456083D02*
X882767Y455750D01*
X883350Y455500D01*
X883850D01*
X884350Y455667D01*
X884683Y455917D01*
X884850Y456250D01*
X884767Y456750D01*
X884433Y457000D01*
X882933Y457500D01*
X882600Y458083D01*
X882767Y458500D01*
X883100Y458750D01*
X883600Y458833D01*
X884100Y458750D01*
X884600Y458500D01*
G01X889200Y458833D02*
Y455500D01*
G01Y460167D02*
X889033Y460250D01*
Y460417D01*
X889200Y460500D01*
X889367Y460417D01*
Y460250D01*
X889200Y460167D01*
G01X896300Y460500D02*
Y455500D01*
G01Y456250D02*
X895967Y455833D01*
X895467Y455583D01*
X894883Y455500D01*
X894217Y455667D01*
X893717Y456083D01*
X893383Y456583D01*
X893300Y457167D01*
X893383Y457750D01*
X893717Y458250D01*
X894217Y458667D01*
X894883Y458833D01*
X895467Y458750D01*
X895883Y458583D01*
X896300Y458250D01*
G01X899150Y457750D02*
X901817D01*
X901567Y458333D01*
X901150Y458667D01*
X900567Y458833D01*
X899983Y458750D01*
X899483Y458500D01*
X899150Y457917D01*
X898983Y457417D01*
Y456917D01*
X899150Y456417D01*
X899567Y455917D01*
X900067Y455583D01*
X900650Y455500D01*
X901233Y455667D01*
X901817Y456167D01*
G01X819917Y470833D02*
X820917Y467500D01*
X822000Y470833D01*
X823083Y467500D01*
X824083Y470833D01*
G01X827600D02*
Y467500D01*
G01Y472167D02*
X827433Y472250D01*
Y472417D01*
X827600Y472500D01*
X827767Y472417D01*
Y472250D01*
X827600Y472167D01*
G01X833200Y472500D02*
Y467500D01*
G01X832033Y470833D02*
X834367D01*
G01X837383Y467500D02*
Y472500D01*
G01Y470083D02*
X837800Y470500D01*
X838217Y470750D01*
X838883Y470833D01*
X839383Y470750D01*
X839967Y470417D01*
X840217Y469917D01*
Y467500D01*
G01X844400D02*
X843900Y467583D01*
X843400Y467917D01*
X843067Y468500D01*
X842900Y469167D01*
X843067Y469833D01*
X843400Y470417D01*
X843900Y470750D01*
X844400Y470833D01*
X844900Y470750D01*
X845400Y470417D01*
X845733Y469833D01*
X845817Y469167D01*
X845733Y468500D01*
X845400Y467917D01*
X844900Y467583D01*
X844400Y467500D01*
G01X848583Y470833D02*
Y468500D01*
X848917Y467917D01*
X849417Y467583D01*
X850000Y467500D01*
X850583Y467583D01*
X851083Y467917D01*
X851417Y468500D01*
G01Y467500D02*
Y470833D01*
G01X855600Y472500D02*
Y467500D01*
G01X854433Y470833D02*
X856767D01*
G01X865550Y468083D02*
X865967Y467750D01*
X866550Y467500D01*
X867050D01*
X867550Y467667D01*
X867883Y467917D01*
X868050Y468250D01*
X867967Y468750D01*
X867633Y469000D01*
X866133Y469500D01*
X865800Y470083D01*
X865967Y470500D01*
X866300Y470750D01*
X866800Y470833D01*
X867300Y470750D01*
X867800Y470500D01*
G01X872400Y467500D02*
X871900Y467583D01*
X871400Y467917D01*
X871067Y468500D01*
X870900Y469167D01*
X871067Y469833D01*
X871400Y470417D01*
X871900Y470750D01*
X872400Y470833D01*
X872900Y470750D01*
X873400Y470417D01*
X873733Y469833D01*
X873817Y469167D01*
X873733Y468500D01*
X873400Y467917D01*
X872900Y467583D01*
X872400Y467500D01*
G01X878000D02*
Y472500D01*
G01X885100D02*
Y467500D01*
G01Y468250D02*
X884767Y467833D01*
X884267Y467583D01*
X883683Y467500D01*
X883017Y467667D01*
X882517Y468083D01*
X882183Y468583D01*
X882100Y469167D01*
X882183Y469750D01*
X882517Y470250D01*
X883017Y470667D01*
X883683Y470833D01*
X884267Y470750D01*
X884683Y470583D01*
X885100Y470250D01*
G01X887950Y469750D02*
X890617D01*
X890367Y470333D01*
X889950Y470667D01*
X889367Y470833D01*
X888783Y470750D01*
X888283Y470500D01*
X887950Y469917D01*
X887783Y469417D01*
Y468917D01*
X887950Y468417D01*
X888367Y467917D01*
X888867Y467583D01*
X889450Y467500D01*
X890033Y467667D01*
X890617Y468167D01*
G01X893633Y467500D02*
Y470833D01*
G01Y470167D02*
X894050Y470500D01*
X894467Y470750D01*
X895050Y470833D01*
X895467Y470750D01*
X895967Y470500D01*
G01X903500Y467500D02*
Y470833D01*
G01Y469917D02*
X903750Y470333D01*
X904167Y470667D01*
X904750Y470833D01*
X905333Y470667D01*
X905750Y470333D01*
X906000Y469917D01*
Y467500D01*
G01Y469917D02*
X906250Y470333D01*
X906667Y470667D01*
X907250Y470833D01*
X907833Y470667D01*
X908250Y470333D01*
X908500Y469833D01*
Y467500D01*
G01X913100D02*
Y470833D01*
G01Y470250D02*
X912767Y470583D01*
X912267Y470750D01*
X911683Y470833D01*
X911100Y470667D01*
X910600Y470333D01*
X910267Y469833D01*
X910100Y469167D01*
X910267Y468500D01*
X910600Y468000D01*
X911100Y467667D01*
X911683Y467500D01*
X912267Y467583D01*
X912767Y467833D01*
X913100Y468167D01*
G01X915950Y468083D02*
X916367Y467750D01*
X916950Y467500D01*
X917450D01*
X917950Y467667D01*
X918283Y467917D01*
X918450Y468250D01*
X918367Y468750D01*
X918033Y469000D01*
X916533Y469500D01*
X916200Y470083D01*
X916367Y470500D01*
X916700Y470750D01*
X917200Y470833D01*
X917700Y470750D01*
X918200Y470500D01*
G01X921383Y467500D02*
Y472500D01*
G01X924050Y470833D02*
X921383Y468917D01*
G01X922467Y469667D02*
X924217Y467500D01*
G01X932500Y465833D02*
Y470833D01*
G01Y470083D02*
X932917Y470500D01*
X933333Y470750D01*
X934000Y470833D01*
X934583Y470750D01*
X935167Y470333D01*
X935417Y469750D01*
X935500Y469167D01*
X935417Y468583D01*
X935167Y468000D01*
X934667Y467667D01*
X934000Y467500D01*
X933417Y467583D01*
X932833Y467833D01*
X932500Y468167D01*
G01X941100Y467500D02*
Y470833D01*
G01Y470250D02*
X940767Y470583D01*
X940267Y470750D01*
X939683Y470833D01*
X939100Y470667D01*
X938600Y470333D01*
X938267Y469833D01*
X938100Y469167D01*
X938267Y468500D01*
X938600Y468000D01*
X939100Y467667D01*
X939683Y467500D01*
X940267Y467583D01*
X940767Y467833D01*
X941100Y468167D01*
G01X946700Y472500D02*
Y467500D01*
G01Y468250D02*
X946367Y467833D01*
X945867Y467583D01*
X945283Y467500D01*
X944617Y467667D01*
X944117Y468083D01*
X943783Y468583D01*
X943700Y469167D01*
X943783Y469750D01*
X944117Y470250D01*
X944617Y470667D01*
X945283Y470833D01*
X945867Y470750D01*
X946283Y470583D01*
X946700Y470250D01*
G01X956400Y467500D02*
X955900Y467583D01*
X955400Y467917D01*
X955067Y468500D01*
X954900Y469167D01*
X955067Y469833D01*
X955400Y470417D01*
X955900Y470750D01*
X956400Y470833D01*
X956900Y470750D01*
X957400Y470417D01*
X957733Y469833D01*
X957817Y469167D01*
X957733Y468500D01*
X957400Y467917D01*
X956900Y467583D01*
X956400Y467500D01*
G01X960583D02*
Y470833D01*
G01Y470000D02*
X960917Y470417D01*
X961417Y470750D01*
X962083Y470833D01*
X962667Y470750D01*
X963167Y470417D01*
X963417Y469833D01*
Y467500D01*
G01X973200Y472500D02*
Y467500D01*
G01X972033Y470833D02*
X974367D01*
G01X978800Y467500D02*
X978300Y467583D01*
X977800Y467917D01*
X977467Y468500D01*
X977300Y469167D01*
X977467Y469833D01*
X977800Y470417D01*
X978300Y470750D01*
X978800Y470833D01*
X979300Y470750D01*
X979800Y470417D01*
X980133Y469833D01*
X980217Y469167D01*
X980133Y468500D01*
X979800Y467917D01*
X979300Y467583D01*
X978800Y467500D01*
G01X982900Y465833D02*
Y470833D01*
G01Y470083D02*
X983317Y470500D01*
X983733Y470750D01*
X984400Y470833D01*
X984983Y470750D01*
X985567Y470333D01*
X985817Y469750D01*
X985900Y469167D01*
X985817Y468583D01*
X985567Y468000D01*
X985067Y467667D01*
X984400Y467500D01*
X983817Y467583D01*
X983233Y467833D01*
X982900Y468167D01*
G01X821500Y440500D02*
Y444750D01*
X821667Y445167D01*
X822000Y445417D01*
X822500Y445500D01*
X823000Y445333D01*
X823250Y444917D01*
G01X822250Y443500D02*
X820583D01*
G01X827600Y440500D02*
X827100Y440583D01*
X826600Y440917D01*
X826267Y441500D01*
X826100Y442167D01*
X826267Y442833D01*
X826600Y443417D01*
X827100Y443750D01*
X827600Y443833D01*
X828100Y443750D01*
X828600Y443417D01*
X828933Y442833D01*
X829017Y442167D01*
X828933Y441500D01*
X828600Y440917D01*
X828100Y440583D01*
X827600Y440500D01*
G01X833200D02*
Y445500D01*
G01X838800Y440500D02*
Y445500D01*
G01X844400Y440500D02*
X843900Y440583D01*
X843400Y440917D01*
X843067Y441500D01*
X842900Y442167D01*
X843067Y442833D01*
X843400Y443417D01*
X843900Y443750D01*
X844400Y443833D01*
X844900Y443750D01*
X845400Y443417D01*
X845733Y442833D01*
X845817Y442167D01*
X845733Y441500D01*
X845400Y440917D01*
X844900Y440583D01*
X844400Y440500D01*
G01X847917Y443833D02*
X848917Y440500D01*
X850000Y443833D01*
X851083Y440500D01*
X852083Y443833D01*
G01X861700Y443000D02*
X863367D01*
Y441500D01*
X862867Y441000D01*
X862283Y440667D01*
X861450Y440500D01*
X860617Y440667D01*
X860033Y441000D01*
X859533Y441500D01*
X859200Y442083D01*
X859033Y442750D01*
Y443333D01*
X859200Y443833D01*
X859533Y444417D01*
X860033Y444917D01*
X860533Y445250D01*
X861200Y445500D01*
X861783D01*
X862450Y445333D01*
X862950Y445000D01*
G01X865550Y442750D02*
X868217D01*
X867967Y443333D01*
X867550Y443667D01*
X866967Y443833D01*
X866383Y443750D01*
X865883Y443500D01*
X865550Y442917D01*
X865383Y442417D01*
Y441917D01*
X865550Y441417D01*
X865967Y440917D01*
X866467Y440583D01*
X867050Y440500D01*
X867633Y440667D01*
X868217Y441167D01*
G01X871233Y440500D02*
Y443833D01*
G01Y443167D02*
X871650Y443500D01*
X872067Y443750D01*
X872650Y443833D01*
X873067Y443750D01*
X873567Y443500D01*
G01X876500Y440500D02*
Y445500D01*
G01Y443000D02*
X876917Y443500D01*
X877417Y443750D01*
X877917Y443833D01*
X878667Y443667D01*
X879167Y443333D01*
X879500Y442750D01*
Y442083D01*
X879333Y441417D01*
X879000Y440917D01*
X878417Y440583D01*
X877917Y440500D01*
X877417Y440583D01*
X876917Y440833D01*
X876500Y441250D01*
G01X882350Y442750D02*
X885017D01*
X884767Y443333D01*
X884350Y443667D01*
X883767Y443833D01*
X883183Y443750D01*
X882683Y443500D01*
X882350Y442917D01*
X882183Y442417D01*
Y441917D01*
X882350Y441417D01*
X882767Y440917D01*
X883267Y440583D01*
X883850Y440500D01*
X884433Y440667D01*
X885017Y441167D01*
G01X888033Y440500D02*
Y443833D01*
G01Y443167D02*
X888450Y443500D01*
X888867Y443750D01*
X889450Y443833D01*
X889867Y443750D01*
X890367Y443500D01*
G01X821500Y419500D02*
Y423750D01*
X821667Y424167D01*
X822000Y424417D01*
X822500Y424500D01*
X823000Y424333D01*
X823250Y423917D01*
G01X822250Y422500D02*
X820583D01*
G01X827600Y419500D02*
X827100Y419583D01*
X826600Y419917D01*
X826267Y420500D01*
X826100Y421167D01*
X826267Y421833D01*
X826600Y422417D01*
X827100Y422750D01*
X827600Y422833D01*
X828100Y422750D01*
X828600Y422417D01*
X828933Y421833D01*
X829017Y421167D01*
X828933Y420500D01*
X828600Y419917D01*
X828100Y419583D01*
X827600Y419500D01*
G01X833200D02*
Y424500D01*
G01X838800Y419500D02*
Y424500D01*
G01X844400Y419500D02*
X843900Y419583D01*
X843400Y419917D01*
X843067Y420500D01*
X842900Y421167D01*
X843067Y421833D01*
X843400Y422417D01*
X843900Y422750D01*
X844400Y422833D01*
X844900Y422750D01*
X845400Y422417D01*
X845733Y421833D01*
X845817Y421167D01*
X845733Y420500D01*
X845400Y419917D01*
X844900Y419583D01*
X844400Y419500D01*
G01X847917Y422833D02*
X848917Y419500D01*
X850000Y422833D01*
X851083Y419500D01*
X852083Y422833D01*
G01X861700Y422000D02*
X863367D01*
Y420500D01*
X862867Y420000D01*
X862283Y419667D01*
X861450Y419500D01*
X860617Y419667D01*
X860033Y420000D01*
X859533Y420500D01*
X859200Y421083D01*
X859033Y421750D01*
Y422333D01*
X859200Y422833D01*
X859533Y423417D01*
X860033Y423917D01*
X860533Y424250D01*
X861200Y424500D01*
X861783D01*
X862450Y424333D01*
X862950Y424000D01*
G01X865550Y421750D02*
X868217D01*
X867967Y422333D01*
X867550Y422667D01*
X866967Y422833D01*
X866383Y422750D01*
X865883Y422500D01*
X865550Y421917D01*
X865383Y421417D01*
Y420917D01*
X865550Y420417D01*
X865967Y419917D01*
X866467Y419583D01*
X867050Y419500D01*
X867633Y419667D01*
X868217Y420167D01*
G01X871233Y419500D02*
Y422833D01*
G01Y422167D02*
X871650Y422500D01*
X872067Y422750D01*
X872650Y422833D01*
X873067Y422750D01*
X873567Y422500D01*
G01X876500Y419500D02*
Y424500D01*
G01Y422000D02*
X876917Y422500D01*
X877417Y422750D01*
X877917Y422833D01*
X878667Y422667D01*
X879167Y422333D01*
X879500Y421750D01*
Y421083D01*
X879333Y420417D01*
X879000Y419917D01*
X878417Y419583D01*
X877917Y419500D01*
X877417Y419583D01*
X876917Y419833D01*
X876500Y420250D01*
G01X882350Y421750D02*
X885017D01*
X884767Y422333D01*
X884350Y422667D01*
X883767Y422833D01*
X883183Y422750D01*
X882683Y422500D01*
X882350Y421917D01*
X882183Y421417D01*
Y420917D01*
X882350Y420417D01*
X882767Y419917D01*
X883267Y419583D01*
X883850Y419500D01*
X884433Y419667D01*
X885017Y420167D01*
G01X888033Y419500D02*
Y422833D01*
G01Y422167D02*
X888450Y422500D01*
X888867Y422750D01*
X889450Y422833D01*
X889867Y422750D01*
X890367Y422500D01*
G01X901900Y419500D02*
Y422833D01*
G01Y422250D02*
X901567Y422583D01*
X901067Y422750D01*
X900483Y422833D01*
X899900Y422667D01*
X899400Y422333D01*
X899067Y421833D01*
X898900Y421167D01*
X899067Y420500D01*
X899400Y420000D01*
X899900Y419667D01*
X900483Y419500D01*
X901067Y419583D01*
X901567Y419833D01*
X901900Y420167D01*
G01X904583Y419500D02*
Y422833D01*
G01Y422000D02*
X904917Y422417D01*
X905417Y422750D01*
X906083Y422833D01*
X906667Y422750D01*
X907167Y422417D01*
X907417Y421833D01*
Y419500D01*
G01X913100Y424500D02*
Y419500D01*
G01Y420250D02*
X912767Y419833D01*
X912267Y419583D01*
X911683Y419500D01*
X911017Y419667D01*
X910517Y420083D01*
X910183Y420583D01*
X910100Y421167D01*
X910183Y421750D01*
X910517Y422250D01*
X911017Y422667D01*
X911683Y422833D01*
X912267Y422750D01*
X912683Y422583D01*
X913100Y422250D01*
G01X921300Y417833D02*
Y422833D01*
G01Y422083D02*
X921717Y422500D01*
X922133Y422750D01*
X922800Y422833D01*
X923383Y422750D01*
X923967Y422333D01*
X924217Y421750D01*
X924300Y421167D01*
X924217Y420583D01*
X923967Y420000D01*
X923467Y419667D01*
X922800Y419500D01*
X922217Y419583D01*
X921633Y419833D01*
X921300Y420167D01*
G01X928400Y419500D02*
Y424500D01*
G01X932583Y422833D02*
Y420500D01*
X932917Y419917D01*
X933417Y419583D01*
X934000Y419500D01*
X934583Y419583D01*
X935083Y419917D01*
X935417Y420500D01*
G01Y419500D02*
Y422833D01*
G01X938433Y418250D02*
X939017Y417917D01*
X939683Y417833D01*
X940267Y417917D01*
X940767Y418333D01*
X941100Y418917D01*
Y422833D01*
G01Y422167D02*
X940767Y422500D01*
X940267Y422750D01*
X939683Y422833D01*
X939017Y422667D01*
X938600Y422333D01*
X938267Y421750D01*
X938100Y421167D01*
X938183Y420667D01*
X938517Y420083D01*
X939017Y419667D01*
X939683Y419500D01*
X940183Y419583D01*
X940767Y419917D01*
X941100Y420250D01*
G01X948717Y422833D02*
X949717Y419500D01*
X950800Y422833D01*
X951883Y419500D01*
X952883Y422833D01*
G01X956400D02*
Y419500D01*
G01Y424167D02*
X956233Y424250D01*
Y424417D01*
X956400Y424500D01*
X956567Y424417D01*
Y424250D01*
X956400Y424167D01*
G01X962000Y424500D02*
Y419500D01*
G01X960833Y422833D02*
X963167D01*
G01X966183Y419500D02*
Y424500D01*
G01Y422083D02*
X966600Y422500D01*
X967017Y422750D01*
X967683Y422833D01*
X968183Y422750D01*
X968767Y422417D01*
X969017Y421917D01*
Y419500D01*
G01X977633D02*
Y422833D01*
G01Y422167D02*
X978050Y422500D01*
X978467Y422750D01*
X979050Y422833D01*
X979467Y422750D01*
X979967Y422500D01*
G01X983150Y421750D02*
X985817D01*
X985567Y422333D01*
X985150Y422667D01*
X984567Y422833D01*
X983983Y422750D01*
X983483Y422500D01*
X983150Y421917D01*
X982983Y421417D01*
Y420917D01*
X983150Y420417D01*
X983567Y419917D01*
X984067Y419583D01*
X984650Y419500D01*
X985233Y419667D01*
X985817Y420167D01*
G01X988750Y420083D02*
X989167Y419750D01*
X989750Y419500D01*
X990250D01*
X990750Y419667D01*
X991083Y419917D01*
X991250Y420250D01*
X991167Y420750D01*
X990833Y421000D01*
X989333Y421500D01*
X989000Y422083D01*
X989167Y422500D01*
X989500Y422750D01*
X990000Y422833D01*
X990500Y422750D01*
X991000Y422500D01*
G01X995600Y422833D02*
Y419500D01*
G01Y424167D02*
X995433Y424250D01*
Y424417D01*
X995600Y424500D01*
X995767Y424417D01*
Y424250D01*
X995600Y424167D01*
G01X999783Y419500D02*
Y422833D01*
G01Y422000D02*
X1000117Y422417D01*
X1000617Y422750D01*
X1001283Y422833D01*
X1001867Y422750D01*
X1002367Y422417D01*
X1002617Y421833D01*
Y419500D01*
G01X829750Y542583D02*
X830167Y542250D01*
X830750Y542000D01*
X831250D01*
X831750Y542167D01*
X832083Y542417D01*
X832250Y542750D01*
X832167Y543250D01*
X831833Y543500D01*
X830333Y544000D01*
X830000Y544583D01*
X830167Y545000D01*
X830500Y545250D01*
X831000Y545333D01*
X831500Y545250D01*
X832000Y545000D01*
G01X836600Y542000D02*
X836100Y542083D01*
X835600Y542417D01*
X835267Y543000D01*
X835100Y543667D01*
X835267Y544333D01*
X835600Y544917D01*
X836100Y545250D01*
X836600Y545333D01*
X837100Y545250D01*
X837600Y544917D01*
X837933Y544333D01*
X838017Y543667D01*
X837933Y543000D01*
X837600Y542417D01*
X837100Y542083D01*
X836600Y542000D01*
G01X842200D02*
Y547000D01*
G01X849300D02*
Y542000D01*
G01Y542750D02*
X848967Y542333D01*
X848467Y542083D01*
X847883Y542000D01*
X847217Y542167D01*
X846717Y542583D01*
X846383Y543083D01*
X846300Y543667D01*
X846383Y544250D01*
X846717Y544750D01*
X847217Y545167D01*
X847883Y545333D01*
X848467Y545250D01*
X848883Y545083D01*
X849300Y544750D01*
G01X852150Y544250D02*
X854817D01*
X854567Y544833D01*
X854150Y545167D01*
X853567Y545333D01*
X852983Y545250D01*
X852483Y545000D01*
X852150Y544417D01*
X851983Y543917D01*
Y543417D01*
X852150Y542917D01*
X852567Y542417D01*
X853067Y542083D01*
X853650Y542000D01*
X854233Y542167D01*
X854817Y542667D01*
G01X857833Y542000D02*
Y545333D01*
G01Y544667D02*
X858250Y545000D01*
X858667Y545250D01*
X859250Y545333D01*
X859667Y545250D01*
X860167Y545000D01*
G01X867700Y542000D02*
Y545333D01*
G01Y544417D02*
X867950Y544833D01*
X868367Y545167D01*
X868950Y545333D01*
X869533Y545167D01*
X869950Y544833D01*
X870200Y544417D01*
Y542000D01*
G01Y544417D02*
X870450Y544833D01*
X870867Y545167D01*
X871450Y545333D01*
X872033Y545167D01*
X872450Y544833D01*
X872700Y544333D01*
Y542000D01*
G01X877300D02*
Y545333D01*
G01Y544750D02*
X876967Y545083D01*
X876467Y545250D01*
X875883Y545333D01*
X875300Y545167D01*
X874800Y544833D01*
X874467Y544333D01*
X874300Y543667D01*
X874467Y543000D01*
X874800Y542500D01*
X875300Y542167D01*
X875883Y542000D01*
X876467Y542083D01*
X876967Y542333D01*
X877300Y542667D01*
G01X880150Y542583D02*
X880567Y542250D01*
X881150Y542000D01*
X881650D01*
X882150Y542167D01*
X882483Y542417D01*
X882650Y542750D01*
X882567Y543250D01*
X882233Y543500D01*
X880733Y544000D01*
X880400Y544583D01*
X880567Y545000D01*
X880900Y545250D01*
X881400Y545333D01*
X881900Y545250D01*
X882400Y545000D01*
G01X885583Y542000D02*
Y547000D01*
G01X888250Y545333D02*
X885583Y543417D01*
G01X886667Y544167D02*
X888417Y542000D01*
G01X896700Y540333D02*
Y545333D01*
G01Y544583D02*
X897117Y545000D01*
X897533Y545250D01*
X898200Y545333D01*
X898783Y545250D01*
X899367Y544833D01*
X899617Y544250D01*
X899700Y543667D01*
X899617Y543083D01*
X899367Y542500D01*
X898867Y542167D01*
X898200Y542000D01*
X897617Y542083D01*
X897033Y542333D01*
X896700Y542667D01*
G01X905300Y542000D02*
Y545333D01*
G01Y544750D02*
X904967Y545083D01*
X904467Y545250D01*
X903883Y545333D01*
X903300Y545167D01*
X902800Y544833D01*
X902467Y544333D01*
X902300Y543667D01*
X902467Y543000D01*
X902800Y542500D01*
X903300Y542167D01*
X903883Y542000D01*
X904467Y542083D01*
X904967Y542333D01*
X905300Y542667D01*
G01X910900Y547000D02*
Y542000D01*
G01Y542750D02*
X910567Y542333D01*
X910067Y542083D01*
X909483Y542000D01*
X908817Y542167D01*
X908317Y542583D01*
X907983Y543083D01*
X907900Y543667D01*
X907983Y544250D01*
X908317Y544750D01*
X908817Y545167D01*
X909483Y545333D01*
X910067Y545250D01*
X910483Y545083D01*
X910900Y544750D01*
G01X831333Y551000D02*
Y554333D01*
G01Y553667D02*
X831750Y554000D01*
X832167Y554250D01*
X832750Y554333D01*
X833167Y554250D01*
X833667Y554000D01*
G01X838100Y554333D02*
Y551000D01*
G01Y555667D02*
X837933Y555750D01*
Y555917D01*
X838100Y556000D01*
X838267Y555917D01*
Y555750D01*
X838100Y555667D01*
G01X842283Y551000D02*
Y554333D01*
G01Y553500D02*
X842617Y553917D01*
X843117Y554250D01*
X843783Y554333D01*
X844367Y554250D01*
X844867Y553917D01*
X845117Y553333D01*
Y551000D01*
G01X848133Y549750D02*
X848717Y549417D01*
X849383Y549333D01*
X849967Y549417D01*
X850467Y549833D01*
X850800Y550417D01*
Y554333D01*
G01Y553667D02*
X850467Y554000D01*
X849967Y554250D01*
X849383Y554333D01*
X848717Y554167D01*
X848300Y553833D01*
X847967Y553250D01*
X847800Y552667D01*
X847883Y552167D01*
X848217Y551583D01*
X848717Y551167D01*
X849383Y551000D01*
X849883Y551083D01*
X850467Y551417D01*
X850800Y551750D01*
G01X859250Y551583D02*
X859667Y551250D01*
X860250Y551000D01*
X860750D01*
X861250Y551167D01*
X861583Y551417D01*
X861750Y551750D01*
X861667Y552250D01*
X861333Y552500D01*
X859833Y553000D01*
X859500Y553583D01*
X859667Y554000D01*
X860000Y554250D01*
X860500Y554333D01*
X861000Y554250D01*
X861500Y554000D01*
G01X866100Y554333D02*
Y551000D01*
G01Y555667D02*
X865933Y555750D01*
Y555917D01*
X866100Y556000D01*
X866267Y555917D01*
Y555750D01*
X866100Y555667D01*
G01X870450Y554333D02*
X872950D01*
X870450Y551000D01*
X872950D01*
G01X876050Y553250D02*
X878717D01*
X878467Y553833D01*
X878050Y554167D01*
X877467Y554333D01*
X876883Y554250D01*
X876383Y554000D01*
X876050Y553417D01*
X875883Y552917D01*
Y552417D01*
X876050Y551917D01*
X876467Y551417D01*
X876967Y551083D01*
X877550Y551000D01*
X878133Y551167D01*
X878717Y551667D01*
G01X888333Y550083D02*
X888667Y551167D01*
G01X829917Y563333D02*
X830917Y560000D01*
X832000Y563333D01*
X833083Y560000D01*
X834083Y563333D01*
G01X836183Y560000D02*
Y565000D01*
G01Y562583D02*
X836600Y563000D01*
X837017Y563250D01*
X837683Y563333D01*
X838183Y563250D01*
X838767Y562917D01*
X839017Y562417D01*
Y560000D01*
G01X843200Y563333D02*
Y560000D01*
G01Y564667D02*
X843033Y564750D01*
Y564917D01*
X843200Y565000D01*
X843367Y564917D01*
Y564750D01*
X843200Y564667D01*
G01X850133Y562917D02*
X849550Y563250D01*
X849050Y563333D01*
X848383Y563167D01*
X847883Y562833D01*
X847550Y562250D01*
X847467Y561667D01*
X847550Y561083D01*
X847883Y560583D01*
X848383Y560167D01*
X849050Y560000D01*
X849633Y560167D01*
X850133Y560500D01*
G01X852983Y560000D02*
Y565000D01*
G01Y562583D02*
X853400Y563000D01*
X853817Y563250D01*
X854483Y563333D01*
X854983Y563250D01*
X855567Y562917D01*
X855817Y562417D01*
Y560000D01*
G01X864350Y560583D02*
X864767Y560250D01*
X865350Y560000D01*
X865850D01*
X866350Y560167D01*
X866683Y560417D01*
X866850Y560750D01*
X866767Y561250D01*
X866433Y561500D01*
X864933Y562000D01*
X864600Y562583D01*
X864767Y563000D01*
X865100Y563250D01*
X865600Y563333D01*
X866100Y563250D01*
X866600Y563000D01*
G01X871200Y563333D02*
Y560000D01*
G01Y564667D02*
X871033Y564750D01*
Y564917D01*
X871200Y565000D01*
X871367Y564917D01*
Y564750D01*
X871200Y564667D01*
G01X875550Y563333D02*
X878050D01*
X875550Y560000D01*
X878050D01*
G01X881150Y562250D02*
X883817D01*
X883567Y562833D01*
X883150Y563167D01*
X882567Y563333D01*
X881983Y563250D01*
X881483Y563000D01*
X881150Y562417D01*
X880983Y561917D01*
Y561417D01*
X881150Y560917D01*
X881567Y560417D01*
X882067Y560083D01*
X882650Y560000D01*
X883233Y560167D01*
X883817Y560667D01*
G01X893600Y563333D02*
Y560000D01*
G01Y564667D02*
X893433Y564750D01*
Y564917D01*
X893600Y565000D01*
X893767Y564917D01*
Y564750D01*
X893600Y564667D01*
G01X897950Y560583D02*
X898367Y560250D01*
X898950Y560000D01*
X899450D01*
X899950Y560167D01*
X900283Y560417D01*
X900450Y560750D01*
X900367Y561250D01*
X900033Y561500D01*
X898533Y562000D01*
X898200Y562583D01*
X898367Y563000D01*
X898700Y563250D01*
X899200Y563333D01*
X899700Y563250D01*
X900200Y563000D01*
G01X908900Y560000D02*
Y565000D01*
G01Y562500D02*
X909317Y563000D01*
X909817Y563250D01*
X910317Y563333D01*
X911067Y563167D01*
X911567Y562833D01*
X911900Y562250D01*
Y561583D01*
X911733Y560917D01*
X911400Y560417D01*
X910817Y560083D01*
X910317Y560000D01*
X909817Y560083D01*
X909317Y560333D01*
X908900Y560750D01*
G01X916000Y563333D02*
Y560000D01*
G01Y564667D02*
X915833Y564750D01*
Y564917D01*
X916000Y565000D01*
X916167Y564917D01*
Y564750D01*
X916000Y564667D01*
G01X920433Y558750D02*
X921017Y558417D01*
X921683Y558333D01*
X922267Y558417D01*
X922767Y558833D01*
X923100Y559417D01*
Y563333D01*
G01Y562667D02*
X922767Y563000D01*
X922267Y563250D01*
X921683Y563333D01*
X921017Y563167D01*
X920600Y562833D01*
X920267Y562250D01*
X920100Y561667D01*
X920183Y561167D01*
X920517Y560583D01*
X921017Y560167D01*
X921683Y560000D01*
X922183Y560083D01*
X922767Y560417D01*
X923100Y560750D01*
G01X926033Y558750D02*
X926617Y558417D01*
X927283Y558333D01*
X927867Y558417D01*
X928367Y558833D01*
X928700Y559417D01*
Y563333D01*
G01Y562667D02*
X928367Y563000D01*
X927867Y563250D01*
X927283Y563333D01*
X926617Y563167D01*
X926200Y562833D01*
X925867Y562250D01*
X925700Y561667D01*
X925783Y561167D01*
X926117Y560583D01*
X926617Y560167D01*
X927283Y560000D01*
X927783Y560083D01*
X928367Y560417D01*
X928700Y560750D01*
G01X931550Y562250D02*
X934217D01*
X933967Y562833D01*
X933550Y563167D01*
X932967Y563333D01*
X932383Y563250D01*
X931883Y563000D01*
X931550Y562417D01*
X931383Y561917D01*
Y561417D01*
X931550Y560917D01*
X931967Y560417D01*
X932467Y560083D01*
X933050Y560000D01*
X933633Y560167D01*
X934217Y560667D01*
G01X937233Y560000D02*
Y563333D01*
G01Y562667D02*
X937650Y563000D01*
X938067Y563250D01*
X938650Y563333D01*
X939067Y563250D01*
X939567Y563000D01*
G01X949600Y565000D02*
Y560000D01*
G01X948433Y563333D02*
X950767D01*
G01X953783Y560000D02*
Y565000D01*
G01Y562583D02*
X954200Y563000D01*
X954617Y563250D01*
X955283Y563333D01*
X955783Y563250D01*
X956367Y562917D01*
X956617Y562417D01*
Y560000D01*
G01X962300D02*
Y563333D01*
G01Y562750D02*
X961967Y563083D01*
X961467Y563250D01*
X960883Y563333D01*
X960300Y563167D01*
X959800Y562833D01*
X959467Y562333D01*
X959300Y561667D01*
X959467Y561000D01*
X959800Y560500D01*
X960300Y560167D01*
X960883Y560000D01*
X961467Y560083D01*
X961967Y560333D01*
X962300Y560667D01*
G01X964983Y560000D02*
Y563333D01*
G01Y562500D02*
X965317Y562917D01*
X965817Y563250D01*
X966483Y563333D01*
X967067Y563250D01*
X967567Y562917D01*
X967817Y562333D01*
Y560000D01*
G01X979100D02*
Y563333D01*
G01Y562750D02*
X978767Y563083D01*
X978267Y563250D01*
X977683Y563333D01*
X977100Y563167D01*
X976600Y562833D01*
X976267Y562333D01*
X976100Y561667D01*
X976267Y561000D01*
X976600Y560500D01*
X977100Y560167D01*
X977683Y560000D01*
X978267Y560083D01*
X978767Y560333D01*
X979100Y560667D01*
G01X981783Y560000D02*
Y563333D01*
G01Y562500D02*
X982117Y562917D01*
X982617Y563250D01*
X983283Y563333D01*
X983867Y563250D01*
X984367Y562917D01*
X984617Y562333D01*
Y560000D01*
G01X987383D02*
Y563333D01*
G01Y562500D02*
X987717Y562917D01*
X988217Y563250D01*
X988883Y563333D01*
X989467Y563250D01*
X989967Y562917D01*
X990217Y562333D01*
Y560000D01*
G01X992983Y563333D02*
Y561000D01*
X993317Y560417D01*
X993817Y560083D01*
X994400Y560000D01*
X994983Y560083D01*
X995483Y560417D01*
X995817Y561000D01*
G01Y560000D02*
Y563333D01*
G01X1001500Y560000D02*
Y563333D01*
G01Y562750D02*
X1001167Y563083D01*
X1000667Y563250D01*
X1000083Y563333D01*
X999500Y563167D01*
X999000Y562833D01*
X998667Y562333D01*
X998500Y561667D01*
X998667Y561000D01*
X999000Y560500D01*
X999500Y560167D01*
X1000083Y560000D01*
X1000667Y560083D01*
X1001167Y560333D01*
X1001500Y560667D01*
G01X1005600Y560000D02*
Y565000D01*
G01X822000Y569000D02*
Y574000D01*
X821000Y573000D01*
G01Y569000D02*
X823000D01*
G01X827600Y568833D02*
X827433Y568917D01*
Y569083D01*
X827600Y569167D01*
X827767Y569083D01*
Y568917D01*
X827600Y568833D01*
G01X833200Y569000D02*
X832533Y569083D01*
X831950Y569417D01*
X831450Y569917D01*
X831117Y570500D01*
X830950Y571167D01*
Y571833D01*
X831117Y572500D01*
X831450Y573083D01*
X831950Y573583D01*
X832533Y573917D01*
X833200Y574000D01*
X833867Y573917D01*
X834450Y573583D01*
X834950Y573083D01*
X835283Y572500D01*
X835450Y571833D01*
Y571167D01*
X835283Y570500D01*
X834950Y569917D01*
X834450Y569417D01*
X833867Y569083D01*
X833200Y569000D01*
G01X837383D02*
Y572333D01*
G01Y571500D02*
X837717Y571917D01*
X838217Y572250D01*
X838883Y572333D01*
X839467Y572250D01*
X839967Y571917D01*
X840217Y571333D01*
Y569000D01*
G01X843150Y571250D02*
X845817D01*
X845567Y571833D01*
X845150Y572167D01*
X844567Y572333D01*
X843983Y572250D01*
X843483Y572000D01*
X843150Y571417D01*
X842983Y570917D01*
Y570417D01*
X843150Y569917D01*
X843567Y569417D01*
X844067Y569083D01*
X844650Y569000D01*
X845233Y569167D01*
X845817Y569667D01*
G01X854350Y569583D02*
X854767Y569250D01*
X855350Y569000D01*
X855850D01*
X856350Y569167D01*
X856683Y569417D01*
X856850Y569750D01*
X856767Y570250D01*
X856433Y570500D01*
X854933Y571000D01*
X854600Y571583D01*
X854767Y572000D01*
X855100Y572250D01*
X855600Y572333D01*
X856100Y572250D01*
X856600Y572000D01*
G01X861200Y572333D02*
Y569000D01*
G01Y573667D02*
X861033Y573750D01*
Y573917D01*
X861200Y574000D01*
X861367Y573917D01*
Y573750D01*
X861200Y573667D01*
G01X868300Y574000D02*
Y569000D01*
G01Y569750D02*
X867967Y569333D01*
X867467Y569083D01*
X866883Y569000D01*
X866217Y569167D01*
X865717Y569583D01*
X865383Y570083D01*
X865300Y570667D01*
X865383Y571250D01*
X865717Y571750D01*
X866217Y572167D01*
X866883Y572333D01*
X867467Y572250D01*
X867883Y572083D01*
X868300Y571750D01*
G01X871150Y571250D02*
X873817D01*
X873567Y571833D01*
X873150Y572167D01*
X872567Y572333D01*
X871983Y572250D01*
X871483Y572000D01*
X871150Y571417D01*
X870983Y570917D01*
Y570417D01*
X871150Y569917D01*
X871567Y569417D01*
X872067Y569083D01*
X872650Y569000D01*
X873233Y569167D01*
X873817Y569667D01*
G01X881517Y572333D02*
X882517Y569000D01*
X883600Y572333D01*
X884683Y569000D01*
X885683Y572333D01*
G01X889200D02*
Y569000D01*
G01Y573667D02*
X889033Y573750D01*
Y573917D01*
X889200Y574000D01*
X889367Y573917D01*
Y573750D01*
X889200Y573667D01*
G01X894800Y574000D02*
Y569000D01*
G01X893633Y572333D02*
X895967D01*
G01X898983Y569000D02*
Y574000D01*
G01Y571583D02*
X899400Y572000D01*
X899817Y572250D01*
X900483Y572333D01*
X900983Y572250D01*
X901567Y571917D01*
X901817Y571417D01*
Y569000D01*
G01X910350Y569583D02*
X910767Y569250D01*
X911350Y569000D01*
X911850D01*
X912350Y569167D01*
X912683Y569417D01*
X912850Y569750D01*
X912767Y570250D01*
X912433Y570500D01*
X910933Y571000D01*
X910600Y571583D01*
X910767Y572000D01*
X911100Y572250D01*
X911600Y572333D01*
X912100Y572250D01*
X912600Y572000D01*
G01X917200Y569000D02*
X916700Y569083D01*
X916200Y569417D01*
X915867Y570000D01*
X915700Y570667D01*
X915867Y571333D01*
X916200Y571917D01*
X916700Y572250D01*
X917200Y572333D01*
X917700Y572250D01*
X918200Y571917D01*
X918533Y571333D01*
X918617Y570667D01*
X918533Y570000D01*
X918200Y569417D01*
X917700Y569083D01*
X917200Y569000D01*
G01X922800D02*
Y574000D01*
G01X929900D02*
Y569000D01*
G01Y569750D02*
X929567Y569333D01*
X929067Y569083D01*
X928483Y569000D01*
X927817Y569167D01*
X927317Y569583D01*
X926983Y570083D01*
X926900Y570667D01*
X926983Y571250D01*
X927317Y571750D01*
X927817Y572167D01*
X928483Y572333D01*
X929067Y572250D01*
X929483Y572083D01*
X929900Y571750D01*
G01X932750Y571250D02*
X935417D01*
X935167Y571833D01*
X934750Y572167D01*
X934167Y572333D01*
X933583Y572250D01*
X933083Y572000D01*
X932750Y571417D01*
X932583Y570917D01*
Y570417D01*
X932750Y569917D01*
X933167Y569417D01*
X933667Y569083D01*
X934250Y569000D01*
X934833Y569167D01*
X935417Y569667D01*
G01X938433Y569000D02*
Y572333D01*
G01Y571667D02*
X938850Y572000D01*
X939267Y572250D01*
X939850Y572333D01*
X940267Y572250D01*
X940767Y572000D01*
G01X948300Y569000D02*
Y572333D01*
G01Y571417D02*
X948550Y571833D01*
X948967Y572167D01*
X949550Y572333D01*
X950133Y572167D01*
X950550Y571833D01*
X950800Y571417D01*
Y569000D01*
G01Y571417D02*
X951050Y571833D01*
X951467Y572167D01*
X952050Y572333D01*
X952633Y572167D01*
X953050Y571833D01*
X953300Y571333D01*
Y569000D01*
G01X957900D02*
Y572333D01*
G01Y571750D02*
X957567Y572083D01*
X957067Y572250D01*
X956483Y572333D01*
X955900Y572167D01*
X955400Y571833D01*
X955067Y571333D01*
X954900Y570667D01*
X955067Y570000D01*
X955400Y569500D01*
X955900Y569167D01*
X956483Y569000D01*
X957067Y569083D01*
X957567Y569333D01*
X957900Y569667D01*
G01X960750Y569583D02*
X961167Y569250D01*
X961750Y569000D01*
X962250D01*
X962750Y569167D01*
X963083Y569417D01*
X963250Y569750D01*
X963167Y570250D01*
X962833Y570500D01*
X961333Y571000D01*
X961000Y571583D01*
X961167Y572000D01*
X961500Y572250D01*
X962000Y572333D01*
X962500Y572250D01*
X963000Y572000D01*
G01X966183Y569000D02*
Y574000D01*
G01X968850Y572333D02*
X966183Y570417D01*
G01X967267Y571167D02*
X969017Y569000D01*
G01X977300Y567333D02*
Y572333D01*
G01Y571583D02*
X977717Y572000D01*
X978133Y572250D01*
X978800Y572333D01*
X979383Y572250D01*
X979967Y571833D01*
X980217Y571250D01*
X980300Y570667D01*
X980217Y570083D01*
X979967Y569500D01*
X979467Y569167D01*
X978800Y569000D01*
X978217Y569083D01*
X977633Y569333D01*
X977300Y569667D01*
G01X985900Y569000D02*
Y572333D01*
G01Y571750D02*
X985567Y572083D01*
X985067Y572250D01*
X984483Y572333D01*
X983900Y572167D01*
X983400Y571833D01*
X983067Y571333D01*
X982900Y570667D01*
X983067Y570000D01*
X983400Y569500D01*
X983900Y569167D01*
X984483Y569000D01*
X985067Y569083D01*
X985567Y569333D01*
X985900Y569667D01*
G01X991500Y574000D02*
Y569000D01*
G01Y569750D02*
X991167Y569333D01*
X990667Y569083D01*
X990083Y569000D01*
X989417Y569167D01*
X988917Y569583D01*
X988583Y570083D01*
X988500Y570667D01*
X988583Y571250D01*
X988917Y571750D01*
X989417Y572167D01*
X990083Y572333D01*
X990667Y572250D01*
X991083Y572083D01*
X991500Y571750D01*
G01X794500Y674500D02*
Y669500D01*
G01X793333Y672833D02*
X795667D01*
G01X798683Y669500D02*
Y674500D01*
G01Y672083D02*
X799100Y672500D01*
X799517Y672750D01*
X800183Y672833D01*
X800683Y672750D01*
X801267Y672417D01*
X801517Y671917D01*
Y669500D01*
G01X805700Y672833D02*
Y669500D01*
G01Y674167D02*
X805533Y674250D01*
Y674417D01*
X805700Y674500D01*
X805867Y674417D01*
Y674250D01*
X805700Y674167D01*
G01X812633Y672417D02*
X812050Y672750D01*
X811550Y672833D01*
X810883Y672667D01*
X810383Y672333D01*
X810050Y671750D01*
X809967Y671167D01*
X810050Y670583D01*
X810383Y670083D01*
X810883Y669667D01*
X811550Y669500D01*
X812133Y669667D01*
X812633Y670000D01*
G01X815483Y669500D02*
Y674500D01*
G01X818150Y672833D02*
X815483Y670917D01*
G01X816567Y671667D02*
X818317Y669500D01*
G01X821083D02*
Y672833D01*
G01Y672000D02*
X821417Y672417D01*
X821917Y672750D01*
X822583Y672833D01*
X823167Y672750D01*
X823667Y672417D01*
X823917Y671833D01*
Y669500D01*
G01X826850Y671750D02*
X829517D01*
X829267Y672333D01*
X828850Y672667D01*
X828267Y672833D01*
X827683Y672750D01*
X827183Y672500D01*
X826850Y671917D01*
X826683Y671417D01*
Y670917D01*
X826850Y670417D01*
X827267Y669917D01*
X827767Y669583D01*
X828350Y669500D01*
X828933Y669667D01*
X829517Y670167D01*
G01X832450Y670083D02*
X832867Y669750D01*
X833450Y669500D01*
X833950D01*
X834450Y669667D01*
X834783Y669917D01*
X834950Y670250D01*
X834867Y670750D01*
X834533Y671000D01*
X833033Y671500D01*
X832700Y672083D01*
X832867Y672500D01*
X833200Y672750D01*
X833700Y672833D01*
X834200Y672750D01*
X834700Y672500D01*
G01X838050Y670083D02*
X838467Y669750D01*
X839050Y669500D01*
X839550D01*
X840050Y669667D01*
X840383Y669917D01*
X840550Y670250D01*
X840467Y670750D01*
X840133Y671000D01*
X838633Y671500D01*
X838300Y672083D01*
X838467Y672500D01*
X838800Y672750D01*
X839300Y672833D01*
X839800Y672750D01*
X840300Y672500D01*
G01X809000Y686500D02*
Y691500D01*
G01Y689000D02*
X809417Y689500D01*
X809917Y689750D01*
X810417Y689833D01*
X811167Y689667D01*
X811667Y689333D01*
X812000Y688750D01*
Y688083D01*
X811833Y687417D01*
X811500Y686917D01*
X810917Y686583D01*
X810417Y686500D01*
X809917Y686583D01*
X809417Y686833D01*
X809000Y687250D01*
G01X816100Y686500D02*
X815600Y686583D01*
X815100Y686917D01*
X814767Y687500D01*
X814600Y688167D01*
X814767Y688833D01*
X815100Y689417D01*
X815600Y689750D01*
X816100Y689833D01*
X816600Y689750D01*
X817100Y689417D01*
X817433Y688833D01*
X817517Y688167D01*
X817433Y687500D01*
X817100Y686917D01*
X816600Y686583D01*
X816100Y686500D01*
G01X823200D02*
Y689833D01*
G01Y689250D02*
X822867Y689583D01*
X822367Y689750D01*
X821783Y689833D01*
X821200Y689667D01*
X820700Y689333D01*
X820367Y688833D01*
X820200Y688167D01*
X820367Y687500D01*
X820700Y687000D01*
X821200Y686667D01*
X821783Y686500D01*
X822367Y686583D01*
X822867Y686833D01*
X823200Y687167D01*
G01X826133Y686500D02*
Y689833D01*
G01Y689167D02*
X826550Y689500D01*
X826967Y689750D01*
X827550Y689833D01*
X827967Y689750D01*
X828467Y689500D01*
G01X834400Y691500D02*
Y686500D01*
G01Y687250D02*
X834067Y686833D01*
X833567Y686583D01*
X832983Y686500D01*
X832317Y686667D01*
X831817Y687083D01*
X831483Y687583D01*
X831400Y688167D01*
X831483Y688750D01*
X831817Y689250D01*
X832317Y689667D01*
X832983Y689833D01*
X833567Y689750D01*
X833983Y689583D01*
X834400Y689250D01*
G01X798500Y795500D02*
Y790500D01*
G01X796583Y795500D02*
X800417D01*
G01X802017Y793833D02*
X803017Y790500D01*
X804100Y793833D01*
X805183Y790500D01*
X806183Y793833D01*
G01X809700D02*
Y790500D01*
G01Y795167D02*
X809533Y795250D01*
Y795417D01*
X809700Y795500D01*
X809867Y795417D01*
Y795250D01*
X809700Y795167D01*
G01X814050Y791083D02*
X814467Y790750D01*
X815050Y790500D01*
X815550D01*
X816050Y790667D01*
X816383Y790917D01*
X816550Y791250D01*
X816467Y791750D01*
X816133Y792000D01*
X814633Y792500D01*
X814300Y793083D01*
X814467Y793500D01*
X814800Y793750D01*
X815300Y793833D01*
X815800Y793750D01*
X816300Y793500D01*
G01X820900Y795500D02*
Y790500D01*
G01X819733Y793833D02*
X822067D01*
G01X833600Y790500D02*
Y793833D01*
G01Y793250D02*
X833267Y793583D01*
X832767Y793750D01*
X832183Y793833D01*
X831600Y793667D01*
X831100Y793333D01*
X830767Y792833D01*
X830600Y792167D01*
X830767Y791500D01*
X831100Y791000D01*
X831600Y790667D01*
X832183Y790500D01*
X832767Y790583D01*
X833267Y790833D01*
X833600Y791167D01*
G01X836283Y790500D02*
Y793833D01*
G01Y793000D02*
X836617Y793417D01*
X837117Y793750D01*
X837783Y793833D01*
X838367Y793750D01*
X838867Y793417D01*
X839117Y792833D01*
Y790500D01*
G01X844800Y795500D02*
Y790500D01*
G01Y791250D02*
X844467Y790833D01*
X843967Y790583D01*
X843383Y790500D01*
X842717Y790667D01*
X842217Y791083D01*
X841883Y791583D01*
X841800Y792167D01*
X841883Y792750D01*
X842217Y793250D01*
X842717Y793667D01*
X843383Y793833D01*
X843967Y793750D01*
X844383Y793583D01*
X844800Y793250D01*
G01X853000Y790500D02*
Y795500D01*
G01Y793000D02*
X853417Y793500D01*
X853917Y793750D01*
X854417Y793833D01*
X855167Y793667D01*
X855667Y793333D01*
X856000Y792750D01*
Y792083D01*
X855833Y791417D01*
X855500Y790917D01*
X854917Y790583D01*
X854417Y790500D01*
X853917Y790583D01*
X853417Y790833D01*
X853000Y791250D01*
G01X860100Y790500D02*
X859600Y790583D01*
X859100Y790917D01*
X858767Y791500D01*
X858600Y792167D01*
X858767Y792833D01*
X859100Y793417D01*
X859600Y793750D01*
X860100Y793833D01*
X860600Y793750D01*
X861100Y793417D01*
X861433Y792833D01*
X861517Y792167D01*
X861433Y791500D01*
X861100Y790917D01*
X860600Y790583D01*
X860100Y790500D01*
G01X863617Y793833D02*
X864617Y790500D01*
X865700Y793833D01*
X866783Y790500D01*
X867783Y793833D01*
G01X796833Y826500D02*
Y831500D01*
X798917D01*
X799583Y831250D01*
X800000Y830917D01*
X800167Y830250D01*
X800000Y829583D01*
X799500Y829167D01*
X798917Y828917D01*
X796833D01*
G01X798917D02*
X800167Y826500D01*
G01X804100D02*
X803600Y826583D01*
X803100Y826917D01*
X802767Y827500D01*
X802600Y828167D01*
X802767Y828833D01*
X803100Y829417D01*
X803600Y829750D01*
X804100Y829833D01*
X804600Y829750D01*
X805100Y829417D01*
X805433Y828833D01*
X805517Y828167D01*
X805433Y827500D01*
X805100Y826917D01*
X804600Y826583D01*
X804100Y826500D01*
G01X808283Y829833D02*
Y827500D01*
X808617Y826917D01*
X809117Y826583D01*
X809700Y826500D01*
X810283Y826583D01*
X810783Y826917D01*
X811117Y827500D01*
G01Y826500D02*
Y829833D01*
G01X815300Y831500D02*
Y826500D01*
G01X814133Y829833D02*
X816467D01*
G01X820900D02*
Y826500D01*
G01Y831167D02*
X820733Y831250D01*
Y831417D01*
X820900Y831500D01*
X821067Y831417D01*
Y831250D01*
X820900Y831167D01*
G01X825083Y826500D02*
Y829833D01*
G01Y829000D02*
X825417Y829417D01*
X825917Y829750D01*
X826583Y829833D01*
X827167Y829750D01*
X827667Y829417D01*
X827917Y828833D01*
Y826500D01*
G01X830933Y825250D02*
X831517Y824917D01*
X832183Y824833D01*
X832767Y824917D01*
X833267Y825333D01*
X833600Y825917D01*
Y829833D01*
G01Y829167D02*
X833267Y829500D01*
X832767Y829750D01*
X832183Y829833D01*
X831517Y829667D01*
X831100Y829333D01*
X830767Y828750D01*
X830600Y828167D01*
X830683Y827667D01*
X831017Y827083D01*
X831517Y826667D01*
X832183Y826500D01*
X832683Y826583D01*
X833267Y826917D01*
X833600Y827250D01*
G01X843300Y831500D02*
Y826500D01*
G01X842133Y829833D02*
X844467D01*
G01X848900Y826500D02*
X848400Y826583D01*
X847900Y826917D01*
X847567Y827500D01*
X847400Y828167D01*
X847567Y828833D01*
X847900Y829417D01*
X848400Y829750D01*
X848900Y829833D01*
X849400Y829750D01*
X849900Y829417D01*
X850233Y828833D01*
X850317Y828167D01*
X850233Y827500D01*
X849900Y826917D01*
X849400Y826583D01*
X848900Y826500D01*
G01X854500D02*
Y831500D01*
G01X858850Y828750D02*
X861517D01*
X861267Y829333D01*
X860850Y829667D01*
X860267Y829833D01*
X859683Y829750D01*
X859183Y829500D01*
X858850Y828917D01*
X858683Y828417D01*
Y827917D01*
X858850Y827417D01*
X859267Y826917D01*
X859767Y826583D01*
X860350Y826500D01*
X860933Y826667D01*
X861517Y827167D01*
G01X864533Y826500D02*
Y829833D01*
G01Y829167D02*
X864950Y829500D01*
X865367Y829750D01*
X865950Y829833D01*
X866367Y829750D01*
X866867Y829500D01*
G01X872800Y826500D02*
Y829833D01*
G01Y829250D02*
X872467Y829583D01*
X871967Y829750D01*
X871383Y829833D01*
X870800Y829667D01*
X870300Y829333D01*
X869967Y828833D01*
X869800Y828167D01*
X869967Y827500D01*
X870300Y827000D01*
X870800Y826667D01*
X871383Y826500D01*
X871967Y826583D01*
X872467Y826833D01*
X872800Y827167D01*
G01X875483Y826500D02*
Y829833D01*
G01Y829000D02*
X875817Y829417D01*
X876317Y829750D01*
X876983Y829833D01*
X877567Y829750D01*
X878067Y829417D01*
X878317Y828833D01*
Y826500D01*
G01X883833Y829417D02*
X883250Y829750D01*
X882750Y829833D01*
X882083Y829667D01*
X881583Y829333D01*
X881250Y828750D01*
X881167Y828167D01*
X881250Y827583D01*
X881583Y827083D01*
X882083Y826667D01*
X882750Y826500D01*
X883333Y826667D01*
X883833Y827000D01*
G01X886850Y828750D02*
X889517D01*
X889267Y829333D01*
X888850Y829667D01*
X888267Y829833D01*
X887683Y829750D01*
X887183Y829500D01*
X886850Y828917D01*
X886683Y828417D01*
Y827917D01*
X886850Y827417D01*
X887267Y826917D01*
X887767Y826583D01*
X888350Y826500D01*
X888933Y826667D01*
X889517Y827167D01*
G01X788000Y850610D02*
Y782110D01*
G01Y805500D02*
X1343000D01*
G01X909000Y67500D02*
Y72500D01*
X905917Y68917D01*
X910083D01*
G01X911767Y68250D02*
X912267Y67833D01*
X912850Y67583D01*
X913600Y67500D01*
X914350Y67667D01*
X914933Y68000D01*
X915350Y68583D01*
X915433Y69250D01*
X915267Y69917D01*
X914850Y70333D01*
X914267Y70667D01*
X913683Y70750D01*
X913100Y70667D01*
X912350Y70333D01*
X912600Y72500D01*
X914850D01*
G01X909250Y184083D02*
X909667Y183750D01*
X910250Y183500D01*
X910750D01*
X911250Y183667D01*
X911583Y183917D01*
X911750Y184250D01*
X911667Y184750D01*
X911333Y185000D01*
X909833Y185500D01*
X909500Y186083D01*
X909667Y186500D01*
X910000Y186750D01*
X910500Y186833D01*
X911000Y186750D01*
X911500Y186500D01*
G01X916100Y188500D02*
Y183500D01*
G01X914933Y186833D02*
X917267D01*
G01X920283D02*
Y184500D01*
X920617Y183917D01*
X921117Y183583D01*
X921700Y183500D01*
X922283Y183583D01*
X922783Y183917D01*
X923117Y184500D01*
G01Y183500D02*
Y186833D01*
G01X925800Y183500D02*
Y188500D01*
G01Y186000D02*
X926217Y186500D01*
X926717Y186750D01*
X927217Y186833D01*
X927967Y186667D01*
X928467Y186333D01*
X928800Y185750D01*
Y185083D01*
X928633Y184417D01*
X928300Y183917D01*
X927717Y183583D01*
X927217Y183500D01*
X926717Y183583D01*
X926217Y183833D01*
X925800Y184250D01*
G01X938500Y183500D02*
Y188500D01*
G01X942850Y185750D02*
X945517D01*
X945267Y186333D01*
X944850Y186667D01*
X944267Y186833D01*
X943683Y186750D01*
X943183Y186500D01*
X942850Y185917D01*
X942683Y185417D01*
Y184917D01*
X942850Y184417D01*
X943267Y183917D01*
X943767Y183583D01*
X944350Y183500D01*
X944933Y183667D01*
X945517Y184167D01*
G01X948283Y183500D02*
Y186833D01*
G01Y186000D02*
X948617Y186417D01*
X949117Y186750D01*
X949783Y186833D01*
X950367Y186750D01*
X950867Y186417D01*
X951117Y185833D01*
Y183500D01*
G01X954133Y182250D02*
X954717Y181917D01*
X955383Y181833D01*
X955967Y181917D01*
X956467Y182333D01*
X956800Y182917D01*
Y186833D01*
G01Y186167D02*
X956467Y186500D01*
X955967Y186750D01*
X955383Y186833D01*
X954717Y186667D01*
X954300Y186333D01*
X953967Y185750D01*
X953800Y185167D01*
X953883Y184667D01*
X954217Y184083D01*
X954717Y183667D01*
X955383Y183500D01*
X955883Y183583D01*
X956467Y183917D01*
X956800Y184250D01*
G01X960900Y188500D02*
Y183500D01*
G01X959733Y186833D02*
X962067D01*
G01X965083Y183500D02*
Y188500D01*
G01Y186083D02*
X965500Y186500D01*
X965917Y186750D01*
X966583Y186833D01*
X967083Y186750D01*
X967667Y186417D01*
X967917Y185917D01*
Y183500D01*
G01X971017Y184417D02*
X973183D01*
G01Y185917D02*
X971017D01*
G01X976117Y185583D02*
X976700Y186167D01*
X977200Y186500D01*
X977867Y186667D01*
X978450Y186500D01*
X978867Y186167D01*
X979200Y185667D01*
X979283Y185083D01*
X979200Y184583D01*
X978867Y184083D01*
X978367Y183667D01*
X977783Y183500D01*
X977117Y183667D01*
X976533Y184167D01*
X976200Y184917D01*
X976117Y185750D01*
X976283Y186833D01*
X976533Y187417D01*
X976950Y188000D01*
X977533Y188417D01*
X978117Y188500D01*
X978700Y188333D01*
X979117Y187917D01*
G01X982383Y185167D02*
X984383D01*
G01X983300Y186250D02*
Y184083D01*
G01X987400Y183333D02*
X990400Y188500D01*
G01X993417Y185167D02*
X995583D01*
G01X998267Y184250D02*
X998767Y183833D01*
X999350Y183583D01*
X1000100Y183500D01*
X1000850Y183667D01*
X1001433Y184000D01*
X1001850Y184583D01*
X1001933Y185250D01*
X1001767Y185917D01*
X1001350Y186333D01*
X1000767Y186667D01*
X1000183Y186750D01*
X999600Y186667D01*
X998850Y186333D01*
X999100Y188500D01*
X1001350D01*
G01X1003200Y183500D02*
Y186833D01*
G01Y185917D02*
X1003450Y186333D01*
X1003867Y186667D01*
X1004450Y186833D01*
X1005033Y186667D01*
X1005450Y186333D01*
X1005700Y185917D01*
Y183500D01*
G01Y185917D02*
X1005950Y186333D01*
X1006367Y186667D01*
X1006950Y186833D01*
X1007533Y186667D01*
X1007950Y186333D01*
X1008200Y185833D01*
Y183500D01*
G01X1011300Y186833D02*
Y183500D01*
G01Y188167D02*
X1011133Y188250D01*
Y188417D01*
X1011300Y188500D01*
X1011467Y188417D01*
Y188250D01*
X1011300Y188167D01*
G01X1016900Y183500D02*
Y188500D01*
G01X868250Y152000D02*
Y157000D01*
G01X871750D02*
Y152000D01*
G01Y154500D02*
X868250D01*
G01X875600Y152000D02*
X874933Y152083D01*
X874350Y152417D01*
X873850Y152917D01*
X873517Y153500D01*
X873350Y154167D01*
Y154833D01*
X873517Y155500D01*
X873850Y156083D01*
X874350Y156583D01*
X874933Y156917D01*
X875600Y157000D01*
X876267Y156917D01*
X876850Y156583D01*
X877350Y156083D01*
X877683Y155500D01*
X877850Y154833D01*
Y154167D01*
X877683Y153500D01*
X877350Y152917D01*
X876850Y152417D01*
X876267Y152083D01*
X875600Y152000D01*
G01X879533Y157000D02*
Y152000D01*
X882867D01*
G01X888467D02*
X885133D01*
Y157000D01*
X888467D01*
G01X887133Y154583D02*
X885133D01*
G01X912300Y152000D02*
Y155333D01*
G01Y154417D02*
X912550Y154833D01*
X912967Y155167D01*
X913550Y155333D01*
X914133Y155167D01*
X914550Y154833D01*
X914800Y154417D01*
Y152000D01*
G01Y154417D02*
X915050Y154833D01*
X915467Y155167D01*
X916050Y155333D01*
X916633Y155167D01*
X917050Y154833D01*
X917300Y154333D01*
Y152000D01*
G01X920400Y155333D02*
Y152000D01*
G01Y156667D02*
X920233Y156750D01*
Y156917D01*
X920400Y157000D01*
X920567Y156917D01*
Y156750D01*
X920400Y156667D01*
G01X926000Y152000D02*
Y157000D01*
G01X930350Y152583D02*
X930767Y152250D01*
X931350Y152000D01*
X931850D01*
X932350Y152167D01*
X932683Y152417D01*
X932850Y152750D01*
X932767Y153250D01*
X932433Y153500D01*
X930933Y154000D01*
X930600Y154583D01*
X930767Y155000D01*
X931100Y155250D01*
X931600Y155333D01*
X932100Y155250D01*
X932600Y155000D01*
G01X936783Y150333D02*
X935950Y151167D01*
X935533Y152000D01*
Y155333D01*
X935950Y156167D01*
X936783Y157000D01*
G01X941133Y152000D02*
Y157000D01*
X943133D01*
X943800Y156750D01*
X944300Y156167D01*
X944467Y155500D01*
X944300Y154833D01*
X943883Y154333D01*
X943133Y154083D01*
X941133D01*
G01X948400Y157000D02*
Y152000D01*
G01X946483Y157000D02*
X950317D01*
G01X952250Y152000D02*
Y157000D01*
G01X955750D02*
Y152000D01*
G01Y154500D02*
X952250D01*
G01X960017Y150333D02*
X960850Y151167D01*
X961267Y152000D01*
Y155333D01*
X960850Y156167D01*
X960017Y157000D01*
G01X900833Y214500D02*
Y209500D01*
X904167D01*
G01X906683D02*
Y212833D01*
G01Y212000D02*
X907017Y212417D01*
X907517Y212750D01*
X908183Y212833D01*
X908767Y212750D01*
X909267Y212417D01*
X909517Y211833D01*
Y209500D01*
G01X902833Y255500D02*
Y250500D01*
X906167D01*
G01X908850Y253833D02*
X911350Y250500D01*
G01Y253833D02*
X908850Y250500D01*
G01X868167Y308167D02*
X868500Y308417D01*
X868750Y308833D01*
X868917Y309417D01*
X868750Y309917D01*
X868417Y310250D01*
X867833Y310500D01*
X865583D01*
Y305500D01*
X868333D01*
X868917Y305833D01*
X869250Y306333D01*
X869417Y306917D01*
X869250Y307500D01*
X868750Y308000D01*
X868167Y308167D01*
X865583D01*
G01X871017Y305500D02*
X873100Y310500D01*
X875183Y305500D01*
G01X874433Y307250D02*
X871767D01*
G01X880533Y310083D02*
X880033Y310333D01*
X879450Y310500D01*
X878783D01*
X878033Y310250D01*
X877450Y309833D01*
X877033Y309333D01*
X876700Y308500D01*
X876617Y307750D01*
X876783Y307000D01*
X877033Y306500D01*
X877533Y306000D01*
X878117Y305667D01*
X878700Y305500D01*
X879283D01*
X879867Y305667D01*
X880367Y305917D01*
X880783Y306250D01*
G01X882467Y305500D02*
Y310500D01*
G01X885633D02*
X882467Y307417D01*
G01X886133Y305500D02*
X883883Y308833D01*
G01X893667Y305500D02*
Y310500D01*
X895333D01*
X896000Y310250D01*
X896500Y309917D01*
X896917Y309417D01*
X897250Y308833D01*
X897333Y308000D01*
X897250Y307167D01*
X896917Y306583D01*
X896500Y306083D01*
X896000Y305750D01*
X895333Y305500D01*
X893667D01*
G01X899433D02*
Y310500D01*
X901517D01*
X902183Y310250D01*
X902600Y309917D01*
X902767Y309250D01*
X902600Y308583D01*
X902100Y308167D01*
X901517Y307917D01*
X899433D01*
G01X901517D02*
X902767Y305500D01*
G01X905700Y310500D02*
X907700D01*
G01X906700D02*
Y305500D01*
G01X905700D02*
X907700D01*
G01X910633Y310500D02*
Y305500D01*
X913967D01*
G01X916233Y310500D02*
Y305500D01*
X919567D01*
G01X943400D02*
Y308833D01*
G01Y307917D02*
X943650Y308333D01*
X944067Y308667D01*
X944650Y308833D01*
X945233Y308667D01*
X945650Y308333D01*
X945900Y307917D01*
Y305500D01*
G01Y307917D02*
X946150Y308333D01*
X946567Y308667D01*
X947150Y308833D01*
X947733Y308667D01*
X948150Y308333D01*
X948400Y307833D01*
Y305500D01*
G01X951500Y308833D02*
Y305500D01*
G01Y310167D02*
X951333Y310250D01*
Y310417D01*
X951500Y310500D01*
X951667Y310417D01*
Y310250D01*
X951500Y310167D01*
G01X957100Y305500D02*
Y310500D01*
G01X961450Y306083D02*
X961867Y305750D01*
X962450Y305500D01*
X962950D01*
X963450Y305667D01*
X963783Y305917D01*
X963950Y306250D01*
X963867Y306750D01*
X963533Y307000D01*
X962033Y307500D01*
X961700Y308083D01*
X961867Y308500D01*
X962200Y308750D01*
X962700Y308833D01*
X963200Y308750D01*
X963700Y308500D01*
G01X967883Y303833D02*
X967050Y304667D01*
X966633Y305500D01*
Y308833D01*
X967050Y309667D01*
X967883Y310500D01*
G01X971983Y305500D02*
Y310500D01*
X975817Y305500D01*
Y310500D01*
G01X977833Y305500D02*
Y310500D01*
X979833D01*
X980500Y310250D01*
X981000Y309667D01*
X981167Y309000D01*
X981000Y308333D01*
X980583Y307833D01*
X979833Y307583D01*
X977833D01*
G01X985100Y310500D02*
Y305500D01*
G01X983183Y310500D02*
X987017D01*
G01X988950Y305500D02*
Y310500D01*
G01X992450D02*
Y305500D01*
G01Y308000D02*
X988950D01*
G01X996717Y303833D02*
X997550Y304667D01*
X997967Y305500D01*
Y308833D01*
X997550Y309667D01*
X996717Y310500D01*
G01X889267Y349073D02*
X892933Y352740D01*
G01X891100Y353407D02*
Y348407D01*
G01X892933Y349073D02*
X889267Y352740D01*
G01X888600Y350907D02*
X893600D01*
G01X896283Y347573D02*
X895450Y348407D01*
X895033Y349240D01*
Y352573D01*
X895450Y353407D01*
X896283Y354240D01*
G01X900467Y349990D02*
X900967Y349573D01*
X901550Y349323D01*
X902300Y349240D01*
X903050Y349407D01*
X903633Y349740D01*
X904050Y350323D01*
X904133Y350990D01*
X903967Y351657D01*
X903550Y352073D01*
X902967Y352407D01*
X902383Y352490D01*
X901800Y352407D01*
X901050Y352073D01*
X901300Y354240D01*
X903550D01*
G01X907900Y349073D02*
X907733Y349157D01*
Y349323D01*
X907900Y349407D01*
X908067Y349323D01*
Y349157D01*
X907900Y349073D01*
G01X913500Y349240D02*
Y354240D01*
X912500Y353240D01*
G01Y349240D02*
X914500D01*
G01X919517Y347573D02*
X920350Y348407D01*
X920767Y349240D01*
Y352573D01*
X920350Y353407D01*
X919517Y354240D01*
G01X894000Y556000D02*
Y551000D01*
G01X892833Y554333D02*
X895167D01*
G01X898183Y551000D02*
Y556000D01*
G01Y553583D02*
X898600Y554000D01*
X899017Y554250D01*
X899683Y554333D01*
X900183Y554250D01*
X900767Y553917D01*
X901017Y553417D01*
Y551000D01*
G01X903950Y553250D02*
X906617D01*
X906367Y553833D01*
X905950Y554167D01*
X905367Y554333D01*
X904783Y554250D01*
X904283Y554000D01*
X903950Y553417D01*
X903783Y552917D01*
Y552417D01*
X903950Y551917D01*
X904367Y551417D01*
X904867Y551083D01*
X905450Y551000D01*
X906033Y551167D01*
X906617Y551667D01*
G01X916400Y551000D02*
X915900Y551083D01*
X915400Y551417D01*
X915067Y552000D01*
X914900Y552667D01*
X915067Y553333D01*
X915400Y553917D01*
X915900Y554250D01*
X916400Y554333D01*
X916900Y554250D01*
X917400Y553917D01*
X917733Y553333D01*
X917817Y552667D01*
X917733Y552000D01*
X917400Y551417D01*
X916900Y551083D01*
X916400Y551000D01*
G01X922000Y556000D02*
Y551000D01*
G01X920833Y554333D02*
X923167D01*
G01X926183Y551000D02*
Y556000D01*
G01Y553583D02*
X926600Y554000D01*
X927017Y554250D01*
X927683Y554333D01*
X928183Y554250D01*
X928767Y553917D01*
X929017Y553417D01*
Y551000D01*
G01X931950Y553250D02*
X934617D01*
X934367Y553833D01*
X933950Y554167D01*
X933367Y554333D01*
X932783Y554250D01*
X932283Y554000D01*
X931950Y553417D01*
X931783Y552917D01*
Y552417D01*
X931950Y551917D01*
X932367Y551417D01*
X932867Y551083D01*
X933450Y551000D01*
X934033Y551167D01*
X934617Y551667D01*
G01X937633Y551000D02*
Y554333D01*
G01Y553667D02*
X938050Y554000D01*
X938467Y554250D01*
X939050Y554333D01*
X939467Y554250D01*
X939967Y554000D01*
G01X948750Y551583D02*
X949167Y551250D01*
X949750Y551000D01*
X950250D01*
X950750Y551167D01*
X951083Y551417D01*
X951250Y551750D01*
X951167Y552250D01*
X950833Y552500D01*
X949333Y553000D01*
X949000Y553583D01*
X949167Y554000D01*
X949500Y554250D01*
X950000Y554333D01*
X950500Y554250D01*
X951000Y554000D01*
G01X955600Y554333D02*
Y551000D01*
G01Y555667D02*
X955433Y555750D01*
Y555917D01*
X955600Y556000D01*
X955767Y555917D01*
Y555750D01*
X955600Y555667D01*
G01X962700Y556000D02*
Y551000D01*
G01Y551750D02*
X962367Y551333D01*
X961867Y551083D01*
X961283Y551000D01*
X960617Y551167D01*
X960117Y551583D01*
X959783Y552083D01*
X959700Y552667D01*
X959783Y553250D01*
X960117Y553750D01*
X960617Y554167D01*
X961283Y554333D01*
X961867Y554250D01*
X962283Y554083D01*
X962700Y553750D01*
G01X965550Y553250D02*
X968217D01*
X967967Y553833D01*
X967550Y554167D01*
X966967Y554333D01*
X966383Y554250D01*
X965883Y554000D01*
X965550Y553417D01*
X965383Y552917D01*
Y552417D01*
X965550Y551917D01*
X965967Y551417D01*
X966467Y551083D01*
X967050Y551000D01*
X967633Y551167D01*
X968217Y551667D01*
G01X975917Y554333D02*
X976917Y551000D01*
X978000Y554333D01*
X979083Y551000D01*
X980083Y554333D01*
G01X983600D02*
Y551000D01*
G01Y555667D02*
X983433Y555750D01*
Y555917D01*
X983600Y556000D01*
X983767Y555917D01*
Y555750D01*
X983600Y555667D01*
G01X989200Y556000D02*
Y551000D01*
G01X988033Y554333D02*
X990367D01*
G01X993383Y551000D02*
Y556000D01*
G01Y553583D02*
X993800Y554000D01*
X994217Y554250D01*
X994883Y554333D01*
X995383Y554250D01*
X995967Y553917D01*
X996217Y553417D01*
Y551000D01*
G01X1000400D02*
X999900Y551083D01*
X999400Y551417D01*
X999067Y552000D01*
X998900Y552667D01*
X999067Y553333D01*
X999400Y553917D01*
X999900Y554250D01*
X1000400Y554333D01*
X1000900Y554250D01*
X1001400Y553917D01*
X1001733Y553333D01*
X1001817Y552667D01*
X1001733Y552000D01*
X1001400Y551417D01*
X1000900Y551083D01*
X1000400Y551000D01*
G01X1004583Y554333D02*
Y552000D01*
X1004917Y551417D01*
X1005417Y551083D01*
X1006000Y551000D01*
X1006583Y551083D01*
X1007083Y551417D01*
X1007417Y552000D01*
G01Y551000D02*
Y554333D01*
G01X1011600Y556000D02*
Y551000D01*
G01X1010433Y554333D02*
X1012767D01*
G01X878000Y591500D02*
X879667D01*
Y590000D01*
X879167Y589500D01*
X878583Y589167D01*
X877750Y589000D01*
X876917Y589167D01*
X876333Y589500D01*
X875833Y590000D01*
X875500Y590583D01*
X875333Y591250D01*
Y591833D01*
X875500Y592333D01*
X875833Y592917D01*
X876333Y593417D01*
X876833Y593750D01*
X877500Y594000D01*
X878083D01*
X878750Y593833D01*
X879250Y593500D01*
G01X881850Y591250D02*
X884517D01*
X884267Y591833D01*
X883850Y592167D01*
X883267Y592333D01*
X882683Y592250D01*
X882183Y592000D01*
X881850Y591417D01*
X881683Y590917D01*
Y590417D01*
X881850Y589917D01*
X882267Y589417D01*
X882767Y589083D01*
X883350Y589000D01*
X883933Y589167D01*
X884517Y589667D01*
G01X887533Y589000D02*
Y592333D01*
G01Y591667D02*
X887950Y592000D01*
X888367Y592250D01*
X888950Y592333D01*
X889367Y592250D01*
X889867Y592000D01*
G01X892800Y589000D02*
Y594000D01*
G01Y591500D02*
X893217Y592000D01*
X893717Y592250D01*
X894217Y592333D01*
X894967Y592167D01*
X895467Y591833D01*
X895800Y591250D01*
Y590583D01*
X895633Y589917D01*
X895300Y589417D01*
X894717Y589083D01*
X894217Y589000D01*
X893717Y589083D01*
X893217Y589333D01*
X892800Y589750D01*
G01X898650Y591250D02*
X901317D01*
X901067Y591833D01*
X900650Y592167D01*
X900067Y592333D01*
X899483Y592250D01*
X898983Y592000D01*
X898650Y591417D01*
X898483Y590917D01*
Y590417D01*
X898650Y589917D01*
X899067Y589417D01*
X899567Y589083D01*
X900150Y589000D01*
X900733Y589167D01*
X901317Y589667D01*
G01X904333Y589000D02*
Y592333D01*
G01Y591667D02*
X904750Y592000D01*
X905167Y592250D01*
X905750Y592333D01*
X906167Y592250D01*
X906667Y592000D01*
G01X918200Y594000D02*
Y589000D01*
G01Y589750D02*
X917867Y589333D01*
X917367Y589083D01*
X916783Y589000D01*
X916117Y589167D01*
X915617Y589583D01*
X915283Y590083D01*
X915200Y590667D01*
X915283Y591250D01*
X915617Y591750D01*
X916117Y592167D01*
X916783Y592333D01*
X917367Y592250D01*
X917783Y592083D01*
X918200Y591750D01*
G01X921050Y591250D02*
X923717D01*
X923467Y591833D01*
X923050Y592167D01*
X922467Y592333D01*
X921883Y592250D01*
X921383Y592000D01*
X921050Y591417D01*
X920883Y590917D01*
Y590417D01*
X921050Y589917D01*
X921467Y589417D01*
X921967Y589083D01*
X922550Y589000D01*
X923133Y589167D01*
X923717Y589667D01*
G01X926650Y589583D02*
X927067Y589250D01*
X927650Y589000D01*
X928150D01*
X928650Y589167D01*
X928983Y589417D01*
X929150Y589750D01*
X929067Y590250D01*
X928733Y590500D01*
X927233Y591000D01*
X926900Y591583D01*
X927067Y592000D01*
X927400Y592250D01*
X927900Y592333D01*
X928400Y592250D01*
X928900Y592000D01*
G01X933500Y592333D02*
Y589000D01*
G01Y593667D02*
X933333Y593750D01*
Y593917D01*
X933500Y594000D01*
X933667Y593917D01*
Y593750D01*
X933500Y593667D01*
G01X937933Y587750D02*
X938517Y587417D01*
X939183Y587333D01*
X939767Y587417D01*
X940267Y587833D01*
X940600Y588417D01*
Y592333D01*
G01Y591667D02*
X940267Y592000D01*
X939767Y592250D01*
X939183Y592333D01*
X938517Y592167D01*
X938100Y591833D01*
X937767Y591250D01*
X937600Y590667D01*
X937683Y590167D01*
X938017Y589583D01*
X938517Y589167D01*
X939183Y589000D01*
X939683Y589083D01*
X940267Y589417D01*
X940600Y589750D01*
G01X943283Y589000D02*
Y592333D01*
G01Y591500D02*
X943617Y591917D01*
X944117Y592250D01*
X944783Y592333D01*
X945367Y592250D01*
X945867Y591917D01*
X946117Y591333D01*
Y589000D01*
G01X843083Y734500D02*
Y739500D01*
G01Y737083D02*
X843500Y737500D01*
X843917Y737750D01*
X844583Y737833D01*
X845083Y737750D01*
X845667Y737417D01*
X845917Y736917D01*
Y734500D01*
G01X851600D02*
Y737833D01*
G01Y737250D02*
X851267Y737583D01*
X850767Y737750D01*
X850183Y737833D01*
X849600Y737667D01*
X849100Y737333D01*
X848767Y736833D01*
X848600Y736167D01*
X848767Y735500D01*
X849100Y735000D01*
X849600Y734667D01*
X850183Y734500D01*
X850767Y734583D01*
X851267Y734833D01*
X851600Y735167D01*
G01X855700Y734500D02*
Y739500D01*
G01X860800Y734500D02*
Y738750D01*
X860967Y739167D01*
X861300Y739417D01*
X861800Y739500D01*
X862300Y739333D01*
X862550Y738917D01*
G01X861550Y737500D02*
X859883D01*
G01X871000Y732833D02*
Y737833D01*
G01Y737083D02*
X871417Y737500D01*
X871833Y737750D01*
X872500Y737833D01*
X873083Y737750D01*
X873667Y737333D01*
X873917Y736750D01*
X874000Y736167D01*
X873917Y735583D01*
X873667Y735000D01*
X873167Y734667D01*
X872500Y734500D01*
X871917Y734583D01*
X871333Y734833D01*
X871000Y735167D01*
G01X878100Y734500D02*
Y739500D01*
G01X882283Y737833D02*
Y735500D01*
X882617Y734917D01*
X883117Y734583D01*
X883700Y734500D01*
X884283Y734583D01*
X884783Y734917D01*
X885117Y735500D01*
G01Y734500D02*
Y737833D01*
G01X888133Y733250D02*
X888717Y732917D01*
X889383Y732833D01*
X889967Y732917D01*
X890467Y733333D01*
X890800Y733917D01*
Y737833D01*
G01Y737167D02*
X890467Y737500D01*
X889967Y737750D01*
X889383Y737833D01*
X888717Y737667D01*
X888300Y737333D01*
X887967Y736750D01*
X887800Y736167D01*
X887883Y735667D01*
X888217Y735083D01*
X888717Y734667D01*
X889383Y734500D01*
X889883Y734583D01*
X890467Y734917D01*
X890800Y735250D01*
G01X893733Y733250D02*
X894317Y732917D01*
X894983Y732833D01*
X895567Y732917D01*
X896067Y733333D01*
X896400Y733917D01*
Y737833D01*
G01Y737167D02*
X896067Y737500D01*
X895567Y737750D01*
X894983Y737833D01*
X894317Y737667D01*
X893900Y737333D01*
X893567Y736750D01*
X893400Y736167D01*
X893483Y735667D01*
X893817Y735083D01*
X894317Y734667D01*
X894983Y734500D01*
X895483Y734583D01*
X896067Y734917D01*
X896400Y735250D01*
G01X900500Y737833D02*
Y734500D01*
G01Y739167D02*
X900333Y739250D01*
Y739417D01*
X900500Y739500D01*
X900667Y739417D01*
Y739250D01*
X900500Y739167D01*
G01X904683Y734500D02*
Y737833D01*
G01Y737000D02*
X905017Y737417D01*
X905517Y737750D01*
X906183Y737833D01*
X906767Y737750D01*
X907267Y737417D01*
X907517Y736833D01*
Y734500D01*
G01X910533Y733250D02*
X911117Y732917D01*
X911783Y732833D01*
X912367Y732917D01*
X912867Y733333D01*
X913200Y733917D01*
Y737833D01*
G01Y737167D02*
X912867Y737500D01*
X912367Y737750D01*
X911783Y737833D01*
X911117Y737667D01*
X910700Y737333D01*
X910367Y736750D01*
X910200Y736167D01*
X910283Y735667D01*
X910617Y735083D01*
X911117Y734667D01*
X911783Y734500D01*
X912283Y734583D01*
X912867Y734917D01*
X913200Y735250D01*
G01X980667Y16500D02*
X977333D01*
Y21500D01*
X980667D01*
G01X979333Y19083D02*
X977333D01*
G01X983350Y19833D02*
X985850Y16500D01*
G01Y19833D02*
X983350Y16500D01*
G01X990200Y16333D02*
X990033Y16417D01*
Y16583D01*
X990200Y16667D01*
X990367Y16583D01*
Y16417D01*
X990200Y16333D01*
G01X994050Y16500D02*
Y21500D01*
G01X997550D02*
Y16500D01*
G01Y19000D02*
X994050D01*
G01X999733Y16500D02*
Y21500D01*
X1001817D01*
X1002483Y21250D01*
X1002900Y20917D01*
X1003067Y20250D01*
X1002900Y19583D01*
X1002400Y19167D01*
X1001817Y18917D01*
X999733D01*
G01X1001817D02*
X1003067Y16500D01*
G01X1008667D02*
X1005333D01*
Y21500D01*
X1008667D01*
G01X1007333Y19083D02*
X1005333D01*
G01X1013600Y16500D02*
Y21500D01*
X1010517Y17917D01*
X1014683D01*
G01X1016367Y17250D02*
X1016867Y16833D01*
X1017450Y16583D01*
X1018200Y16500D01*
X1018950Y16667D01*
X1019533Y17000D01*
X1019950Y17583D01*
X1020033Y18250D01*
X1019867Y18917D01*
X1019450Y19333D01*
X1018867Y19667D01*
X1018283Y19750D01*
X1017700Y19667D01*
X1016950Y19333D01*
X1017200Y21500D01*
X1019450D01*
G01X1022050Y16500D02*
X1025550Y21500D01*
G01X1022050D02*
X1025550Y16500D01*
G01X1027983Y17083D02*
X1028567Y16667D01*
X1029233Y16500D01*
X1029900Y16667D01*
X1030483Y17167D01*
X1030900Y17917D01*
X1031067Y18667D01*
Y19583D01*
X1030900Y20333D01*
X1030483Y21000D01*
X1029983Y21333D01*
X1029400Y21500D01*
X1028733Y21333D01*
X1028233Y21000D01*
X1027900Y20500D01*
X1027733Y19833D01*
X1027900Y19250D01*
X1028317Y18667D01*
X1028817Y18333D01*
X1029400Y18250D01*
X1030067Y18417D01*
X1030567Y18833D01*
X1031067Y19583D01*
G01X1033417Y18583D02*
X1034000Y19167D01*
X1034500Y19500D01*
X1035167Y19667D01*
X1035750Y19500D01*
X1036167Y19167D01*
X1036500Y18667D01*
X1036583Y18083D01*
X1036500Y17583D01*
X1036167Y17083D01*
X1035667Y16667D01*
X1035083Y16500D01*
X1034417Y16667D01*
X1033833Y17167D01*
X1033500Y17917D01*
X1033417Y18750D01*
X1033583Y19833D01*
X1033833Y20417D01*
X1034250Y21000D01*
X1034833Y21417D01*
X1035417Y21500D01*
X1036000Y21333D01*
X1036417Y20917D01*
G01X1040183Y14833D02*
X1039350Y15667D01*
X1038933Y16500D01*
Y19833D01*
X1039350Y20667D01*
X1040183Y21500D01*
G01X1044367Y16500D02*
Y21500D01*
X1046033D01*
X1046700Y21250D01*
X1047200Y20917D01*
X1047617Y20417D01*
X1047950Y19833D01*
X1048033Y19000D01*
X1047950Y18167D01*
X1047617Y17583D01*
X1047200Y17083D01*
X1046700Y16750D01*
X1046033Y16500D01*
X1044367D01*
G01X1051800D02*
Y21500D01*
X1050800Y20500D01*
G01Y16500D02*
X1052800D01*
G01X1055817Y18583D02*
X1056400Y19167D01*
X1056900Y19500D01*
X1057567Y19667D01*
X1058150Y19500D01*
X1058567Y19167D01*
X1058900Y18667D01*
X1058983Y18083D01*
X1058900Y17583D01*
X1058567Y17083D01*
X1058067Y16667D01*
X1057483Y16500D01*
X1056817Y16667D01*
X1056233Y17167D01*
X1055900Y17917D01*
X1055817Y18750D01*
X1055983Y19833D01*
X1056233Y20417D01*
X1056650Y21000D01*
X1057233Y21417D01*
X1057817Y21500D01*
X1058400Y21333D01*
X1058817Y20917D01*
G01X1061250Y16500D02*
X1064750Y21500D01*
G01X1061250D02*
X1064750Y16500D01*
G01X1069600D02*
Y21500D01*
X1066517Y17917D01*
X1070683D01*
G01X1074617Y14833D02*
X1075450Y15667D01*
X1075867Y16500D01*
Y19833D01*
X1075450Y20667D01*
X1074617Y21500D01*
G01X928583Y23083D02*
X929167Y22667D01*
X929833Y22500D01*
X930500Y22667D01*
X931083Y23167D01*
X931500Y23917D01*
X931667Y24667D01*
Y25583D01*
X931500Y26333D01*
X931083Y27000D01*
X930583Y27333D01*
X930000Y27500D01*
X929333Y27333D01*
X928833Y27000D01*
X928500Y26500D01*
X928333Y25833D01*
X928500Y25250D01*
X928917Y24667D01*
X929417Y24333D01*
X930000Y24250D01*
X930667Y24417D01*
X931167Y24833D01*
X931667Y25583D01*
G01X934017Y24583D02*
X934600Y25167D01*
X935100Y25500D01*
X935767Y25667D01*
X936350Y25500D01*
X936767Y25167D01*
X937100Y24667D01*
X937183Y24083D01*
X937100Y23583D01*
X936767Y23083D01*
X936267Y22667D01*
X935683Y22500D01*
X935017Y22667D01*
X934433Y23167D01*
X934100Y23917D01*
X934017Y24750D01*
X934183Y25833D01*
X934433Y26417D01*
X934850Y27000D01*
X935433Y27417D01*
X936017Y27500D01*
X936600Y27333D01*
X937017Y26917D01*
G01X977333Y65500D02*
Y70500D01*
X979417D01*
X980083Y70250D01*
X980500Y69917D01*
X980667Y69250D01*
X980500Y68583D01*
X980000Y68167D01*
X979417Y67917D01*
X977333D01*
G01X979417D02*
X980667Y65500D01*
G01X986267D02*
X982933D01*
Y70500D01*
X986267D01*
G01X984933Y68083D02*
X982933D01*
G01X992033Y70083D02*
X991533Y70333D01*
X990950Y70500D01*
X990283D01*
X989533Y70250D01*
X988950Y69833D01*
X988533Y69333D01*
X988200Y68500D01*
X988117Y67750D01*
X988283Y67000D01*
X988533Y66500D01*
X989033Y66000D01*
X989617Y65667D01*
X990200Y65500D01*
X990783D01*
X991367Y65667D01*
X991867Y65917D01*
X992283Y66250D01*
G01X995800Y70500D02*
Y65500D01*
G01X993883Y70500D02*
X997717D01*
G01X999317Y65500D02*
X1001400Y70500D01*
X1003483Y65500D01*
G01X1002733Y67250D02*
X1000067D01*
G01X1005083Y65500D02*
Y70500D01*
X1008917Y65500D01*
Y70500D01*
G01X1013100Y68000D02*
X1014767D01*
Y66500D01*
X1014267Y66000D01*
X1013683Y65667D01*
X1012850Y65500D01*
X1012017Y65667D01*
X1011433Y66000D01*
X1010933Y66500D01*
X1010600Y67083D01*
X1010433Y67750D01*
Y68333D01*
X1010600Y68833D01*
X1010933Y69417D01*
X1011433Y69917D01*
X1011933Y70250D01*
X1012600Y70500D01*
X1013183D01*
X1013850Y70333D01*
X1014350Y70000D01*
G01X1016533Y70500D02*
Y65500D01*
X1019867D01*
G01X1025467D02*
X1022133D01*
Y70500D01*
X1025467D01*
G01X1024133Y68083D02*
X1022133D01*
G01X1033167Y65500D02*
Y70500D01*
X1034833D01*
X1035500Y70250D01*
X1036000Y69917D01*
X1036417Y69417D01*
X1036750Y68833D01*
X1036833Y68000D01*
X1036750Y67167D01*
X1036417Y66583D01*
X1036000Y66083D01*
X1035500Y65750D01*
X1034833Y65500D01*
X1033167D01*
G01X1038933D02*
Y70500D01*
X1041017D01*
X1041683Y70250D01*
X1042100Y69917D01*
X1042267Y69250D01*
X1042100Y68583D01*
X1041600Y68167D01*
X1041017Y67917D01*
X1038933D01*
G01X1041017D02*
X1042267Y65500D01*
G01X1045200Y70500D02*
X1047200D01*
G01X1046200D02*
Y65500D01*
G01X1045200D02*
X1047200D01*
G01X1050133Y70500D02*
Y65500D01*
X1053467D01*
G01X1055733Y70500D02*
Y65500D01*
X1059067D01*
G01X1066850D02*
Y70500D01*
G01X1070350D02*
Y65500D01*
G01Y68000D02*
X1066850D01*
G01X1074200Y65500D02*
X1073533Y65583D01*
X1072950Y65917D01*
X1072450Y66417D01*
X1072117Y67000D01*
X1071950Y67667D01*
Y68333D01*
X1072117Y69000D01*
X1072450Y69583D01*
X1072950Y70083D01*
X1073533Y70417D01*
X1074200Y70500D01*
X1074867Y70417D01*
X1075450Y70083D01*
X1075950Y69583D01*
X1076283Y69000D01*
X1076450Y68333D01*
Y67667D01*
X1076283Y67000D01*
X1075950Y66417D01*
X1075450Y65917D01*
X1074867Y65583D01*
X1074200Y65500D01*
G01X1078133Y70500D02*
Y65500D01*
X1081467D01*
G01X1087067D02*
X1083733D01*
Y70500D01*
X1087067D01*
G01X1085733Y68083D02*
X1083733D01*
G01X1094767Y65500D02*
Y70500D01*
X1096433D01*
X1097100Y70250D01*
X1097600Y69917D01*
X1098017Y69417D01*
X1098350Y68833D01*
X1098433Y68000D01*
X1098350Y67167D01*
X1098017Y66583D01*
X1097600Y66083D01*
X1097100Y65750D01*
X1096433Y65500D01*
X1094767D01*
G01X1103867D02*
X1100533D01*
Y70500D01*
X1103867D01*
G01X1102533Y68083D02*
X1100533D01*
G01X1106217Y65500D02*
Y70500D01*
X1109383D01*
G01X1108217Y68083D02*
X1106217D01*
G01X1112400Y70500D02*
X1114400D01*
G01X1113400D02*
Y65500D01*
G01X1112400D02*
X1114400D01*
G01X1117083D02*
Y70500D01*
X1120917Y65500D01*
Y70500D01*
G01X1126267Y65500D02*
X1122933D01*
Y70500D01*
X1126267D01*
G01X1124933Y68083D02*
X1122933D01*
G01X929000Y734500D02*
Y738750D01*
X929167Y739167D01*
X929500Y739417D01*
X930000Y739500D01*
X930500Y739333D01*
X930750Y738917D01*
G01X929750Y737500D02*
X928083D01*
G01X933683Y737833D02*
Y735500D01*
X934017Y734917D01*
X934517Y734583D01*
X935100Y734500D01*
X935683Y734583D01*
X936183Y734917D01*
X936517Y735500D01*
G01Y734500D02*
Y737833D01*
G01X940700Y734500D02*
Y739500D01*
G01X946300Y734500D02*
Y739500D01*
G01X956000Y732833D02*
Y737833D01*
G01Y737083D02*
X956417Y737500D01*
X956833Y737750D01*
X957500Y737833D01*
X958083Y737750D01*
X958667Y737333D01*
X958917Y736750D01*
X959000Y736167D01*
X958917Y735583D01*
X958667Y735000D01*
X958167Y734667D01*
X957500Y734500D01*
X956917Y734583D01*
X956333Y734833D01*
X956000Y735167D01*
G01X963100Y734500D02*
Y739500D01*
G01X967283Y737833D02*
Y735500D01*
X967617Y734917D01*
X968117Y734583D01*
X968700Y734500D01*
X969283Y734583D01*
X969783Y734917D01*
X970117Y735500D01*
G01Y734500D02*
Y737833D01*
G01X973133Y733250D02*
X973717Y732917D01*
X974383Y732833D01*
X974967Y732917D01*
X975467Y733333D01*
X975800Y733917D01*
Y737833D01*
G01Y737167D02*
X975467Y737500D01*
X974967Y737750D01*
X974383Y737833D01*
X973717Y737667D01*
X973300Y737333D01*
X972967Y736750D01*
X972800Y736167D01*
X972883Y735667D01*
X973217Y735083D01*
X973717Y734667D01*
X974383Y734500D01*
X974883Y734583D01*
X975467Y734917D01*
X975800Y735250D01*
G01X978733Y733250D02*
X979317Y732917D01*
X979983Y732833D01*
X980567Y732917D01*
X981067Y733333D01*
X981400Y733917D01*
Y737833D01*
G01Y737167D02*
X981067Y737500D01*
X980567Y737750D01*
X979983Y737833D01*
X979317Y737667D01*
X978900Y737333D01*
X978567Y736750D01*
X978400Y736167D01*
X978483Y735667D01*
X978817Y735083D01*
X979317Y734667D01*
X979983Y734500D01*
X980483Y734583D01*
X981067Y734917D01*
X981400Y735250D01*
G01X985500Y737833D02*
Y734500D01*
G01Y739167D02*
X985333Y739250D01*
Y739417D01*
X985500Y739500D01*
X985667Y739417D01*
Y739250D01*
X985500Y739167D01*
G01X989683Y734500D02*
Y737833D01*
G01Y737000D02*
X990017Y737417D01*
X990517Y737750D01*
X991183Y737833D01*
X991767Y737750D01*
X992267Y737417D01*
X992517Y736833D01*
Y734500D01*
G01X995533Y733250D02*
X996117Y732917D01*
X996783Y732833D01*
X997367Y732917D01*
X997867Y733333D01*
X998200Y733917D01*
Y737833D01*
G01Y737167D02*
X997867Y737500D01*
X997367Y737750D01*
X996783Y737833D01*
X996117Y737667D01*
X995700Y737333D01*
X995367Y736750D01*
X995200Y736167D01*
X995283Y735667D01*
X995617Y735083D01*
X996117Y734667D01*
X996783Y734500D01*
X997283Y734583D01*
X997867Y734917D01*
X998200Y735250D01*
G01X956000Y795980D02*
Y790980D01*
G01X954083Y795980D02*
X957917D01*
G01X959517Y794313D02*
X960517Y790980D01*
X961600Y794313D01*
X962683Y790980D01*
X963683Y794313D01*
G01X967200D02*
Y790980D01*
G01Y795647D02*
X967033Y795730D01*
Y795897D01*
X967200Y795980D01*
X967367Y795897D01*
Y795730D01*
X967200Y795647D01*
G01X971550Y791563D02*
X971967Y791230D01*
X972550Y790980D01*
X973050D01*
X973550Y791147D01*
X973883Y791397D01*
X974050Y791730D01*
X973967Y792230D01*
X973633Y792480D01*
X972133Y792980D01*
X971800Y793563D01*
X971967Y793980D01*
X972300Y794230D01*
X972800Y794313D01*
X973300Y794230D01*
X973800Y793980D01*
G01X978400Y795980D02*
Y790980D01*
G01X977233Y794313D02*
X979567D01*
G01X991100Y790980D02*
Y794313D01*
G01Y793730D02*
X990767Y794063D01*
X990267Y794230D01*
X989683Y794313D01*
X989100Y794147D01*
X988600Y793813D01*
X988267Y793313D01*
X988100Y792647D01*
X988267Y791980D01*
X988600Y791480D01*
X989100Y791147D01*
X989683Y790980D01*
X990267Y791063D01*
X990767Y791313D01*
X991100Y791647D01*
G01X993783Y790980D02*
Y794313D01*
G01Y793480D02*
X994117Y793897D01*
X994617Y794230D01*
X995283Y794313D01*
X995867Y794230D01*
X996367Y793897D01*
X996617Y793313D01*
Y790980D01*
G01X1002300Y795980D02*
Y790980D01*
G01Y791730D02*
X1001967Y791313D01*
X1001467Y791063D01*
X1000883Y790980D01*
X1000217Y791147D01*
X999717Y791563D01*
X999383Y792063D01*
X999300Y792647D01*
X999383Y793230D01*
X999717Y793730D01*
X1000217Y794147D01*
X1000883Y794313D01*
X1001467Y794230D01*
X1001883Y794063D01*
X1002300Y793730D01*
G01X1010500Y790980D02*
Y795980D01*
G01Y793480D02*
X1010917Y793980D01*
X1011417Y794230D01*
X1011917Y794313D01*
X1012667Y794147D01*
X1013167Y793813D01*
X1013500Y793230D01*
Y792563D01*
X1013333Y791897D01*
X1013000Y791397D01*
X1012417Y791063D01*
X1011917Y790980D01*
X1011417Y791063D01*
X1010917Y791313D01*
X1010500Y791730D01*
G01X1017600Y790980D02*
X1017100Y791063D01*
X1016600Y791397D01*
X1016267Y791980D01*
X1016100Y792647D01*
X1016267Y793313D01*
X1016600Y793897D01*
X1017100Y794230D01*
X1017600Y794313D01*
X1018100Y794230D01*
X1018600Y793897D01*
X1018933Y793313D01*
X1019017Y792647D01*
X1018933Y791980D01*
X1018600Y791397D01*
X1018100Y791063D01*
X1017600Y790980D01*
G01X1021117Y794313D02*
X1022117Y790980D01*
X1023200Y794313D01*
X1024283Y790980D01*
X1025283Y794313D01*
G01X957500Y811500D02*
X959167D01*
Y810000D01*
X958667Y809500D01*
X958083Y809167D01*
X957250Y809000D01*
X956417Y809167D01*
X955833Y809500D01*
X955333Y810000D01*
X955000Y810583D01*
X954833Y811250D01*
Y811833D01*
X955000Y812333D01*
X955333Y812917D01*
X955833Y813417D01*
X956333Y813750D01*
X957000Y814000D01*
X957583D01*
X958250Y813833D01*
X958750Y813500D01*
G01X961100Y808833D02*
X964100Y814000D01*
G01X966617Y809000D02*
Y814000D01*
X969783D01*
G01X968617Y811583D02*
X966617D01*
G01X977650Y809667D02*
X978317Y809250D01*
X979067Y809000D01*
X979733D01*
X980400Y809250D01*
X980900Y809667D01*
X981150Y810250D01*
X980983Y810833D01*
X980567Y811333D01*
X979817Y811667D01*
X978817Y811833D01*
X978233Y812167D01*
X977983Y812750D01*
X978150Y813333D01*
X978567Y813750D01*
X979150Y814000D01*
X979733D01*
X980317Y813833D01*
X980817Y813417D01*
G01X985000Y809000D02*
Y814000D01*
G01X990600Y809000D02*
X990100Y809083D01*
X989600Y809417D01*
X989267Y810000D01*
X989100Y810667D01*
X989267Y811333D01*
X989600Y811917D01*
X990100Y812250D01*
X990600Y812333D01*
X991100Y812250D01*
X991600Y811917D01*
X991933Y811333D01*
X992017Y810667D01*
X991933Y810000D01*
X991600Y809417D01*
X991100Y809083D01*
X990600Y809000D01*
G01X996200Y814000D02*
Y809000D01*
G01X995033Y812333D02*
X997367D01*
G01X955750Y826250D02*
X958417D01*
X958167Y826833D01*
X957750Y827167D01*
X957167Y827333D01*
X956583Y827250D01*
X956083Y827000D01*
X955750Y826417D01*
X955583Y825917D01*
Y825417D01*
X955750Y824917D01*
X956167Y824417D01*
X956667Y824083D01*
X957250Y824000D01*
X957833Y824167D01*
X958417Y824667D01*
G01X964100Y829000D02*
Y824000D01*
G01Y824750D02*
X963767Y824333D01*
X963267Y824083D01*
X962683Y824000D01*
X962017Y824167D01*
X961517Y824583D01*
X961183Y825083D01*
X961100Y825667D01*
X961183Y826250D01*
X961517Y826750D01*
X962017Y827167D01*
X962683Y827333D01*
X963267Y827250D01*
X963683Y827083D01*
X964100Y826750D01*
G01X967033Y822750D02*
X967617Y822417D01*
X968283Y822333D01*
X968867Y822417D01*
X969367Y822833D01*
X969700Y823417D01*
Y827333D01*
G01Y826667D02*
X969367Y827000D01*
X968867Y827250D01*
X968283Y827333D01*
X967617Y827167D01*
X967200Y826833D01*
X966867Y826250D01*
X966700Y825667D01*
X966783Y825167D01*
X967117Y824583D01*
X967617Y824167D01*
X968283Y824000D01*
X968783Y824083D01*
X969367Y824417D01*
X969700Y824750D01*
G01X972550Y826250D02*
X975217D01*
X974967Y826833D01*
X974550Y827167D01*
X973967Y827333D01*
X973383Y827250D01*
X972883Y827000D01*
X972550Y826417D01*
X972383Y825917D01*
Y825417D01*
X972550Y824917D01*
X972967Y824417D01*
X973467Y824083D01*
X974050Y824000D01*
X974633Y824167D01*
X975217Y824667D01*
G01X985000Y829000D02*
Y824000D01*
G01X983833Y827333D02*
X986167D01*
G01X990600Y824000D02*
X990100Y824083D01*
X989600Y824417D01*
X989267Y825000D01*
X989100Y825667D01*
X989267Y826333D01*
X989600Y826917D01*
X990100Y827250D01*
X990600Y827333D01*
X991100Y827250D01*
X991600Y826917D01*
X991933Y826333D01*
X992017Y825667D01*
X991933Y825000D01*
X991600Y824417D01*
X991100Y824083D01*
X990600Y824000D01*
G01X1000383D02*
Y829000D01*
G01Y826583D02*
X1000800Y827000D01*
X1001217Y827250D01*
X1001883Y827333D01*
X1002383Y827250D01*
X1002967Y826917D01*
X1003217Y826417D01*
Y824000D01*
G01X1007400D02*
X1006900Y824083D01*
X1006400Y824417D01*
X1006067Y825000D01*
X1005900Y825667D01*
X1006067Y826333D01*
X1006400Y826917D01*
X1006900Y827250D01*
X1007400Y827333D01*
X1007900Y827250D01*
X1008400Y826917D01*
X1008733Y826333D01*
X1008817Y825667D01*
X1008733Y825000D01*
X1008400Y824417D01*
X1007900Y824083D01*
X1007400Y824000D01*
G01X1013000D02*
Y829000D01*
G01X1017350Y826250D02*
X1020017D01*
X1019767Y826833D01*
X1019350Y827167D01*
X1018767Y827333D01*
X1018183Y827250D01*
X1017683Y827000D01*
X1017350Y826417D01*
X1017183Y825917D01*
Y825417D01*
X1017350Y824917D01*
X1017767Y824417D01*
X1018267Y824083D01*
X1018850Y824000D01*
X1019433Y824167D01*
X1020017Y824667D01*
G01X955750Y842750D02*
X958417D01*
X958167Y843333D01*
X957750Y843667D01*
X957167Y843833D01*
X956583Y843750D01*
X956083Y843500D01*
X955750Y842917D01*
X955583Y842417D01*
Y841917D01*
X955750Y841417D01*
X956167Y840917D01*
X956667Y840583D01*
X957250Y840500D01*
X957833Y840667D01*
X958417Y841167D01*
G01X964100Y845500D02*
Y840500D01*
G01Y841250D02*
X963767Y840833D01*
X963267Y840583D01*
X962683Y840500D01*
X962017Y840667D01*
X961517Y841083D01*
X961183Y841583D01*
X961100Y842167D01*
X961183Y842750D01*
X961517Y843250D01*
X962017Y843667D01*
X962683Y843833D01*
X963267Y843750D01*
X963683Y843583D01*
X964100Y843250D01*
G01X967033Y839250D02*
X967617Y838917D01*
X968283Y838833D01*
X968867Y838917D01*
X969367Y839333D01*
X969700Y839917D01*
Y843833D01*
G01Y843167D02*
X969367Y843500D01*
X968867Y843750D01*
X968283Y843833D01*
X967617Y843667D01*
X967200Y843333D01*
X966867Y842750D01*
X966700Y842167D01*
X966783Y841667D01*
X967117Y841083D01*
X967617Y840667D01*
X968283Y840500D01*
X968783Y840583D01*
X969367Y840917D01*
X969700Y841250D01*
G01X972550Y842750D02*
X975217D01*
X974967Y843333D01*
X974550Y843667D01*
X973967Y843833D01*
X973383Y843750D01*
X972883Y843500D01*
X972550Y842917D01*
X972383Y842417D01*
Y841917D01*
X972550Y841417D01*
X972967Y840917D01*
X973467Y840583D01*
X974050Y840500D01*
X974633Y840667D01*
X975217Y841167D01*
G01X985000Y845500D02*
Y840500D01*
G01X983833Y843833D02*
X986167D01*
G01X990600Y840500D02*
X990100Y840583D01*
X989600Y840917D01*
X989267Y841500D01*
X989100Y842167D01*
X989267Y842833D01*
X989600Y843417D01*
X990100Y843750D01*
X990600Y843833D01*
X991100Y843750D01*
X991600Y843417D01*
X991933Y842833D01*
X992017Y842167D01*
X991933Y841500D01*
X991600Y840917D01*
X991100Y840583D01*
X990600Y840500D01*
G01X1000550Y842750D02*
X1003217D01*
X1002967Y843333D01*
X1002550Y843667D01*
X1001967Y843833D01*
X1001383Y843750D01*
X1000883Y843500D01*
X1000550Y842917D01*
X1000383Y842417D01*
Y841917D01*
X1000550Y841417D01*
X1000967Y840917D01*
X1001467Y840583D01*
X1002050Y840500D01*
X1002633Y840667D01*
X1003217Y841167D01*
G01X1008900Y845500D02*
Y840500D01*
G01Y841250D02*
X1008567Y840833D01*
X1008067Y840583D01*
X1007483Y840500D01*
X1006817Y840667D01*
X1006317Y841083D01*
X1005983Y841583D01*
X1005900Y842167D01*
X1005983Y842750D01*
X1006317Y843250D01*
X1006817Y843667D01*
X1007483Y843833D01*
X1008067Y843750D01*
X1008483Y843583D01*
X1008900Y843250D01*
G01X1011833Y839250D02*
X1012417Y838917D01*
X1013083Y838833D01*
X1013667Y838917D01*
X1014167Y839333D01*
X1014500Y839917D01*
Y843833D01*
G01Y843167D02*
X1014167Y843500D01*
X1013667Y843750D01*
X1013083Y843833D01*
X1012417Y843667D01*
X1012000Y843333D01*
X1011667Y842750D01*
X1011500Y842167D01*
X1011583Y841667D01*
X1011917Y841083D01*
X1012417Y840667D01*
X1013083Y840500D01*
X1013583Y840583D01*
X1014167Y840917D01*
X1014500Y841250D01*
G01X1017350Y842750D02*
X1020017D01*
X1019767Y843333D01*
X1019350Y843667D01*
X1018767Y843833D01*
X1018183Y843750D01*
X1017683Y843500D01*
X1017350Y842917D01*
X1017183Y842417D01*
Y841917D01*
X1017350Y841417D01*
X1017767Y840917D01*
X1018267Y840583D01*
X1018850Y840500D01*
X1019433Y840667D01*
X1020017Y841167D01*
G01X948000Y850610D02*
Y782110D01*
G01X948500Y819500D02*
X1343000D01*
G01X948500Y834500D02*
X1343000D01*
G01X995667Y5500D02*
Y10500D01*
X997333D01*
X998000Y10250D01*
X998500Y9917D01*
X998917Y9417D01*
X999250Y8833D01*
X999333Y8000D01*
X999250Y7167D01*
X998917Y6583D01*
X998500Y6083D01*
X998000Y5750D01*
X997333Y5500D01*
X995667D01*
G01X1003100D02*
Y10500D01*
X1002100Y9500D01*
G01Y5500D02*
X1004100D01*
G01X1007117Y7583D02*
X1007700Y8167D01*
X1008200Y8500D01*
X1008867Y8667D01*
X1009450Y8500D01*
X1009867Y8167D01*
X1010200Y7667D01*
X1010283Y7083D01*
X1010200Y6583D01*
X1009867Y6083D01*
X1009367Y5667D01*
X1008783Y5500D01*
X1008117Y5667D01*
X1007533Y6167D01*
X1007200Y6917D01*
X1007117Y7750D01*
X1007283Y8833D01*
X1007533Y9417D01*
X1007950Y10000D01*
X1008533Y10417D01*
X1009117Y10500D01*
X1009700Y10333D01*
X1010117Y9917D01*
G01X1014300Y5333D02*
X1014133Y5417D01*
Y5583D01*
X1014300Y5667D01*
X1014467Y5583D01*
Y5417D01*
X1014300Y5333D01*
G01Y7583D02*
X1014133Y7667D01*
Y7833D01*
X1014300Y7917D01*
X1014467Y7833D01*
Y7667D01*
X1014300Y7583D01*
G01X1018067Y5500D02*
Y10500D01*
X1019733D01*
X1020400Y10250D01*
X1020900Y9917D01*
X1021317Y9417D01*
X1021650Y8833D01*
X1021733Y8000D01*
X1021650Y7167D01*
X1021317Y6583D01*
X1020900Y6083D01*
X1020400Y5750D01*
X1019733Y5500D01*
X1018067D01*
G01X1025500Y8833D02*
Y5500D01*
G01Y10167D02*
X1025333Y10250D01*
Y10417D01*
X1025500Y10500D01*
X1025667Y10417D01*
Y10250D01*
X1025500Y10167D01*
G01X1032600Y5500D02*
Y8833D01*
G01Y8250D02*
X1032267Y8583D01*
X1031767Y8750D01*
X1031183Y8833D01*
X1030600Y8667D01*
X1030100Y8333D01*
X1029767Y7833D01*
X1029600Y7167D01*
X1029767Y6500D01*
X1030100Y6000D01*
X1030600Y5667D01*
X1031183Y5500D01*
X1031767Y5583D01*
X1032267Y5833D01*
X1032600Y6167D01*
G01X1034200Y5500D02*
Y8833D01*
G01Y7917D02*
X1034450Y8333D01*
X1034867Y8667D01*
X1035450Y8833D01*
X1036033Y8667D01*
X1036450Y8333D01*
X1036700Y7917D01*
Y5500D01*
G01Y7917D02*
X1036950Y8333D01*
X1037367Y8667D01*
X1037950Y8833D01*
X1038533Y8667D01*
X1038950Y8333D01*
X1039200Y7833D01*
Y5500D01*
G01X1041050Y7750D02*
X1043717D01*
X1043467Y8333D01*
X1043050Y8667D01*
X1042467Y8833D01*
X1041883Y8750D01*
X1041383Y8500D01*
X1041050Y7917D01*
X1040883Y7417D01*
Y6917D01*
X1041050Y6417D01*
X1041467Y5917D01*
X1041967Y5583D01*
X1042550Y5500D01*
X1043133Y5667D01*
X1043717Y6167D01*
G01X1047900Y10500D02*
Y5500D01*
G01X1046733Y8833D02*
X1049067D01*
G01X1052250Y7750D02*
X1054917D01*
X1054667Y8333D01*
X1054250Y8667D01*
X1053667Y8833D01*
X1053083Y8750D01*
X1052583Y8500D01*
X1052250Y7917D01*
X1052083Y7417D01*
Y6917D01*
X1052250Y6417D01*
X1052667Y5917D01*
X1053167Y5583D01*
X1053750Y5500D01*
X1054333Y5667D01*
X1054917Y6167D01*
G01X1057933Y5500D02*
Y8833D01*
G01Y8167D02*
X1058350Y8500D01*
X1058767Y8750D01*
X1059350Y8833D01*
X1059767Y8750D01*
X1060267Y8500D01*
G01X1070300Y5500D02*
Y10500D01*
X1069300Y9500D01*
G01Y5500D02*
X1071300D01*
G01X1074317Y7583D02*
X1074900Y8167D01*
X1075400Y8500D01*
X1076067Y8667D01*
X1076650Y8500D01*
X1077067Y8167D01*
X1077400Y7667D01*
X1077483Y7083D01*
X1077400Y6583D01*
X1077067Y6083D01*
X1076567Y5667D01*
X1075983Y5500D01*
X1075317Y5667D01*
X1074733Y6167D01*
X1074400Y6917D01*
X1074317Y7750D01*
X1074483Y8833D01*
X1074733Y9417D01*
X1075150Y10000D01*
X1075733Y10417D01*
X1076317Y10500D01*
X1076900Y10333D01*
X1077317Y9917D01*
G01X1079000Y5500D02*
Y8833D01*
G01Y7917D02*
X1079250Y8333D01*
X1079667Y8667D01*
X1080250Y8833D01*
X1080833Y8667D01*
X1081250Y8333D01*
X1081500Y7917D01*
Y5500D01*
G01Y7917D02*
X1081750Y8333D01*
X1082167Y8667D01*
X1082750Y8833D01*
X1083333Y8667D01*
X1083750Y8333D01*
X1084000Y7833D01*
Y5500D01*
G01X1087100Y8833D02*
Y5500D01*
G01Y10167D02*
X1086933Y10250D01*
Y10417D01*
X1087100Y10500D01*
X1087267Y10417D01*
Y10250D01*
X1087100Y10167D01*
G01X1092700Y5500D02*
Y10500D01*
G01X1026000Y336000D02*
Y86000D01*
G01X1033500Y370500D02*
Y375500D01*
G01Y373000D02*
X1033917Y373500D01*
X1034417Y373750D01*
X1034917Y373833D01*
X1035667Y373667D01*
X1036167Y373333D01*
X1036500Y372750D01*
Y372083D01*
X1036333Y371417D01*
X1036000Y370917D01*
X1035417Y370583D01*
X1034917Y370500D01*
X1034417Y370583D01*
X1033917Y370833D01*
X1033500Y371250D01*
G01X1039183Y373833D02*
Y371500D01*
X1039517Y370917D01*
X1040017Y370583D01*
X1040600Y370500D01*
X1041183Y370583D01*
X1041683Y370917D01*
X1042017Y371500D01*
G01Y370500D02*
Y373833D01*
G01X1044700Y370500D02*
Y375500D01*
G01Y373000D02*
X1045117Y373500D01*
X1045617Y373750D01*
X1046117Y373833D01*
X1046867Y373667D01*
X1047367Y373333D01*
X1047700Y372750D01*
Y372083D01*
X1047533Y371417D01*
X1047200Y370917D01*
X1046617Y370583D01*
X1046117Y370500D01*
X1045617Y370583D01*
X1045117Y370833D01*
X1044700Y371250D01*
G01X1050300Y370500D02*
Y375500D01*
G01Y373000D02*
X1050717Y373500D01*
X1051217Y373750D01*
X1051717Y373833D01*
X1052467Y373667D01*
X1052967Y373333D01*
X1053300Y372750D01*
Y372083D01*
X1053133Y371417D01*
X1052800Y370917D01*
X1052217Y370583D01*
X1051717Y370500D01*
X1051217Y370583D01*
X1050717Y370833D01*
X1050300Y371250D01*
G01X1057400Y370500D02*
Y375500D01*
G01X1061750Y372750D02*
X1064417D01*
X1064167Y373333D01*
X1063750Y373667D01*
X1063167Y373833D01*
X1062583Y373750D01*
X1062083Y373500D01*
X1061750Y372917D01*
X1061583Y372417D01*
Y371917D01*
X1061750Y371417D01*
X1062167Y370917D01*
X1062667Y370583D01*
X1063250Y370500D01*
X1063833Y370667D01*
X1064417Y371167D01*
G01X1074200Y373833D02*
Y370500D01*
G01Y375167D02*
X1074033Y375250D01*
Y375417D01*
X1074200Y375500D01*
X1074367Y375417D01*
Y375250D01*
X1074200Y375167D01*
G01X1078383Y370500D02*
Y373833D01*
G01Y373000D02*
X1078717Y373417D01*
X1079217Y373750D01*
X1079883Y373833D01*
X1080467Y373750D01*
X1080967Y373417D01*
X1081217Y372833D01*
Y370500D01*
G01X1084150Y371083D02*
X1084567Y370750D01*
X1085150Y370500D01*
X1085650D01*
X1086150Y370667D01*
X1086483Y370917D01*
X1086650Y371250D01*
X1086567Y371750D01*
X1086233Y372000D01*
X1084733Y372500D01*
X1084400Y373083D01*
X1084567Y373500D01*
X1084900Y373750D01*
X1085400Y373833D01*
X1085900Y373750D01*
X1086400Y373500D01*
G01X1091000Y373833D02*
Y370500D01*
G01Y375167D02*
X1090833Y375250D01*
Y375417D01*
X1091000Y375500D01*
X1091167Y375417D01*
Y375250D01*
X1091000Y375167D01*
G01X1098100Y375500D02*
Y370500D01*
G01Y371250D02*
X1097767Y370833D01*
X1097267Y370583D01*
X1096683Y370500D01*
X1096017Y370667D01*
X1095517Y371083D01*
X1095183Y371583D01*
X1095100Y372167D01*
X1095183Y372750D01*
X1095517Y373250D01*
X1096017Y373667D01*
X1096683Y373833D01*
X1097267Y373750D01*
X1097683Y373583D01*
X1098100Y373250D01*
G01X1100950Y372750D02*
X1103617D01*
X1103367Y373333D01*
X1102950Y373667D01*
X1102367Y373833D01*
X1101783Y373750D01*
X1101283Y373500D01*
X1100950Y372917D01*
X1100783Y372417D01*
Y371917D01*
X1100950Y371417D01*
X1101367Y370917D01*
X1101867Y370583D01*
X1102450Y370500D01*
X1103033Y370667D01*
X1103617Y371167D01*
G01X1113400Y375500D02*
Y370500D01*
G01X1112233Y373833D02*
X1114567D01*
G01X1117583Y370500D02*
Y375500D01*
G01Y373083D02*
X1118000Y373500D01*
X1118417Y373750D01*
X1119083Y373833D01*
X1119583Y373750D01*
X1120167Y373417D01*
X1120417Y372917D01*
Y370500D01*
G01X1123350Y372750D02*
X1126017D01*
X1125767Y373333D01*
X1125350Y373667D01*
X1124767Y373833D01*
X1124183Y373750D01*
X1123683Y373500D01*
X1123350Y372917D01*
X1123183Y372417D01*
Y371917D01*
X1123350Y371417D01*
X1123767Y370917D01*
X1124267Y370583D01*
X1124850Y370500D01*
X1125433Y370667D01*
X1126017Y371167D01*
G01X1134633Y370500D02*
Y373833D01*
G01Y373167D02*
X1135050Y373500D01*
X1135467Y373750D01*
X1136050Y373833D01*
X1136467Y373750D01*
X1136967Y373500D01*
G01X1140150Y372750D02*
X1142817D01*
X1142567Y373333D01*
X1142150Y373667D01*
X1141567Y373833D01*
X1140983Y373750D01*
X1140483Y373500D01*
X1140150Y372917D01*
X1139983Y372417D01*
Y371917D01*
X1140150Y371417D01*
X1140567Y370917D01*
X1141067Y370583D01*
X1141650Y370500D01*
X1142233Y370667D01*
X1142817Y371167D01*
G01X1145750Y371083D02*
X1146167Y370750D01*
X1146750Y370500D01*
X1147250D01*
X1147750Y370667D01*
X1148083Y370917D01*
X1148250Y371250D01*
X1148167Y371750D01*
X1147833Y372000D01*
X1146333Y372500D01*
X1146000Y373083D01*
X1146167Y373500D01*
X1146500Y373750D01*
X1147000Y373833D01*
X1147500Y373750D01*
X1148000Y373500D01*
G01X1152600Y373833D02*
Y370500D01*
G01Y375167D02*
X1152433Y375250D01*
Y375417D01*
X1152600Y375500D01*
X1152767Y375417D01*
Y375250D01*
X1152600Y375167D01*
G01X1156783Y370500D02*
Y373833D01*
G01Y373000D02*
X1157117Y373417D01*
X1157617Y373750D01*
X1158283Y373833D01*
X1158867Y373750D01*
X1159367Y373417D01*
X1159617Y372833D01*
Y370500D01*
G01X1163800Y370333D02*
X1163633Y370417D01*
Y370583D01*
X1163800Y370667D01*
X1163967Y370583D01*
Y370417D01*
X1163800Y370333D01*
G01X1021417Y383667D02*
X1021917Y384167D01*
X1022500Y384417D01*
X1023167Y384500D01*
X1024000Y384333D01*
X1024583Y383917D01*
X1024750Y383417D01*
X1024667Y382917D01*
X1024333Y382500D01*
X1022667Y381667D01*
X1021917Y381083D01*
X1021417Y380250D01*
X1021250Y379500D01*
X1024750D01*
G01X1028600Y379333D02*
X1028433Y379417D01*
Y379583D01*
X1028600Y379667D01*
X1028767Y379583D01*
Y379417D01*
X1028600Y379333D01*
G01X1032117Y384500D02*
X1034200Y379500D01*
X1036283Y384500D01*
G01X1039800Y382833D02*
Y379500D01*
G01Y384167D02*
X1039633Y384250D01*
Y384417D01*
X1039800Y384500D01*
X1039967Y384417D01*
Y384250D01*
X1039800Y384167D01*
G01X1046900Y379500D02*
Y382833D01*
G01Y382250D02*
X1046567Y382583D01*
X1046067Y382750D01*
X1045483Y382833D01*
X1044900Y382667D01*
X1044400Y382333D01*
X1044067Y381833D01*
X1043900Y381167D01*
X1044067Y380500D01*
X1044400Y380000D01*
X1044900Y379667D01*
X1045483Y379500D01*
X1046067Y379583D01*
X1046567Y379833D01*
X1046900Y380167D01*
G01X1055350Y380083D02*
X1055767Y379750D01*
X1056350Y379500D01*
X1056850D01*
X1057350Y379667D01*
X1057683Y379917D01*
X1057850Y380250D01*
X1057767Y380750D01*
X1057433Y381000D01*
X1055933Y381500D01*
X1055600Y382083D01*
X1055767Y382500D01*
X1056100Y382750D01*
X1056600Y382833D01*
X1057100Y382750D01*
X1057600Y382500D01*
G01X1060783Y379500D02*
Y384500D01*
G01Y382083D02*
X1061200Y382500D01*
X1061617Y382750D01*
X1062283Y382833D01*
X1062783Y382750D01*
X1063367Y382417D01*
X1063617Y381917D01*
Y379500D01*
G01X1067800D02*
X1067300Y379583D01*
X1066800Y379917D01*
X1066467Y380500D01*
X1066300Y381167D01*
X1066467Y381833D01*
X1066800Y382417D01*
X1067300Y382750D01*
X1067800Y382833D01*
X1068300Y382750D01*
X1068800Y382417D01*
X1069133Y381833D01*
X1069217Y381167D01*
X1069133Y380500D01*
X1068800Y379917D01*
X1068300Y379583D01*
X1067800Y379500D01*
G01X1071983Y382833D02*
Y380500D01*
X1072317Y379917D01*
X1072817Y379583D01*
X1073400Y379500D01*
X1073983Y379583D01*
X1074483Y379917D01*
X1074817Y380500D01*
G01Y379500D02*
Y382833D01*
G01X1079000Y379500D02*
Y384500D01*
G01X1086100D02*
Y379500D01*
G01Y380250D02*
X1085767Y379833D01*
X1085267Y379583D01*
X1084683Y379500D01*
X1084017Y379667D01*
X1083517Y380083D01*
X1083183Y380583D01*
X1083100Y381167D01*
X1083183Y381750D01*
X1083517Y382250D01*
X1084017Y382667D01*
X1084683Y382833D01*
X1085267Y382750D01*
X1085683Y382583D01*
X1086100Y382250D01*
G01X1094300Y379500D02*
Y384500D01*
G01Y382000D02*
X1094717Y382500D01*
X1095217Y382750D01*
X1095717Y382833D01*
X1096467Y382667D01*
X1096967Y382333D01*
X1097300Y381750D01*
Y381083D01*
X1097133Y380417D01*
X1096800Y379917D01*
X1096217Y379583D01*
X1095717Y379500D01*
X1095217Y379583D01*
X1094717Y379833D01*
X1094300Y380250D01*
G01X1100150Y381750D02*
X1102817D01*
X1102567Y382333D01*
X1102150Y382667D01*
X1101567Y382833D01*
X1100983Y382750D01*
X1100483Y382500D01*
X1100150Y381917D01*
X1099983Y381417D01*
Y380917D01*
X1100150Y380417D01*
X1100567Y379917D01*
X1101067Y379583D01*
X1101650Y379500D01*
X1102233Y379667D01*
X1102817Y380167D01*
G01X1111100Y377833D02*
Y382833D01*
G01Y382083D02*
X1111517Y382500D01*
X1111933Y382750D01*
X1112600Y382833D01*
X1113183Y382750D01*
X1113767Y382333D01*
X1114017Y381750D01*
X1114100Y381167D01*
X1114017Y380583D01*
X1113767Y380000D01*
X1113267Y379667D01*
X1112600Y379500D01*
X1112017Y379583D01*
X1111433Y379833D01*
X1111100Y380167D01*
G01X1118200Y379500D02*
Y384500D01*
G01X1122383Y382833D02*
Y380500D01*
X1122717Y379917D01*
X1123217Y379583D01*
X1123800Y379500D01*
X1124383Y379583D01*
X1124883Y379917D01*
X1125217Y380500D01*
G01Y379500D02*
Y382833D01*
G01X1128233Y378250D02*
X1128817Y377917D01*
X1129483Y377833D01*
X1130067Y377917D01*
X1130567Y378333D01*
X1130900Y378917D01*
Y382833D01*
G01Y382167D02*
X1130567Y382500D01*
X1130067Y382750D01*
X1129483Y382833D01*
X1128817Y382667D01*
X1128400Y382333D01*
X1128067Y381750D01*
X1127900Y381167D01*
X1127983Y380667D01*
X1128317Y380083D01*
X1128817Y379667D01*
X1129483Y379500D01*
X1129983Y379583D01*
X1130567Y379917D01*
X1130900Y380250D01*
G01X1133833Y378250D02*
X1134417Y377917D01*
X1135083Y377833D01*
X1135667Y377917D01*
X1136167Y378333D01*
X1136500Y378917D01*
Y382833D01*
G01Y382167D02*
X1136167Y382500D01*
X1135667Y382750D01*
X1135083Y382833D01*
X1134417Y382667D01*
X1134000Y382333D01*
X1133667Y381750D01*
X1133500Y381167D01*
X1133583Y380667D01*
X1133917Y380083D01*
X1134417Y379667D01*
X1135083Y379500D01*
X1135583Y379583D01*
X1136167Y379917D01*
X1136500Y380250D01*
G01X1139350Y381750D02*
X1142017D01*
X1141767Y382333D01*
X1141350Y382667D01*
X1140767Y382833D01*
X1140183Y382750D01*
X1139683Y382500D01*
X1139350Y381917D01*
X1139183Y381417D01*
Y380917D01*
X1139350Y380417D01*
X1139767Y379917D01*
X1140267Y379583D01*
X1140850Y379500D01*
X1141433Y379667D01*
X1142017Y380167D01*
G01X1147700Y384500D02*
Y379500D01*
G01Y380250D02*
X1147367Y379833D01*
X1146867Y379583D01*
X1146283Y379500D01*
X1145617Y379667D01*
X1145117Y380083D01*
X1144783Y380583D01*
X1144700Y381167D01*
X1144783Y381750D01*
X1145117Y382250D01*
X1145617Y382667D01*
X1146283Y382833D01*
X1146867Y382750D01*
X1147283Y382583D01*
X1147700Y382250D01*
G01X1155317Y382833D02*
X1156317Y379500D01*
X1157400Y382833D01*
X1158483Y379500D01*
X1159483Y382833D01*
G01X1163000D02*
Y379500D01*
G01Y384167D02*
X1162833Y384250D01*
Y384417D01*
X1163000Y384500D01*
X1163167Y384417D01*
Y384250D01*
X1163000Y384167D01*
G01X1168600Y384500D02*
Y379500D01*
G01X1167433Y382833D02*
X1169767D01*
G01X1172783Y379500D02*
Y384500D01*
G01Y382083D02*
X1173200Y382500D01*
X1173617Y382750D01*
X1174283Y382833D01*
X1174783Y382750D01*
X1175367Y382417D01*
X1175617Y381917D01*
Y379500D01*
G01X1183733D02*
X1187067Y381167D01*
X1183733Y382833D01*
G01X1189583Y380083D02*
X1190167Y379667D01*
X1190833Y379500D01*
X1191500Y379667D01*
X1192083Y380167D01*
X1192500Y380917D01*
X1192667Y381667D01*
Y382583D01*
X1192500Y383333D01*
X1192083Y384000D01*
X1191583Y384333D01*
X1191000Y384500D01*
X1190333Y384333D01*
X1189833Y384000D01*
X1189500Y383500D01*
X1189333Y382833D01*
X1189500Y382250D01*
X1189917Y381667D01*
X1190417Y381333D01*
X1191000Y381250D01*
X1191667Y381417D01*
X1192167Y381833D01*
X1192667Y382583D01*
G01X1196600Y384500D02*
X1195933Y384333D01*
X1195433Y383917D01*
X1195100Y383417D01*
X1194850Y382750D01*
X1194767Y382000D01*
X1194850Y381250D01*
X1195100Y380583D01*
X1195433Y380083D01*
X1195933Y379667D01*
X1196600Y379500D01*
X1197267Y379667D01*
X1197767Y380083D01*
X1198100Y380583D01*
X1198350Y381250D01*
X1198433Y382000D01*
X1198350Y382750D01*
X1198100Y383417D01*
X1197767Y383917D01*
X1197267Y384333D01*
X1196600Y384500D01*
G01X1200700Y379333D02*
X1203700Y384500D01*
G01X1200700D02*
X1200200Y384333D01*
X1199950Y384083D01*
X1199783Y383583D01*
X1199950Y383083D01*
X1200200Y382833D01*
X1200700Y382667D01*
X1201200Y382833D01*
X1201450Y383083D01*
X1201617Y383583D01*
X1201450Y384083D01*
X1201200Y384333D01*
X1200700Y384500D01*
G01X1203700Y381167D02*
X1203200Y381000D01*
X1202950Y380750D01*
X1202783Y380250D01*
X1202950Y379750D01*
X1203200Y379500D01*
X1203700Y379333D01*
X1204200Y379500D01*
X1204450Y379750D01*
X1204617Y380250D01*
X1204450Y380750D01*
X1204200Y381000D01*
X1203700Y381167D01*
G01X1212233Y379500D02*
Y382833D01*
G01Y382167D02*
X1212650Y382500D01*
X1213067Y382750D01*
X1213650Y382833D01*
X1214067Y382750D01*
X1214567Y382500D01*
G01X1217750Y381750D02*
X1220417D01*
X1220167Y382333D01*
X1219750Y382667D01*
X1219167Y382833D01*
X1218583Y382750D01*
X1218083Y382500D01*
X1217750Y381917D01*
X1217583Y381417D01*
Y380917D01*
X1217750Y380417D01*
X1218167Y379917D01*
X1218667Y379583D01*
X1219250Y379500D01*
X1219833Y379667D01*
X1220417Y380167D01*
G01X1223350Y380083D02*
X1223767Y379750D01*
X1224350Y379500D01*
X1224850D01*
X1225350Y379667D01*
X1225683Y379917D01*
X1225850Y380250D01*
X1225767Y380750D01*
X1225433Y381000D01*
X1223933Y381500D01*
X1223600Y382083D01*
X1223767Y382500D01*
X1224100Y382750D01*
X1224600Y382833D01*
X1225100Y382750D01*
X1225600Y382500D01*
G01X1230200Y382833D02*
Y379500D01*
G01Y384167D02*
X1230033Y384250D01*
Y384417D01*
X1230200Y384500D01*
X1230367Y384417D01*
Y384250D01*
X1230200Y384167D01*
G01X1234383Y379500D02*
Y382833D01*
G01Y382000D02*
X1234717Y382417D01*
X1235217Y382750D01*
X1235883Y382833D01*
X1236467Y382750D01*
X1236967Y382417D01*
X1237217Y381833D01*
Y379500D01*
G01X1246417Y378000D02*
X1247583Y379167D01*
Y380333D01*
X1246417D01*
Y379167D01*
X1247583D01*
G01Y381167D02*
Y382333D01*
X1246417D01*
Y381167D01*
X1247583D01*
G01X1250767Y379500D02*
Y384500D01*
X1252433D01*
X1253100Y384250D01*
X1253600Y383917D01*
X1254017Y383417D01*
X1254350Y382833D01*
X1254433Y382000D01*
X1254350Y381167D01*
X1254017Y380583D01*
X1253600Y380083D01*
X1253100Y379750D01*
X1252433Y379500D01*
X1250767D01*
G01X1258200D02*
X1257700Y379583D01*
X1257200Y379917D01*
X1256867Y380500D01*
X1256700Y381167D01*
X1256867Y381833D01*
X1257200Y382417D01*
X1257700Y382750D01*
X1258200Y382833D01*
X1258700Y382750D01*
X1259200Y382417D01*
X1259533Y381833D01*
X1259617Y381167D01*
X1259533Y380500D01*
X1259200Y379917D01*
X1258700Y379583D01*
X1258200Y379500D01*
G01X1267983D02*
Y382833D01*
G01Y382000D02*
X1268317Y382417D01*
X1268817Y382750D01*
X1269483Y382833D01*
X1270067Y382750D01*
X1270567Y382417D01*
X1270817Y381833D01*
Y379500D01*
G01X1275000D02*
X1274500Y379583D01*
X1274000Y379917D01*
X1273667Y380500D01*
X1273500Y381167D01*
X1273667Y381833D01*
X1274000Y382417D01*
X1274500Y382750D01*
X1275000Y382833D01*
X1275500Y382750D01*
X1276000Y382417D01*
X1276333Y381833D01*
X1276417Y381167D01*
X1276333Y380500D01*
X1276000Y379917D01*
X1275500Y379583D01*
X1275000Y379500D01*
G01X1280600Y384500D02*
Y379500D01*
G01X1279433Y382833D02*
X1281767D01*
G01X1293300Y379500D02*
Y382833D01*
G01Y382250D02*
X1292967Y382583D01*
X1292467Y382750D01*
X1291883Y382833D01*
X1291300Y382667D01*
X1290800Y382333D01*
X1290467Y381833D01*
X1290300Y381167D01*
X1290467Y380500D01*
X1290800Y380000D01*
X1291300Y379667D01*
X1291883Y379500D01*
X1292467Y379583D01*
X1292967Y379833D01*
X1293300Y380167D01*
G01X1297400Y379500D02*
Y384500D01*
G01X1303000Y379500D02*
Y384500D01*
G01X1308600Y379500D02*
X1308100Y379583D01*
X1307600Y379917D01*
X1307267Y380500D01*
X1307100Y381167D01*
X1307267Y381833D01*
X1307600Y382417D01*
X1308100Y382750D01*
X1308600Y382833D01*
X1309100Y382750D01*
X1309600Y382417D01*
X1309933Y381833D01*
X1310017Y381167D01*
X1309933Y380500D01*
X1309600Y379917D01*
X1309100Y379583D01*
X1308600Y379500D01*
G01X1312117Y382833D02*
X1313117Y379500D01*
X1314200Y382833D01*
X1315283Y379500D01*
X1316283Y382833D01*
G01X1023000Y390000D02*
Y395000D01*
X1022000Y394000D01*
G01Y390000D02*
X1024000D01*
G01X1028600Y389833D02*
X1028433Y389917D01*
Y390083D01*
X1028600Y390167D01*
X1028767Y390083D01*
Y389917D01*
X1028600Y389833D01*
G01X1032367Y390000D02*
Y395000D01*
X1034033D01*
X1034700Y394750D01*
X1035200Y394417D01*
X1035617Y393917D01*
X1035950Y393333D01*
X1036033Y392500D01*
X1035950Y391667D01*
X1035617Y391083D01*
X1035200Y390583D01*
X1034700Y390250D01*
X1034033Y390000D01*
X1032367D01*
G01X1039800Y393333D02*
Y390000D01*
G01Y394667D02*
X1039633Y394750D01*
Y394917D01*
X1039800Y395000D01*
X1039967Y394917D01*
Y394750D01*
X1039800Y394667D01*
G01X1042900Y390000D02*
Y393333D01*
G01Y392417D02*
X1043150Y392833D01*
X1043567Y393167D01*
X1044150Y393333D01*
X1044733Y393167D01*
X1045150Y392833D01*
X1045400Y392417D01*
Y390000D01*
G01Y392417D02*
X1045650Y392833D01*
X1046067Y393167D01*
X1046650Y393333D01*
X1047233Y393167D01*
X1047650Y392833D01*
X1047900Y392333D01*
Y390000D01*
G01X1049500Y388333D02*
Y393333D01*
G01Y392583D02*
X1049917Y393000D01*
X1050333Y393250D01*
X1051000Y393333D01*
X1051583Y393250D01*
X1052167Y392833D01*
X1052417Y392250D01*
X1052500Y391667D01*
X1052417Y391083D01*
X1052167Y390500D01*
X1051667Y390167D01*
X1051000Y390000D01*
X1050417Y390083D01*
X1049833Y390333D01*
X1049500Y390667D01*
G01X1056600Y390000D02*
Y395000D01*
G01X1060950Y392250D02*
X1063617D01*
X1063367Y392833D01*
X1062950Y393167D01*
X1062367Y393333D01*
X1061783Y393250D01*
X1061283Y393000D01*
X1060950Y392417D01*
X1060783Y391917D01*
Y391417D01*
X1060950Y390917D01*
X1061367Y390417D01*
X1061867Y390083D01*
X1062450Y390000D01*
X1063033Y390167D01*
X1063617Y390667D01*
G01X1075067Y390000D02*
X1071733Y391667D01*
X1075067Y393333D01*
G01X1084600Y390000D02*
Y395000D01*
X1083600Y394000D01*
G01Y390000D02*
X1085600D01*
G01X1093300D02*
Y393333D01*
G01Y392417D02*
X1093550Y392833D01*
X1093967Y393167D01*
X1094550Y393333D01*
X1095133Y393167D01*
X1095550Y392833D01*
X1095800Y392417D01*
Y390000D01*
G01Y392417D02*
X1096050Y392833D01*
X1096467Y393167D01*
X1097050Y393333D01*
X1097633Y393167D01*
X1098050Y392833D01*
X1098300Y392333D01*
Y390000D01*
G01X1101400Y393333D02*
Y390000D01*
G01Y394667D02*
X1101233Y394750D01*
Y394917D01*
X1101400Y395000D01*
X1101567Y394917D01*
Y394750D01*
X1101400Y394667D01*
G01X1107000Y390000D02*
Y395000D01*
G01X1117617Y388500D02*
X1118783Y389667D01*
Y390833D01*
X1117617D01*
Y389667D01*
X1118783D01*
G01Y391667D02*
Y392833D01*
X1117617D01*
Y391667D01*
X1118783D01*
G01X1016000Y604500D02*
Y366000D01*
G01X1033500Y413500D02*
Y418500D01*
G01Y416000D02*
X1033917Y416500D01*
X1034417Y416750D01*
X1034917Y416833D01*
X1035667Y416667D01*
X1036167Y416333D01*
X1036500Y415750D01*
Y415083D01*
X1036333Y414417D01*
X1036000Y413917D01*
X1035417Y413583D01*
X1034917Y413500D01*
X1034417Y413583D01*
X1033917Y413833D01*
X1033500Y414250D01*
G01X1039183Y416833D02*
Y414500D01*
X1039517Y413917D01*
X1040017Y413583D01*
X1040600Y413500D01*
X1041183Y413583D01*
X1041683Y413917D01*
X1042017Y414500D01*
G01Y413500D02*
Y416833D01*
G01X1044700Y413500D02*
Y418500D01*
G01Y416000D02*
X1045117Y416500D01*
X1045617Y416750D01*
X1046117Y416833D01*
X1046867Y416667D01*
X1047367Y416333D01*
X1047700Y415750D01*
Y415083D01*
X1047533Y414417D01*
X1047200Y413917D01*
X1046617Y413583D01*
X1046117Y413500D01*
X1045617Y413583D01*
X1045117Y413833D01*
X1044700Y414250D01*
G01X1050300Y413500D02*
Y418500D01*
G01Y416000D02*
X1050717Y416500D01*
X1051217Y416750D01*
X1051717Y416833D01*
X1052467Y416667D01*
X1052967Y416333D01*
X1053300Y415750D01*
Y415083D01*
X1053133Y414417D01*
X1052800Y413917D01*
X1052217Y413583D01*
X1051717Y413500D01*
X1051217Y413583D01*
X1050717Y413833D01*
X1050300Y414250D01*
G01X1057400Y413500D02*
Y418500D01*
G01X1061750Y415750D02*
X1064417D01*
X1064167Y416333D01*
X1063750Y416667D01*
X1063167Y416833D01*
X1062583Y416750D01*
X1062083Y416500D01*
X1061750Y415917D01*
X1061583Y415417D01*
Y414917D01*
X1061750Y414417D01*
X1062167Y413917D01*
X1062667Y413583D01*
X1063250Y413500D01*
X1063833Y413667D01*
X1064417Y414167D01*
G01X1074200Y416833D02*
Y413500D01*
G01Y418167D02*
X1074033Y418250D01*
Y418417D01*
X1074200Y418500D01*
X1074367Y418417D01*
Y418250D01*
X1074200Y418167D01*
G01X1078383Y413500D02*
Y416833D01*
G01Y416000D02*
X1078717Y416417D01*
X1079217Y416750D01*
X1079883Y416833D01*
X1080467Y416750D01*
X1080967Y416417D01*
X1081217Y415833D01*
Y413500D01*
G01X1084150Y414083D02*
X1084567Y413750D01*
X1085150Y413500D01*
X1085650D01*
X1086150Y413667D01*
X1086483Y413917D01*
X1086650Y414250D01*
X1086567Y414750D01*
X1086233Y415000D01*
X1084733Y415500D01*
X1084400Y416083D01*
X1084567Y416500D01*
X1084900Y416750D01*
X1085400Y416833D01*
X1085900Y416750D01*
X1086400Y416500D01*
G01X1091000Y416833D02*
Y413500D01*
G01Y418167D02*
X1090833Y418250D01*
Y418417D01*
X1091000Y418500D01*
X1091167Y418417D01*
Y418250D01*
X1091000Y418167D01*
G01X1098100Y418500D02*
Y413500D01*
G01Y414250D02*
X1097767Y413833D01*
X1097267Y413583D01*
X1096683Y413500D01*
X1096017Y413667D01*
X1095517Y414083D01*
X1095183Y414583D01*
X1095100Y415167D01*
X1095183Y415750D01*
X1095517Y416250D01*
X1096017Y416667D01*
X1096683Y416833D01*
X1097267Y416750D01*
X1097683Y416583D01*
X1098100Y416250D01*
G01X1100950Y415750D02*
X1103617D01*
X1103367Y416333D01*
X1102950Y416667D01*
X1102367Y416833D01*
X1101783Y416750D01*
X1101283Y416500D01*
X1100950Y415917D01*
X1100783Y415417D01*
Y414917D01*
X1100950Y414417D01*
X1101367Y413917D01*
X1101867Y413583D01*
X1102450Y413500D01*
X1103033Y413667D01*
X1103617Y414167D01*
G01X1113400Y418500D02*
Y413500D01*
G01X1112233Y416833D02*
X1114567D01*
G01X1117583Y413500D02*
Y418500D01*
G01Y416083D02*
X1118000Y416500D01*
X1118417Y416750D01*
X1119083Y416833D01*
X1119583Y416750D01*
X1120167Y416417D01*
X1120417Y415917D01*
Y413500D01*
G01X1123350Y415750D02*
X1126017D01*
X1125767Y416333D01*
X1125350Y416667D01*
X1124767Y416833D01*
X1124183Y416750D01*
X1123683Y416500D01*
X1123350Y415917D01*
X1123183Y415417D01*
Y414917D01*
X1123350Y414417D01*
X1123767Y413917D01*
X1124267Y413583D01*
X1124850Y413500D01*
X1125433Y413667D01*
X1126017Y414167D01*
G01X1134633Y413500D02*
Y416833D01*
G01Y416167D02*
X1135050Y416500D01*
X1135467Y416750D01*
X1136050Y416833D01*
X1136467Y416750D01*
X1136967Y416500D01*
G01X1140150Y415750D02*
X1142817D01*
X1142567Y416333D01*
X1142150Y416667D01*
X1141567Y416833D01*
X1140983Y416750D01*
X1140483Y416500D01*
X1140150Y415917D01*
X1139983Y415417D01*
Y414917D01*
X1140150Y414417D01*
X1140567Y413917D01*
X1141067Y413583D01*
X1141650Y413500D01*
X1142233Y413667D01*
X1142817Y414167D01*
G01X1145750Y414083D02*
X1146167Y413750D01*
X1146750Y413500D01*
X1147250D01*
X1147750Y413667D01*
X1148083Y413917D01*
X1148250Y414250D01*
X1148167Y414750D01*
X1147833Y415000D01*
X1146333Y415500D01*
X1146000Y416083D01*
X1146167Y416500D01*
X1146500Y416750D01*
X1147000Y416833D01*
X1147500Y416750D01*
X1148000Y416500D01*
G01X1152600Y416833D02*
Y413500D01*
G01Y418167D02*
X1152433Y418250D01*
Y418417D01*
X1152600Y418500D01*
X1152767Y418417D01*
Y418250D01*
X1152600Y418167D01*
G01X1156783Y413500D02*
Y416833D01*
G01Y416000D02*
X1157117Y416417D01*
X1157617Y416750D01*
X1158283Y416833D01*
X1158867Y416750D01*
X1159367Y416417D01*
X1159617Y415833D01*
Y413500D01*
G01X1163800Y413333D02*
X1163633Y413417D01*
Y413583D01*
X1163800Y413667D01*
X1163967Y413583D01*
Y413417D01*
X1163800Y413333D01*
G01X1023000Y424000D02*
Y429000D01*
X1022000Y428000D01*
G01Y424000D02*
X1024000D01*
G01X1028600Y423833D02*
X1028433Y423917D01*
Y424083D01*
X1028600Y424167D01*
X1028767Y424083D01*
Y423917D01*
X1028600Y423833D01*
G01X1032117Y429000D02*
X1034200Y424000D01*
X1036283Y429000D01*
G01X1039800Y427333D02*
Y424000D01*
G01Y428667D02*
X1039633Y428750D01*
Y428917D01*
X1039800Y429000D01*
X1039967Y428917D01*
Y428750D01*
X1039800Y428667D01*
G01X1046900Y424000D02*
Y427333D01*
G01Y426750D02*
X1046567Y427083D01*
X1046067Y427250D01*
X1045483Y427333D01*
X1044900Y427167D01*
X1044400Y426833D01*
X1044067Y426333D01*
X1043900Y425667D01*
X1044067Y425000D01*
X1044400Y424500D01*
X1044900Y424167D01*
X1045483Y424000D01*
X1046067Y424083D01*
X1046567Y424333D01*
X1046900Y424667D01*
G01X1055350Y424583D02*
X1055767Y424250D01*
X1056350Y424000D01*
X1056850D01*
X1057350Y424167D01*
X1057683Y424417D01*
X1057850Y424750D01*
X1057767Y425250D01*
X1057433Y425500D01*
X1055933Y426000D01*
X1055600Y426583D01*
X1055767Y427000D01*
X1056100Y427250D01*
X1056600Y427333D01*
X1057100Y427250D01*
X1057600Y427000D01*
G01X1060783Y424000D02*
Y429000D01*
G01Y426583D02*
X1061200Y427000D01*
X1061617Y427250D01*
X1062283Y427333D01*
X1062783Y427250D01*
X1063367Y426917D01*
X1063617Y426417D01*
Y424000D01*
G01X1067800D02*
X1067300Y424083D01*
X1066800Y424417D01*
X1066467Y425000D01*
X1066300Y425667D01*
X1066467Y426333D01*
X1066800Y426917D01*
X1067300Y427250D01*
X1067800Y427333D01*
X1068300Y427250D01*
X1068800Y426917D01*
X1069133Y426333D01*
X1069217Y425667D01*
X1069133Y425000D01*
X1068800Y424417D01*
X1068300Y424083D01*
X1067800Y424000D01*
G01X1071983Y427333D02*
Y425000D01*
X1072317Y424417D01*
X1072817Y424083D01*
X1073400Y424000D01*
X1073983Y424083D01*
X1074483Y424417D01*
X1074817Y425000D01*
G01Y424000D02*
Y427333D01*
G01X1079000Y424000D02*
Y429000D01*
G01X1086100D02*
Y424000D01*
G01Y424750D02*
X1085767Y424333D01*
X1085267Y424083D01*
X1084683Y424000D01*
X1084017Y424167D01*
X1083517Y424583D01*
X1083183Y425083D01*
X1083100Y425667D01*
X1083183Y426250D01*
X1083517Y426750D01*
X1084017Y427167D01*
X1084683Y427333D01*
X1085267Y427250D01*
X1085683Y427083D01*
X1086100Y426750D01*
G01X1094300Y424000D02*
Y429000D01*
G01Y426500D02*
X1094717Y427000D01*
X1095217Y427250D01*
X1095717Y427333D01*
X1096467Y427167D01*
X1096967Y426833D01*
X1097300Y426250D01*
Y425583D01*
X1097133Y424917D01*
X1096800Y424417D01*
X1096217Y424083D01*
X1095717Y424000D01*
X1095217Y424083D01*
X1094717Y424333D01*
X1094300Y424750D01*
G01X1100150Y426250D02*
X1102817D01*
X1102567Y426833D01*
X1102150Y427167D01*
X1101567Y427333D01*
X1100983Y427250D01*
X1100483Y427000D01*
X1100150Y426417D01*
X1099983Y425917D01*
Y425417D01*
X1100150Y424917D01*
X1100567Y424417D01*
X1101067Y424083D01*
X1101650Y424000D01*
X1102233Y424167D01*
X1102817Y424667D01*
G01X1111100Y422333D02*
Y427333D01*
G01Y426583D02*
X1111517Y427000D01*
X1111933Y427250D01*
X1112600Y427333D01*
X1113183Y427250D01*
X1113767Y426833D01*
X1114017Y426250D01*
X1114100Y425667D01*
X1114017Y425083D01*
X1113767Y424500D01*
X1113267Y424167D01*
X1112600Y424000D01*
X1112017Y424083D01*
X1111433Y424333D01*
X1111100Y424667D01*
G01X1118200Y424000D02*
Y429000D01*
G01X1122383Y427333D02*
Y425000D01*
X1122717Y424417D01*
X1123217Y424083D01*
X1123800Y424000D01*
X1124383Y424083D01*
X1124883Y424417D01*
X1125217Y425000D01*
G01Y424000D02*
Y427333D01*
G01X1128233Y422750D02*
X1128817Y422417D01*
X1129483Y422333D01*
X1130067Y422417D01*
X1130567Y422833D01*
X1130900Y423417D01*
Y427333D01*
G01Y426667D02*
X1130567Y427000D01*
X1130067Y427250D01*
X1129483Y427333D01*
X1128817Y427167D01*
X1128400Y426833D01*
X1128067Y426250D01*
X1127900Y425667D01*
X1127983Y425167D01*
X1128317Y424583D01*
X1128817Y424167D01*
X1129483Y424000D01*
X1129983Y424083D01*
X1130567Y424417D01*
X1130900Y424750D01*
G01X1133833Y422750D02*
X1134417Y422417D01*
X1135083Y422333D01*
X1135667Y422417D01*
X1136167Y422833D01*
X1136500Y423417D01*
Y427333D01*
G01Y426667D02*
X1136167Y427000D01*
X1135667Y427250D01*
X1135083Y427333D01*
X1134417Y427167D01*
X1134000Y426833D01*
X1133667Y426250D01*
X1133500Y425667D01*
X1133583Y425167D01*
X1133917Y424583D01*
X1134417Y424167D01*
X1135083Y424000D01*
X1135583Y424083D01*
X1136167Y424417D01*
X1136500Y424750D01*
G01X1139350Y426250D02*
X1142017D01*
X1141767Y426833D01*
X1141350Y427167D01*
X1140767Y427333D01*
X1140183Y427250D01*
X1139683Y427000D01*
X1139350Y426417D01*
X1139183Y425917D01*
Y425417D01*
X1139350Y424917D01*
X1139767Y424417D01*
X1140267Y424083D01*
X1140850Y424000D01*
X1141433Y424167D01*
X1142017Y424667D01*
G01X1147700Y429000D02*
Y424000D01*
G01Y424750D02*
X1147367Y424333D01*
X1146867Y424083D01*
X1146283Y424000D01*
X1145617Y424167D01*
X1145117Y424583D01*
X1144783Y425083D01*
X1144700Y425667D01*
X1144783Y426250D01*
X1145117Y426750D01*
X1145617Y427167D01*
X1146283Y427333D01*
X1146867Y427250D01*
X1147283Y427083D01*
X1147700Y426750D01*
G01X1155317Y427333D02*
X1156317Y424000D01*
X1157400Y427333D01*
X1158483Y424000D01*
X1159483Y427333D01*
G01X1163000D02*
Y424000D01*
G01Y428667D02*
X1162833Y428750D01*
Y428917D01*
X1163000Y429000D01*
X1163167Y428917D01*
Y428750D01*
X1163000Y428667D01*
G01X1168600Y429000D02*
Y424000D01*
G01X1167433Y427333D02*
X1169767D01*
G01X1172783Y424000D02*
Y429000D01*
G01Y426583D02*
X1173200Y427000D01*
X1173617Y427250D01*
X1174283Y427333D01*
X1174783Y427250D01*
X1175367Y426917D01*
X1175617Y426417D01*
Y424000D01*
G01X1183733D02*
X1187067Y425667D01*
X1183733Y427333D01*
G01X1189583Y424583D02*
X1190167Y424167D01*
X1190833Y424000D01*
X1191500Y424167D01*
X1192083Y424667D01*
X1192500Y425417D01*
X1192667Y426167D01*
Y427083D01*
X1192500Y427833D01*
X1192083Y428500D01*
X1191583Y428833D01*
X1191000Y429000D01*
X1190333Y428833D01*
X1189833Y428500D01*
X1189500Y428000D01*
X1189333Y427333D01*
X1189500Y426750D01*
X1189917Y426167D01*
X1190417Y425833D01*
X1191000Y425750D01*
X1191667Y425917D01*
X1192167Y426333D01*
X1192667Y427083D01*
G01X1196600Y429000D02*
X1195933Y428833D01*
X1195433Y428417D01*
X1195100Y427917D01*
X1194850Y427250D01*
X1194767Y426500D01*
X1194850Y425750D01*
X1195100Y425083D01*
X1195433Y424583D01*
X1195933Y424167D01*
X1196600Y424000D01*
X1197267Y424167D01*
X1197767Y424583D01*
X1198100Y425083D01*
X1198350Y425750D01*
X1198433Y426500D01*
X1198350Y427250D01*
X1198100Y427917D01*
X1197767Y428417D01*
X1197267Y428833D01*
X1196600Y429000D01*
G01X1200700Y423833D02*
X1203700Y429000D01*
G01X1200700D02*
X1200200Y428833D01*
X1199950Y428583D01*
X1199783Y428083D01*
X1199950Y427583D01*
X1200200Y427333D01*
X1200700Y427167D01*
X1201200Y427333D01*
X1201450Y427583D01*
X1201617Y428083D01*
X1201450Y428583D01*
X1201200Y428833D01*
X1200700Y429000D01*
G01X1203700Y425667D02*
X1203200Y425500D01*
X1202950Y425250D01*
X1202783Y424750D01*
X1202950Y424250D01*
X1203200Y424000D01*
X1203700Y423833D01*
X1204200Y424000D01*
X1204450Y424250D01*
X1204617Y424750D01*
X1204450Y425250D01*
X1204200Y425500D01*
X1203700Y425667D01*
G01X1212233Y424000D02*
Y427333D01*
G01Y426667D02*
X1212650Y427000D01*
X1213067Y427250D01*
X1213650Y427333D01*
X1214067Y427250D01*
X1214567Y427000D01*
G01X1217750Y426250D02*
X1220417D01*
X1220167Y426833D01*
X1219750Y427167D01*
X1219167Y427333D01*
X1218583Y427250D01*
X1218083Y427000D01*
X1217750Y426417D01*
X1217583Y425917D01*
Y425417D01*
X1217750Y424917D01*
X1218167Y424417D01*
X1218667Y424083D01*
X1219250Y424000D01*
X1219833Y424167D01*
X1220417Y424667D01*
G01X1223350Y424583D02*
X1223767Y424250D01*
X1224350Y424000D01*
X1224850D01*
X1225350Y424167D01*
X1225683Y424417D01*
X1225850Y424750D01*
X1225767Y425250D01*
X1225433Y425500D01*
X1223933Y426000D01*
X1223600Y426583D01*
X1223767Y427000D01*
X1224100Y427250D01*
X1224600Y427333D01*
X1225100Y427250D01*
X1225600Y427000D01*
G01X1230200Y427333D02*
Y424000D01*
G01Y428667D02*
X1230033Y428750D01*
Y428917D01*
X1230200Y429000D01*
X1230367Y428917D01*
Y428750D01*
X1230200Y428667D01*
G01X1234383Y424000D02*
Y427333D01*
G01Y426500D02*
X1234717Y426917D01*
X1235217Y427250D01*
X1235883Y427333D01*
X1236467Y427250D01*
X1236967Y426917D01*
X1237217Y426333D01*
Y424000D01*
G01X1246417Y422500D02*
X1247583Y423667D01*
Y424833D01*
X1246417D01*
Y423667D01*
X1247583D01*
G01Y425667D02*
Y426833D01*
X1246417D01*
Y425667D01*
X1247583D01*
G01X1250767Y424000D02*
Y429000D01*
X1252433D01*
X1253100Y428750D01*
X1253600Y428417D01*
X1254017Y427917D01*
X1254350Y427333D01*
X1254433Y426500D01*
X1254350Y425667D01*
X1254017Y425083D01*
X1253600Y424583D01*
X1253100Y424250D01*
X1252433Y424000D01*
X1250767D01*
G01X1258200D02*
X1257700Y424083D01*
X1257200Y424417D01*
X1256867Y425000D01*
X1256700Y425667D01*
X1256867Y426333D01*
X1257200Y426917D01*
X1257700Y427250D01*
X1258200Y427333D01*
X1258700Y427250D01*
X1259200Y426917D01*
X1259533Y426333D01*
X1259617Y425667D01*
X1259533Y425000D01*
X1259200Y424417D01*
X1258700Y424083D01*
X1258200Y424000D01*
G01X1267983D02*
Y427333D01*
G01Y426500D02*
X1268317Y426917D01*
X1268817Y427250D01*
X1269483Y427333D01*
X1270067Y427250D01*
X1270567Y426917D01*
X1270817Y426333D01*
Y424000D01*
G01X1275000D02*
X1274500Y424083D01*
X1274000Y424417D01*
X1273667Y425000D01*
X1273500Y425667D01*
X1273667Y426333D01*
X1274000Y426917D01*
X1274500Y427250D01*
X1275000Y427333D01*
X1275500Y427250D01*
X1276000Y426917D01*
X1276333Y426333D01*
X1276417Y425667D01*
X1276333Y425000D01*
X1276000Y424417D01*
X1275500Y424083D01*
X1275000Y424000D01*
G01X1280600Y429000D02*
Y424000D01*
G01X1279433Y427333D02*
X1281767D01*
G01X1293300Y424000D02*
Y427333D01*
G01Y426750D02*
X1292967Y427083D01*
X1292467Y427250D01*
X1291883Y427333D01*
X1291300Y427167D01*
X1290800Y426833D01*
X1290467Y426333D01*
X1290300Y425667D01*
X1290467Y425000D01*
X1290800Y424500D01*
X1291300Y424167D01*
X1291883Y424000D01*
X1292467Y424083D01*
X1292967Y424333D01*
X1293300Y424667D01*
G01X1297400Y424000D02*
Y429000D01*
G01X1303000Y424000D02*
Y429000D01*
G01X1308600Y424000D02*
X1308100Y424083D01*
X1307600Y424417D01*
X1307267Y425000D01*
X1307100Y425667D01*
X1307267Y426333D01*
X1307600Y426917D01*
X1308100Y427250D01*
X1308600Y427333D01*
X1309100Y427250D01*
X1309600Y426917D01*
X1309933Y426333D01*
X1310017Y425667D01*
X1309933Y425000D01*
X1309600Y424417D01*
X1309100Y424083D01*
X1308600Y424000D01*
G01X1312117Y427333D02*
X1313117Y424000D01*
X1314200Y427333D01*
X1315283Y424000D01*
X1316283Y427333D01*
G01X1025417Y445500D02*
X1027500Y440500D01*
X1029583Y445500D01*
G01X1033100Y443833D02*
Y440500D01*
G01Y445167D02*
X1032933Y445250D01*
Y445417D01*
X1033100Y445500D01*
X1033267Y445417D01*
Y445250D01*
X1033100Y445167D01*
G01X1040200Y440500D02*
Y443833D01*
G01Y443250D02*
X1039867Y443583D01*
X1039367Y443750D01*
X1038783Y443833D01*
X1038200Y443667D01*
X1037700Y443333D01*
X1037367Y442833D01*
X1037200Y442167D01*
X1037367Y441500D01*
X1037700Y441000D01*
X1038200Y440667D01*
X1038783Y440500D01*
X1039367Y440583D01*
X1039867Y440833D01*
X1040200Y441167D01*
G01X1048650Y441083D02*
X1049067Y440750D01*
X1049650Y440500D01*
X1050150D01*
X1050650Y440667D01*
X1050983Y440917D01*
X1051150Y441250D01*
X1051067Y441750D01*
X1050733Y442000D01*
X1049233Y442500D01*
X1048900Y443083D01*
X1049067Y443500D01*
X1049400Y443750D01*
X1049900Y443833D01*
X1050400Y443750D01*
X1050900Y443500D01*
G01X1054083Y440500D02*
Y445500D01*
G01Y443083D02*
X1054500Y443500D01*
X1054917Y443750D01*
X1055583Y443833D01*
X1056083Y443750D01*
X1056667Y443417D01*
X1056917Y442917D01*
Y440500D01*
G01X1061100D02*
X1060600Y440583D01*
X1060100Y440917D01*
X1059767Y441500D01*
X1059600Y442167D01*
X1059767Y442833D01*
X1060100Y443417D01*
X1060600Y443750D01*
X1061100Y443833D01*
X1061600Y443750D01*
X1062100Y443417D01*
X1062433Y442833D01*
X1062517Y442167D01*
X1062433Y441500D01*
X1062100Y440917D01*
X1061600Y440583D01*
X1061100Y440500D01*
G01X1065283Y443833D02*
Y441500D01*
X1065617Y440917D01*
X1066117Y440583D01*
X1066700Y440500D01*
X1067283Y440583D01*
X1067783Y440917D01*
X1068117Y441500D01*
G01Y440500D02*
Y443833D01*
G01X1072300Y440500D02*
Y445500D01*
G01X1079400D02*
Y440500D01*
G01Y441250D02*
X1079067Y440833D01*
X1078567Y440583D01*
X1077983Y440500D01*
X1077317Y440667D01*
X1076817Y441083D01*
X1076483Y441583D01*
X1076400Y442167D01*
X1076483Y442750D01*
X1076817Y443250D01*
X1077317Y443667D01*
X1077983Y443833D01*
X1078567Y443750D01*
X1078983Y443583D01*
X1079400Y443250D01*
G01X1087600Y440500D02*
Y445500D01*
G01Y443000D02*
X1088017Y443500D01*
X1088517Y443750D01*
X1089017Y443833D01*
X1089767Y443667D01*
X1090267Y443333D01*
X1090600Y442750D01*
Y442083D01*
X1090433Y441417D01*
X1090100Y440917D01*
X1089517Y440583D01*
X1089017Y440500D01*
X1088517Y440583D01*
X1088017Y440833D01*
X1087600Y441250D01*
G01X1093450Y442750D02*
X1096117D01*
X1095867Y443333D01*
X1095450Y443667D01*
X1094867Y443833D01*
X1094283Y443750D01*
X1093783Y443500D01*
X1093450Y442917D01*
X1093283Y442417D01*
Y441917D01*
X1093450Y441417D01*
X1093867Y440917D01*
X1094367Y440583D01*
X1094950Y440500D01*
X1095533Y440667D01*
X1096117Y441167D01*
G01X1104400Y438833D02*
Y443833D01*
G01Y443083D02*
X1104817Y443500D01*
X1105233Y443750D01*
X1105900Y443833D01*
X1106483Y443750D01*
X1107067Y443333D01*
X1107317Y442750D01*
X1107400Y442167D01*
X1107317Y441583D01*
X1107067Y441000D01*
X1106567Y440667D01*
X1105900Y440500D01*
X1105317Y440583D01*
X1104733Y440833D01*
X1104400Y441167D01*
G01X1111500Y440500D02*
Y445500D01*
G01X1115683Y443833D02*
Y441500D01*
X1116017Y440917D01*
X1116517Y440583D01*
X1117100Y440500D01*
X1117683Y440583D01*
X1118183Y440917D01*
X1118517Y441500D01*
G01Y440500D02*
Y443833D01*
G01X1121533Y439250D02*
X1122117Y438917D01*
X1122783Y438833D01*
X1123367Y438917D01*
X1123867Y439333D01*
X1124200Y439917D01*
Y443833D01*
G01Y443167D02*
X1123867Y443500D01*
X1123367Y443750D01*
X1122783Y443833D01*
X1122117Y443667D01*
X1121700Y443333D01*
X1121367Y442750D01*
X1121200Y442167D01*
X1121283Y441667D01*
X1121617Y441083D01*
X1122117Y440667D01*
X1122783Y440500D01*
X1123283Y440583D01*
X1123867Y440917D01*
X1124200Y441250D01*
G01X1127133Y439250D02*
X1127717Y438917D01*
X1128383Y438833D01*
X1128967Y438917D01*
X1129467Y439333D01*
X1129800Y439917D01*
Y443833D01*
G01Y443167D02*
X1129467Y443500D01*
X1128967Y443750D01*
X1128383Y443833D01*
X1127717Y443667D01*
X1127300Y443333D01*
X1126967Y442750D01*
X1126800Y442167D01*
X1126883Y441667D01*
X1127217Y441083D01*
X1127717Y440667D01*
X1128383Y440500D01*
X1128883Y440583D01*
X1129467Y440917D01*
X1129800Y441250D01*
G01X1132650Y442750D02*
X1135317D01*
X1135067Y443333D01*
X1134650Y443667D01*
X1134067Y443833D01*
X1133483Y443750D01*
X1132983Y443500D01*
X1132650Y442917D01*
X1132483Y442417D01*
Y441917D01*
X1132650Y441417D01*
X1133067Y440917D01*
X1133567Y440583D01*
X1134150Y440500D01*
X1134733Y440667D01*
X1135317Y441167D01*
G01X1141000Y445500D02*
Y440500D01*
G01Y441250D02*
X1140667Y440833D01*
X1140167Y440583D01*
X1139583Y440500D01*
X1138917Y440667D01*
X1138417Y441083D01*
X1138083Y441583D01*
X1138000Y442167D01*
X1138083Y442750D01*
X1138417Y443250D01*
X1138917Y443667D01*
X1139583Y443833D01*
X1140167Y443750D01*
X1140583Y443583D01*
X1141000Y443250D01*
G01X1148617Y443833D02*
X1149617Y440500D01*
X1150700Y443833D01*
X1151783Y440500D01*
X1152783Y443833D01*
G01X1156300D02*
Y440500D01*
G01Y445167D02*
X1156133Y445250D01*
Y445417D01*
X1156300Y445500D01*
X1156467Y445417D01*
Y445250D01*
X1156300Y445167D01*
G01X1161900Y445500D02*
Y440500D01*
G01X1160733Y443833D02*
X1163067D01*
G01X1166083Y440500D02*
Y445500D01*
G01Y443083D02*
X1166500Y443500D01*
X1166917Y443750D01*
X1167583Y443833D01*
X1168083Y443750D01*
X1168667Y443417D01*
X1168917Y442917D01*
Y440500D01*
G01X1177033D02*
X1180367Y442167D01*
X1177033Y443833D01*
G01X1182883Y441083D02*
X1183467Y440667D01*
X1184133Y440500D01*
X1184800Y440667D01*
X1185383Y441167D01*
X1185800Y441917D01*
X1185967Y442667D01*
Y443583D01*
X1185800Y444333D01*
X1185383Y445000D01*
X1184883Y445333D01*
X1184300Y445500D01*
X1183633Y445333D01*
X1183133Y445000D01*
X1182800Y444500D01*
X1182633Y443833D01*
X1182800Y443250D01*
X1183217Y442667D01*
X1183717Y442333D01*
X1184300Y442250D01*
X1184967Y442417D01*
X1185467Y442833D01*
X1185967Y443583D01*
G01X1189900Y445500D02*
X1189233Y445333D01*
X1188733Y444917D01*
X1188400Y444417D01*
X1188150Y443750D01*
X1188067Y443000D01*
X1188150Y442250D01*
X1188400Y441583D01*
X1188733Y441083D01*
X1189233Y440667D01*
X1189900Y440500D01*
X1190567Y440667D01*
X1191067Y441083D01*
X1191400Y441583D01*
X1191650Y442250D01*
X1191733Y443000D01*
X1191650Y443750D01*
X1191400Y444417D01*
X1191067Y444917D01*
X1190567Y445333D01*
X1189900Y445500D01*
G01X1194000Y440333D02*
X1197000Y445500D01*
G01X1194000D02*
X1193500Y445333D01*
X1193250Y445083D01*
X1193083Y444583D01*
X1193250Y444083D01*
X1193500Y443833D01*
X1194000Y443667D01*
X1194500Y443833D01*
X1194750Y444083D01*
X1194917Y444583D01*
X1194750Y445083D01*
X1194500Y445333D01*
X1194000Y445500D01*
G01X1197000Y442167D02*
X1196500Y442000D01*
X1196250Y441750D01*
X1196083Y441250D01*
X1196250Y440750D01*
X1196500Y440500D01*
X1197000Y440333D01*
X1197500Y440500D01*
X1197750Y440750D01*
X1197917Y441250D01*
X1197750Y441750D01*
X1197500Y442000D01*
X1197000Y442167D01*
G01X1205533Y440500D02*
Y443833D01*
G01Y443167D02*
X1205950Y443500D01*
X1206367Y443750D01*
X1206950Y443833D01*
X1207367Y443750D01*
X1207867Y443500D01*
G01X1211050Y442750D02*
X1213717D01*
X1213467Y443333D01*
X1213050Y443667D01*
X1212467Y443833D01*
X1211883Y443750D01*
X1211383Y443500D01*
X1211050Y442917D01*
X1210883Y442417D01*
Y441917D01*
X1211050Y441417D01*
X1211467Y440917D01*
X1211967Y440583D01*
X1212550Y440500D01*
X1213133Y440667D01*
X1213717Y441167D01*
G01X1216650Y441083D02*
X1217067Y440750D01*
X1217650Y440500D01*
X1218150D01*
X1218650Y440667D01*
X1218983Y440917D01*
X1219150Y441250D01*
X1219067Y441750D01*
X1218733Y442000D01*
X1217233Y442500D01*
X1216900Y443083D01*
X1217067Y443500D01*
X1217400Y443750D01*
X1217900Y443833D01*
X1218400Y443750D01*
X1218900Y443500D01*
G01X1223500Y443833D02*
Y440500D01*
G01Y445167D02*
X1223333Y445250D01*
Y445417D01*
X1223500Y445500D01*
X1223667Y445417D01*
Y445250D01*
X1223500Y445167D01*
G01X1227683Y440500D02*
Y443833D01*
G01Y443000D02*
X1228017Y443417D01*
X1228517Y443750D01*
X1229183Y443833D01*
X1229767Y443750D01*
X1230267Y443417D01*
X1230517Y442833D01*
Y440500D01*
G01X1023917Y466500D02*
X1026000Y461500D01*
X1028083Y466500D01*
G01X1031600Y464833D02*
Y461500D01*
G01Y466167D02*
X1031433Y466250D01*
Y466417D01*
X1031600Y466500D01*
X1031767Y466417D01*
Y466250D01*
X1031600Y466167D01*
G01X1038700Y461500D02*
Y464833D01*
G01Y464250D02*
X1038367Y464583D01*
X1037867Y464750D01*
X1037283Y464833D01*
X1036700Y464667D01*
X1036200Y464333D01*
X1035867Y463833D01*
X1035700Y463167D01*
X1035867Y462500D01*
X1036200Y462000D01*
X1036700Y461667D01*
X1037283Y461500D01*
X1037867Y461583D01*
X1038367Y461833D01*
X1038700Y462167D01*
G01X1047150Y462083D02*
X1047567Y461750D01*
X1048150Y461500D01*
X1048650D01*
X1049150Y461667D01*
X1049483Y461917D01*
X1049650Y462250D01*
X1049567Y462750D01*
X1049233Y463000D01*
X1047733Y463500D01*
X1047400Y464083D01*
X1047567Y464500D01*
X1047900Y464750D01*
X1048400Y464833D01*
X1048900Y464750D01*
X1049400Y464500D01*
G01X1052583Y461500D02*
Y466500D01*
G01Y464083D02*
X1053000Y464500D01*
X1053417Y464750D01*
X1054083Y464833D01*
X1054583Y464750D01*
X1055167Y464417D01*
X1055417Y463917D01*
Y461500D01*
G01X1059600D02*
X1059100Y461583D01*
X1058600Y461917D01*
X1058267Y462500D01*
X1058100Y463167D01*
X1058267Y463833D01*
X1058600Y464417D01*
X1059100Y464750D01*
X1059600Y464833D01*
X1060100Y464750D01*
X1060600Y464417D01*
X1060933Y463833D01*
X1061017Y463167D01*
X1060933Y462500D01*
X1060600Y461917D01*
X1060100Y461583D01*
X1059600Y461500D01*
G01X1063783Y464833D02*
Y462500D01*
X1064117Y461917D01*
X1064617Y461583D01*
X1065200Y461500D01*
X1065783Y461583D01*
X1066283Y461917D01*
X1066617Y462500D01*
G01Y461500D02*
Y464833D01*
G01X1070800Y461500D02*
Y466500D01*
G01X1077900D02*
Y461500D01*
G01Y462250D02*
X1077567Y461833D01*
X1077067Y461583D01*
X1076483Y461500D01*
X1075817Y461667D01*
X1075317Y462083D01*
X1074983Y462583D01*
X1074900Y463167D01*
X1074983Y463750D01*
X1075317Y464250D01*
X1075817Y464667D01*
X1076483Y464833D01*
X1077067Y464750D01*
X1077483Y464583D01*
X1077900Y464250D01*
G01X1086100Y461500D02*
Y466500D01*
G01Y464000D02*
X1086517Y464500D01*
X1087017Y464750D01*
X1087517Y464833D01*
X1088267Y464667D01*
X1088767Y464333D01*
X1089100Y463750D01*
Y463083D01*
X1088933Y462417D01*
X1088600Y461917D01*
X1088017Y461583D01*
X1087517Y461500D01*
X1087017Y461583D01*
X1086517Y461833D01*
X1086100Y462250D01*
G01X1091950Y463750D02*
X1094617D01*
X1094367Y464333D01*
X1093950Y464667D01*
X1093367Y464833D01*
X1092783Y464750D01*
X1092283Y464500D01*
X1091950Y463917D01*
X1091783Y463417D01*
Y462917D01*
X1091950Y462417D01*
X1092367Y461917D01*
X1092867Y461583D01*
X1093450Y461500D01*
X1094033Y461667D01*
X1094617Y462167D01*
G01X1102900Y459833D02*
Y464833D01*
G01Y464083D02*
X1103317Y464500D01*
X1103733Y464750D01*
X1104400Y464833D01*
X1104983Y464750D01*
X1105567Y464333D01*
X1105817Y463750D01*
X1105900Y463167D01*
X1105817Y462583D01*
X1105567Y462000D01*
X1105067Y461667D01*
X1104400Y461500D01*
X1103817Y461583D01*
X1103233Y461833D01*
X1102900Y462167D01*
G01X1110000Y461500D02*
Y466500D01*
G01X1114183Y464833D02*
Y462500D01*
X1114517Y461917D01*
X1115017Y461583D01*
X1115600Y461500D01*
X1116183Y461583D01*
X1116683Y461917D01*
X1117017Y462500D01*
G01Y461500D02*
Y464833D01*
G01X1120033Y460250D02*
X1120617Y459917D01*
X1121283Y459833D01*
X1121867Y459917D01*
X1122367Y460333D01*
X1122700Y460917D01*
Y464833D01*
G01Y464167D02*
X1122367Y464500D01*
X1121867Y464750D01*
X1121283Y464833D01*
X1120617Y464667D01*
X1120200Y464333D01*
X1119867Y463750D01*
X1119700Y463167D01*
X1119783Y462667D01*
X1120117Y462083D01*
X1120617Y461667D01*
X1121283Y461500D01*
X1121783Y461583D01*
X1122367Y461917D01*
X1122700Y462250D01*
G01X1125633Y460250D02*
X1126217Y459917D01*
X1126883Y459833D01*
X1127467Y459917D01*
X1127967Y460333D01*
X1128300Y460917D01*
Y464833D01*
G01Y464167D02*
X1127967Y464500D01*
X1127467Y464750D01*
X1126883Y464833D01*
X1126217Y464667D01*
X1125800Y464333D01*
X1125467Y463750D01*
X1125300Y463167D01*
X1125383Y462667D01*
X1125717Y462083D01*
X1126217Y461667D01*
X1126883Y461500D01*
X1127383Y461583D01*
X1127967Y461917D01*
X1128300Y462250D01*
G01X1131150Y463750D02*
X1133817D01*
X1133567Y464333D01*
X1133150Y464667D01*
X1132567Y464833D01*
X1131983Y464750D01*
X1131483Y464500D01*
X1131150Y463917D01*
X1130983Y463417D01*
Y462917D01*
X1131150Y462417D01*
X1131567Y461917D01*
X1132067Y461583D01*
X1132650Y461500D01*
X1133233Y461667D01*
X1133817Y462167D01*
G01X1139500Y466500D02*
Y461500D01*
G01Y462250D02*
X1139167Y461833D01*
X1138667Y461583D01*
X1138083Y461500D01*
X1137417Y461667D01*
X1136917Y462083D01*
X1136583Y462583D01*
X1136500Y463167D01*
X1136583Y463750D01*
X1136917Y464250D01*
X1137417Y464667D01*
X1138083Y464833D01*
X1138667Y464750D01*
X1139083Y464583D01*
X1139500Y464250D01*
G01X1150200Y461500D02*
Y466500D01*
X1147117Y462917D01*
X1151283D01*
G01X1154800Y466500D02*
X1154133Y466333D01*
X1153633Y465917D01*
X1153300Y465417D01*
X1153050Y464750D01*
X1152967Y464000D01*
X1153050Y463250D01*
X1153300Y462583D01*
X1153633Y462083D01*
X1154133Y461667D01*
X1154800Y461500D01*
X1155467Y461667D01*
X1155967Y462083D01*
X1156300Y462583D01*
X1156550Y463250D01*
X1156633Y464000D01*
X1156550Y464750D01*
X1156300Y465417D01*
X1155967Y465917D01*
X1155467Y466333D01*
X1154800Y466500D01*
G01X1158900Y461333D02*
X1161900Y466500D01*
G01X1158900D02*
X1158400Y466333D01*
X1158150Y466083D01*
X1157983Y465583D01*
X1158150Y465083D01*
X1158400Y464833D01*
X1158900Y464667D01*
X1159400Y464833D01*
X1159650Y465083D01*
X1159817Y465583D01*
X1159650Y466083D01*
X1159400Y466333D01*
X1158900Y466500D01*
G01X1161900Y463167D02*
X1161400Y463000D01*
X1161150Y462750D01*
X1160983Y462250D01*
X1161150Y461750D01*
X1161400Y461500D01*
X1161900Y461333D01*
X1162400Y461500D01*
X1162650Y461750D01*
X1162817Y462250D01*
X1162650Y462750D01*
X1162400Y463000D01*
X1161900Y463167D01*
G01X1169100D02*
X1169933Y464833D01*
X1170767D01*
X1172433Y461500D01*
X1173267D01*
X1174100Y463167D01*
G01X1182800Y461500D02*
Y466500D01*
X1181800Y465500D01*
G01Y461500D02*
X1183800D01*
G01X1188400Y466500D02*
X1187733Y466333D01*
X1187233Y465917D01*
X1186900Y465417D01*
X1186650Y464750D01*
X1186567Y464000D01*
X1186650Y463250D01*
X1186900Y462583D01*
X1187233Y462083D01*
X1187733Y461667D01*
X1188400Y461500D01*
X1189067Y461667D01*
X1189567Y462083D01*
X1189900Y462583D01*
X1190150Y463250D01*
X1190233Y464000D01*
X1190150Y464750D01*
X1189900Y465417D01*
X1189567Y465917D01*
X1189067Y466333D01*
X1188400Y466500D01*
G01X1194000D02*
X1193333Y466333D01*
X1192833Y465917D01*
X1192500Y465417D01*
X1192250Y464750D01*
X1192167Y464000D01*
X1192250Y463250D01*
X1192500Y462583D01*
X1192833Y462083D01*
X1193333Y461667D01*
X1194000Y461500D01*
X1194667Y461667D01*
X1195167Y462083D01*
X1195500Y462583D01*
X1195750Y463250D01*
X1195833Y464000D01*
X1195750Y464750D01*
X1195500Y465417D01*
X1195167Y465917D01*
X1194667Y466333D01*
X1194000Y466500D01*
G01X1198100Y461333D02*
X1201100Y466500D01*
G01X1198100D02*
X1197600Y466333D01*
X1197350Y466083D01*
X1197183Y465583D01*
X1197350Y465083D01*
X1197600Y464833D01*
X1198100Y464667D01*
X1198600Y464833D01*
X1198850Y465083D01*
X1199017Y465583D01*
X1198850Y466083D01*
X1198600Y466333D01*
X1198100Y466500D01*
G01X1201100Y463167D02*
X1200600Y463000D01*
X1200350Y462750D01*
X1200183Y462250D01*
X1200350Y461750D01*
X1200600Y461500D01*
X1201100Y461333D01*
X1201600Y461500D01*
X1201850Y461750D01*
X1202017Y462250D01*
X1201850Y462750D01*
X1201600Y463000D01*
X1201100Y463167D01*
G01X1209550Y462083D02*
X1209967Y461750D01*
X1210550Y461500D01*
X1211050D01*
X1211550Y461667D01*
X1211883Y461917D01*
X1212050Y462250D01*
X1211967Y462750D01*
X1211633Y463000D01*
X1210133Y463500D01*
X1209800Y464083D01*
X1209967Y464500D01*
X1210300Y464750D01*
X1210800Y464833D01*
X1211300Y464750D01*
X1211800Y464500D01*
G01X1216400Y461500D02*
X1215900Y461583D01*
X1215400Y461917D01*
X1215067Y462500D01*
X1214900Y463167D01*
X1215067Y463833D01*
X1215400Y464417D01*
X1215900Y464750D01*
X1216400Y464833D01*
X1216900Y464750D01*
X1217400Y464417D01*
X1217733Y463833D01*
X1217817Y463167D01*
X1217733Y462500D01*
X1217400Y461917D01*
X1216900Y461583D01*
X1216400Y461500D01*
G01X1222000D02*
Y466500D01*
G01X1229100D02*
Y461500D01*
G01Y462250D02*
X1228767Y461833D01*
X1228267Y461583D01*
X1227683Y461500D01*
X1227017Y461667D01*
X1226517Y462083D01*
X1226183Y462583D01*
X1226100Y463167D01*
X1226183Y463750D01*
X1226517Y464250D01*
X1227017Y464667D01*
X1227683Y464833D01*
X1228267Y464750D01*
X1228683Y464583D01*
X1229100Y464250D01*
G01X1231950Y463750D02*
X1234617D01*
X1234367Y464333D01*
X1233950Y464667D01*
X1233367Y464833D01*
X1232783Y464750D01*
X1232283Y464500D01*
X1231950Y463917D01*
X1231783Y463417D01*
Y462917D01*
X1231950Y462417D01*
X1232367Y461917D01*
X1232867Y461583D01*
X1233450Y461500D01*
X1234033Y461667D01*
X1234617Y462167D01*
G01X1237633Y461500D02*
Y464833D01*
G01Y464167D02*
X1238050Y464500D01*
X1238467Y464750D01*
X1239050Y464833D01*
X1239467Y464750D01*
X1239967Y464500D01*
G01X1247500Y461500D02*
Y464833D01*
G01Y463917D02*
X1247750Y464333D01*
X1248167Y464667D01*
X1248750Y464833D01*
X1249333Y464667D01*
X1249750Y464333D01*
X1250000Y463917D01*
Y461500D01*
G01Y463917D02*
X1250250Y464333D01*
X1250667Y464667D01*
X1251250Y464833D01*
X1251833Y464667D01*
X1252250Y464333D01*
X1252500Y463833D01*
Y461500D01*
G01X1257100D02*
Y464833D01*
G01Y464250D02*
X1256767Y464583D01*
X1256267Y464750D01*
X1255683Y464833D01*
X1255100Y464667D01*
X1254600Y464333D01*
X1254267Y463833D01*
X1254100Y463167D01*
X1254267Y462500D01*
X1254600Y462000D01*
X1255100Y461667D01*
X1255683Y461500D01*
X1256267Y461583D01*
X1256767Y461833D01*
X1257100Y462167D01*
G01X1259950Y462083D02*
X1260367Y461750D01*
X1260950Y461500D01*
X1261450D01*
X1261950Y461667D01*
X1262283Y461917D01*
X1262450Y462250D01*
X1262367Y462750D01*
X1262033Y463000D01*
X1260533Y463500D01*
X1260200Y464083D01*
X1260367Y464500D01*
X1260700Y464750D01*
X1261200Y464833D01*
X1261700Y464750D01*
X1262200Y464500D01*
G01X1265383Y461500D02*
Y466500D01*
G01X1268050Y464833D02*
X1265383Y462917D01*
G01X1266467Y463667D02*
X1268217Y461500D01*
G01X1046500Y485833D02*
X1048000Y482500D01*
X1049500Y485833D01*
G01X1053600D02*
Y482500D01*
G01Y487167D02*
X1053433Y487250D01*
Y487417D01*
X1053600Y487500D01*
X1053767Y487417D01*
Y487250D01*
X1053600Y487167D01*
G01X1060700Y482500D02*
Y485833D01*
G01Y485250D02*
X1060367Y485583D01*
X1059867Y485750D01*
X1059283Y485833D01*
X1058700Y485667D01*
X1058200Y485333D01*
X1057867Y484833D01*
X1057700Y484167D01*
X1057867Y483500D01*
X1058200Y483000D01*
X1058700Y482667D01*
X1059283Y482500D01*
X1059867Y482583D01*
X1060367Y482833D01*
X1060700Y483167D01*
G01X1069150Y483083D02*
X1069567Y482750D01*
X1070150Y482500D01*
X1070650D01*
X1071150Y482667D01*
X1071483Y482917D01*
X1071650Y483250D01*
X1071567Y483750D01*
X1071233Y484000D01*
X1069733Y484500D01*
X1069400Y485083D01*
X1069567Y485500D01*
X1069900Y485750D01*
X1070400Y485833D01*
X1070900Y485750D01*
X1071400Y485500D01*
G01X1074583Y482500D02*
Y487500D01*
G01Y485083D02*
X1075000Y485500D01*
X1075417Y485750D01*
X1076083Y485833D01*
X1076583Y485750D01*
X1077167Y485417D01*
X1077417Y484917D01*
Y482500D01*
G01X1083100D02*
Y485833D01*
G01Y485250D02*
X1082767Y485583D01*
X1082267Y485750D01*
X1081683Y485833D01*
X1081100Y485667D01*
X1080600Y485333D01*
X1080267Y484833D01*
X1080100Y484167D01*
X1080267Y483500D01*
X1080600Y483000D01*
X1081100Y482667D01*
X1081683Y482500D01*
X1082267Y482583D01*
X1082767Y482833D01*
X1083100Y483167D01*
G01X1087200Y482500D02*
Y487500D01*
G01X1092800Y482500D02*
Y487500D01*
G01X1102500Y482500D02*
Y487500D01*
G01Y485000D02*
X1102917Y485500D01*
X1103417Y485750D01*
X1103917Y485833D01*
X1104667Y485667D01*
X1105167Y485333D01*
X1105500Y484750D01*
Y484083D01*
X1105333Y483417D01*
X1105000Y482917D01*
X1104417Y482583D01*
X1103917Y482500D01*
X1103417Y482583D01*
X1102917Y482833D01*
X1102500Y483250D01*
G01X1108350Y484750D02*
X1111017D01*
X1110767Y485333D01*
X1110350Y485667D01*
X1109767Y485833D01*
X1109183Y485750D01*
X1108683Y485500D01*
X1108350Y484917D01*
X1108183Y484417D01*
Y483917D01*
X1108350Y483417D01*
X1108767Y482917D01*
X1109267Y482583D01*
X1109850Y482500D01*
X1110433Y482667D01*
X1111017Y483167D01*
G01X1118717Y485833D02*
X1119717Y482500D01*
X1120800Y485833D01*
X1121883Y482500D01*
X1122883Y485833D01*
G01X1126400D02*
Y482500D01*
G01Y487167D02*
X1126233Y487250D01*
Y487417D01*
X1126400Y487500D01*
X1126567Y487417D01*
Y487250D01*
X1126400Y487167D01*
G01X1132000Y487500D02*
Y482500D01*
G01X1130833Y485833D02*
X1133167D01*
G01X1136183Y482500D02*
Y487500D01*
G01Y485083D02*
X1136600Y485500D01*
X1137017Y485750D01*
X1137683Y485833D01*
X1138183Y485750D01*
X1138767Y485417D01*
X1139017Y484917D01*
Y482500D01*
G01X1150467D02*
X1147133Y484167D01*
X1150467Y485833D01*
G01X1160000Y482500D02*
X1160583Y482583D01*
X1161250Y482833D01*
X1161667Y483250D01*
X1161833Y483833D01*
X1161667Y484417D01*
X1161167Y484917D01*
X1160417Y485167D01*
X1159583D01*
X1159083Y485333D01*
X1158667Y485750D01*
X1158500Y486333D01*
X1158750Y486917D01*
X1159333Y487333D01*
X1160000Y487500D01*
X1160667Y487333D01*
X1161250Y486917D01*
X1161500Y486333D01*
X1161333Y485750D01*
X1160917Y485333D01*
X1160417Y485167D01*
X1159583D01*
X1158833Y484917D01*
X1158333Y484417D01*
X1158167Y483833D01*
X1158333Y483250D01*
X1158750Y482833D01*
X1159417Y482583D01*
X1160000Y482500D01*
G01X1165600Y487500D02*
X1164933Y487333D01*
X1164433Y486917D01*
X1164100Y486417D01*
X1163850Y485750D01*
X1163767Y485000D01*
X1163850Y484250D01*
X1164100Y483583D01*
X1164433Y483083D01*
X1164933Y482667D01*
X1165600Y482500D01*
X1166267Y482667D01*
X1166767Y483083D01*
X1167100Y483583D01*
X1167350Y484250D01*
X1167433Y485000D01*
X1167350Y485750D01*
X1167100Y486417D01*
X1166767Y486917D01*
X1166267Y487333D01*
X1165600Y487500D01*
G01X1175300Y482333D02*
X1178300Y487500D01*
G01X1175300D02*
X1174800Y487333D01*
X1174550Y487083D01*
X1174383Y486583D01*
X1174550Y486083D01*
X1174800Y485833D01*
X1175300Y485667D01*
X1175800Y485833D01*
X1176050Y486083D01*
X1176217Y486583D01*
X1176050Y487083D01*
X1175800Y487333D01*
X1175300Y487500D01*
G01X1178300Y484167D02*
X1177800Y484000D01*
X1177550Y483750D01*
X1177383Y483250D01*
X1177550Y482750D01*
X1177800Y482500D01*
X1178300Y482333D01*
X1178800Y482500D01*
X1179050Y482750D01*
X1179217Y483250D01*
X1179050Y483750D01*
X1178800Y484000D01*
X1178300Y484167D01*
G01X1186750Y483083D02*
X1187167Y482750D01*
X1187750Y482500D01*
X1188250D01*
X1188750Y482667D01*
X1189083Y482917D01*
X1189250Y483250D01*
X1189167Y483750D01*
X1188833Y484000D01*
X1187333Y484500D01*
X1187000Y485083D01*
X1187167Y485500D01*
X1187500Y485750D01*
X1188000Y485833D01*
X1188500Y485750D01*
X1189000Y485500D01*
G01X1193600Y482500D02*
X1193100Y482583D01*
X1192600Y482917D01*
X1192267Y483500D01*
X1192100Y484167D01*
X1192267Y484833D01*
X1192600Y485417D01*
X1193100Y485750D01*
X1193600Y485833D01*
X1194100Y485750D01*
X1194600Y485417D01*
X1194933Y484833D01*
X1195017Y484167D01*
X1194933Y483500D01*
X1194600Y482917D01*
X1194100Y482583D01*
X1193600Y482500D01*
G01X1199200D02*
Y487500D01*
G01X1206300D02*
Y482500D01*
G01Y483250D02*
X1205967Y482833D01*
X1205467Y482583D01*
X1204883Y482500D01*
X1204217Y482667D01*
X1203717Y483083D01*
X1203383Y483583D01*
X1203300Y484167D01*
X1203383Y484750D01*
X1203717Y485250D01*
X1204217Y485667D01*
X1204883Y485833D01*
X1205467Y485750D01*
X1205883Y485583D01*
X1206300Y485250D01*
G01X1209150Y484750D02*
X1211817D01*
X1211567Y485333D01*
X1211150Y485667D01*
X1210567Y485833D01*
X1209983Y485750D01*
X1209483Y485500D01*
X1209150Y484917D01*
X1208983Y484417D01*
Y483917D01*
X1209150Y483417D01*
X1209567Y482917D01*
X1210067Y482583D01*
X1210650Y482500D01*
X1211233Y482667D01*
X1211817Y483167D01*
G01X1214833Y482500D02*
Y485833D01*
G01Y485167D02*
X1215250Y485500D01*
X1215667Y485750D01*
X1216250Y485833D01*
X1216667Y485750D01*
X1217167Y485500D01*
G01X1224700Y482500D02*
Y485833D01*
G01Y484917D02*
X1224950Y485333D01*
X1225367Y485667D01*
X1225950Y485833D01*
X1226533Y485667D01*
X1226950Y485333D01*
X1227200Y484917D01*
Y482500D01*
G01Y484917D02*
X1227450Y485333D01*
X1227867Y485667D01*
X1228450Y485833D01*
X1229033Y485667D01*
X1229450Y485333D01*
X1229700Y484833D01*
Y482500D01*
G01X1234300D02*
Y485833D01*
G01Y485250D02*
X1233967Y485583D01*
X1233467Y485750D01*
X1232883Y485833D01*
X1232300Y485667D01*
X1231800Y485333D01*
X1231467Y484833D01*
X1231300Y484167D01*
X1231467Y483500D01*
X1231800Y483000D01*
X1232300Y482667D01*
X1232883Y482500D01*
X1233467Y482583D01*
X1233967Y482833D01*
X1234300Y483167D01*
G01X1237150Y483083D02*
X1237567Y482750D01*
X1238150Y482500D01*
X1238650D01*
X1239150Y482667D01*
X1239483Y482917D01*
X1239650Y483250D01*
X1239567Y483750D01*
X1239233Y484000D01*
X1237733Y484500D01*
X1237400Y485083D01*
X1237567Y485500D01*
X1237900Y485750D01*
X1238400Y485833D01*
X1238900Y485750D01*
X1239400Y485500D01*
G01X1242583Y482500D02*
Y487500D01*
G01X1245250Y485833D02*
X1242583Y483917D01*
G01X1243667Y484667D02*
X1245417Y482500D01*
G01X1035500Y491500D02*
Y496500D01*
G01Y494000D02*
X1035917Y494500D01*
X1036417Y494750D01*
X1036917Y494833D01*
X1037667Y494667D01*
X1038167Y494333D01*
X1038500Y493750D01*
Y493083D01*
X1038333Y492417D01*
X1038000Y491917D01*
X1037417Y491583D01*
X1036917Y491500D01*
X1036417Y491583D01*
X1035917Y491833D01*
X1035500Y492250D01*
G01X1042600Y491333D02*
X1042433Y491417D01*
Y491583D01*
X1042600Y491667D01*
X1042767Y491583D01*
Y491417D01*
X1042600Y491333D01*
G01X1048867Y494167D02*
X1049200Y494417D01*
X1049450Y494833D01*
X1049617Y495417D01*
X1049450Y495917D01*
X1049117Y496250D01*
X1048533Y496500D01*
X1046283D01*
Y491500D01*
X1049033D01*
X1049617Y491833D01*
X1049950Y492333D01*
X1050117Y492917D01*
X1049950Y493500D01*
X1049450Y494000D01*
X1048867Y494167D01*
X1046283D01*
G01X1053800Y491500D02*
X1053300Y491583D01*
X1052800Y491917D01*
X1052467Y492500D01*
X1052300Y493167D01*
X1052467Y493833D01*
X1052800Y494417D01*
X1053300Y494750D01*
X1053800Y494833D01*
X1054300Y494750D01*
X1054800Y494417D01*
X1055133Y493833D01*
X1055217Y493167D01*
X1055133Y492500D01*
X1054800Y491917D01*
X1054300Y491583D01*
X1053800Y491500D01*
G01X1060900D02*
Y494833D01*
G01Y494250D02*
X1060567Y494583D01*
X1060067Y494750D01*
X1059483Y494833D01*
X1058900Y494667D01*
X1058400Y494333D01*
X1058067Y493833D01*
X1057900Y493167D01*
X1058067Y492500D01*
X1058400Y492000D01*
X1058900Y491667D01*
X1059483Y491500D01*
X1060067Y491583D01*
X1060567Y491833D01*
X1060900Y492167D01*
G01X1063833Y491500D02*
Y494833D01*
G01Y494167D02*
X1064250Y494500D01*
X1064667Y494750D01*
X1065250Y494833D01*
X1065667Y494750D01*
X1066167Y494500D01*
G01X1072100Y496500D02*
Y491500D01*
G01Y492250D02*
X1071767Y491833D01*
X1071267Y491583D01*
X1070683Y491500D01*
X1070017Y491667D01*
X1069517Y492083D01*
X1069183Y492583D01*
X1069100Y493167D01*
X1069183Y493750D01*
X1069517Y494250D01*
X1070017Y494667D01*
X1070683Y494833D01*
X1071267Y494750D01*
X1071683Y494583D01*
X1072100Y494250D01*
G01X1081800Y496500D02*
Y491500D01*
G01X1080633Y494833D02*
X1082967D01*
G01X1085983Y491500D02*
Y496500D01*
G01Y494083D02*
X1086400Y494500D01*
X1086817Y494750D01*
X1087483Y494833D01*
X1087983Y494750D01*
X1088567Y494417D01*
X1088817Y493917D01*
Y491500D01*
G01X1093000Y494833D02*
Y491500D01*
G01Y496167D02*
X1092833Y496250D01*
Y496417D01*
X1093000Y496500D01*
X1093167Y496417D01*
Y496250D01*
X1093000Y496167D01*
G01X1099933Y494417D02*
X1099350Y494750D01*
X1098850Y494833D01*
X1098183Y494667D01*
X1097683Y494333D01*
X1097350Y493750D01*
X1097267Y493167D01*
X1097350Y492583D01*
X1097683Y492083D01*
X1098183Y491667D01*
X1098850Y491500D01*
X1099433Y491667D01*
X1099933Y492000D01*
G01X1102783Y491500D02*
Y496500D01*
G01X1105450Y494833D02*
X1102783Y492917D01*
G01X1103867Y493667D02*
X1105617Y491500D01*
G01X1108383D02*
Y494833D01*
G01Y494000D02*
X1108717Y494417D01*
X1109217Y494750D01*
X1109883Y494833D01*
X1110467Y494750D01*
X1110967Y494417D01*
X1111217Y493833D01*
Y491500D01*
G01X1114150Y493750D02*
X1116817D01*
X1116567Y494333D01*
X1116150Y494667D01*
X1115567Y494833D01*
X1114983Y494750D01*
X1114483Y494500D01*
X1114150Y493917D01*
X1113983Y493417D01*
Y492917D01*
X1114150Y492417D01*
X1114567Y491917D01*
X1115067Y491583D01*
X1115650Y491500D01*
X1116233Y491667D01*
X1116817Y492167D01*
G01X1119750Y492083D02*
X1120167Y491750D01*
X1120750Y491500D01*
X1121250D01*
X1121750Y491667D01*
X1122083Y491917D01*
X1122250Y492250D01*
X1122167Y492750D01*
X1121833Y493000D01*
X1120333Y493500D01*
X1120000Y494083D01*
X1120167Y494500D01*
X1120500Y494750D01*
X1121000Y494833D01*
X1121500Y494750D01*
X1122000Y494500D01*
G01X1125350Y492083D02*
X1125767Y491750D01*
X1126350Y491500D01*
X1126850D01*
X1127350Y491667D01*
X1127683Y491917D01*
X1127850Y492250D01*
X1127767Y492750D01*
X1127433Y493000D01*
X1125933Y493500D01*
X1125600Y494083D01*
X1125767Y494500D01*
X1126100Y494750D01*
X1126600Y494833D01*
X1127100Y494750D01*
X1127600Y494500D01*
G01X1139467Y491500D02*
X1136133Y493167D01*
X1139467Y494833D01*
G01X1149000Y496500D02*
X1148333Y496333D01*
X1147833Y495917D01*
X1147500Y495417D01*
X1147250Y494750D01*
X1147167Y494000D01*
X1147250Y493250D01*
X1147500Y492583D01*
X1147833Y492083D01*
X1148333Y491667D01*
X1149000Y491500D01*
X1149667Y491667D01*
X1150167Y492083D01*
X1150500Y492583D01*
X1150750Y493250D01*
X1150833Y494000D01*
X1150750Y494750D01*
X1150500Y495417D01*
X1150167Y495917D01*
X1149667Y496333D01*
X1149000Y496500D01*
G01X1154600Y491333D02*
X1154433Y491417D01*
Y491583D01*
X1154600Y491667D01*
X1154767Y491583D01*
Y491417D01*
X1154600Y491333D01*
G01X1158783Y492083D02*
X1159367Y491667D01*
X1160033Y491500D01*
X1160700Y491667D01*
X1161283Y492167D01*
X1161700Y492917D01*
X1161867Y493667D01*
Y494583D01*
X1161700Y495333D01*
X1161283Y496000D01*
X1160783Y496333D01*
X1160200Y496500D01*
X1159533Y496333D01*
X1159033Y496000D01*
X1158700Y495500D01*
X1158533Y494833D01*
X1158700Y494250D01*
X1159117Y493667D01*
X1159617Y493333D01*
X1160200Y493250D01*
X1160867Y493417D01*
X1161367Y493833D01*
X1161867Y494583D01*
G01X1163300Y491500D02*
Y494833D01*
G01Y493917D02*
X1163550Y494333D01*
X1163967Y494667D01*
X1164550Y494833D01*
X1165133Y494667D01*
X1165550Y494333D01*
X1165800Y493917D01*
Y491500D01*
G01Y493917D02*
X1166050Y494333D01*
X1166467Y494667D01*
X1167050Y494833D01*
X1167633Y494667D01*
X1168050Y494333D01*
X1168300Y493833D01*
Y491500D01*
G01X1168900D02*
Y494833D01*
G01Y493917D02*
X1169150Y494333D01*
X1169567Y494667D01*
X1170150Y494833D01*
X1170733Y494667D01*
X1171150Y494333D01*
X1171400Y493917D01*
Y491500D01*
G01Y493917D02*
X1171650Y494333D01*
X1172067Y494667D01*
X1172650Y494833D01*
X1173233Y494667D01*
X1173650Y494333D01*
X1173900Y493833D01*
Y491500D01*
G01X1177000Y491333D02*
X1176833Y491417D01*
Y491583D01*
X1177000Y491667D01*
X1177167Y491583D01*
Y491417D01*
X1177000Y491333D01*
G01Y493583D02*
X1176833Y493667D01*
Y493833D01*
X1177000Y493917D01*
X1177167Y493833D01*
Y493667D01*
X1177000Y493583D01*
G01X1045500Y504833D02*
X1047000Y501500D01*
X1048500Y504833D01*
G01X1052600D02*
Y501500D01*
G01Y506167D02*
X1052433Y506250D01*
Y506417D01*
X1052600Y506500D01*
X1052767Y506417D01*
Y506250D01*
X1052600Y506167D01*
G01X1059700Y501500D02*
Y504833D01*
G01Y504250D02*
X1059367Y504583D01*
X1058867Y504750D01*
X1058283Y504833D01*
X1057700Y504667D01*
X1057200Y504333D01*
X1056867Y503833D01*
X1056700Y503167D01*
X1056867Y502500D01*
X1057200Y502000D01*
X1057700Y501667D01*
X1058283Y501500D01*
X1058867Y501583D01*
X1059367Y501833D01*
X1059700Y502167D01*
G01X1068150Y502083D02*
X1068567Y501750D01*
X1069150Y501500D01*
X1069650D01*
X1070150Y501667D01*
X1070483Y501917D01*
X1070650Y502250D01*
X1070567Y502750D01*
X1070233Y503000D01*
X1068733Y503500D01*
X1068400Y504083D01*
X1068567Y504500D01*
X1068900Y504750D01*
X1069400Y504833D01*
X1069900Y504750D01*
X1070400Y504500D01*
G01X1073583Y501500D02*
Y506500D01*
G01Y504083D02*
X1074000Y504500D01*
X1074417Y504750D01*
X1075083Y504833D01*
X1075583Y504750D01*
X1076167Y504417D01*
X1076417Y503917D01*
Y501500D01*
G01X1082100D02*
Y504833D01*
G01Y504250D02*
X1081767Y504583D01*
X1081267Y504750D01*
X1080683Y504833D01*
X1080100Y504667D01*
X1079600Y504333D01*
X1079267Y503833D01*
X1079100Y503167D01*
X1079267Y502500D01*
X1079600Y502000D01*
X1080100Y501667D01*
X1080683Y501500D01*
X1081267Y501583D01*
X1081767Y501833D01*
X1082100Y502167D01*
G01X1086200Y501500D02*
Y506500D01*
G01X1091800Y501500D02*
Y506500D01*
G01X1101500Y501500D02*
Y506500D01*
G01Y504000D02*
X1101917Y504500D01*
X1102417Y504750D01*
X1102917Y504833D01*
X1103667Y504667D01*
X1104167Y504333D01*
X1104500Y503750D01*
Y503083D01*
X1104333Y502417D01*
X1104000Y501917D01*
X1103417Y501583D01*
X1102917Y501500D01*
X1102417Y501583D01*
X1101917Y501833D01*
X1101500Y502250D01*
G01X1107350Y503750D02*
X1110017D01*
X1109767Y504333D01*
X1109350Y504667D01*
X1108767Y504833D01*
X1108183Y504750D01*
X1107683Y504500D01*
X1107350Y503917D01*
X1107183Y503417D01*
Y502917D01*
X1107350Y502417D01*
X1107767Y501917D01*
X1108267Y501583D01*
X1108850Y501500D01*
X1109433Y501667D01*
X1110017Y502167D01*
G01X1118300Y499833D02*
Y504833D01*
G01Y504083D02*
X1118717Y504500D01*
X1119133Y504750D01*
X1119800Y504833D01*
X1120383Y504750D01*
X1120967Y504333D01*
X1121217Y503750D01*
X1121300Y503167D01*
X1121217Y502583D01*
X1120967Y502000D01*
X1120467Y501667D01*
X1119800Y501500D01*
X1119217Y501583D01*
X1118633Y501833D01*
X1118300Y502167D01*
G01X1125400Y501500D02*
Y506500D01*
G01X1129583Y504833D02*
Y502500D01*
X1129917Y501917D01*
X1130417Y501583D01*
X1131000Y501500D01*
X1131583Y501583D01*
X1132083Y501917D01*
X1132417Y502500D01*
G01Y501500D02*
Y504833D01*
G01X1135433Y500250D02*
X1136017Y499917D01*
X1136683Y499833D01*
X1137267Y499917D01*
X1137767Y500333D01*
X1138100Y500917D01*
Y504833D01*
G01Y504167D02*
X1137767Y504500D01*
X1137267Y504750D01*
X1136683Y504833D01*
X1136017Y504667D01*
X1135600Y504333D01*
X1135267Y503750D01*
X1135100Y503167D01*
X1135183Y502667D01*
X1135517Y502083D01*
X1136017Y501667D01*
X1136683Y501500D01*
X1137183Y501583D01*
X1137767Y501917D01*
X1138100Y502250D01*
G01X1141033Y500250D02*
X1141617Y499917D01*
X1142283Y499833D01*
X1142867Y499917D01*
X1143367Y500333D01*
X1143700Y500917D01*
Y504833D01*
G01Y504167D02*
X1143367Y504500D01*
X1142867Y504750D01*
X1142283Y504833D01*
X1141617Y504667D01*
X1141200Y504333D01*
X1140867Y503750D01*
X1140700Y503167D01*
X1140783Y502667D01*
X1141117Y502083D01*
X1141617Y501667D01*
X1142283Y501500D01*
X1142783Y501583D01*
X1143367Y501917D01*
X1143700Y502250D01*
G01X1146550Y503750D02*
X1149217D01*
X1148967Y504333D01*
X1148550Y504667D01*
X1147967Y504833D01*
X1147383Y504750D01*
X1146883Y504500D01*
X1146550Y503917D01*
X1146383Y503417D01*
Y502917D01*
X1146550Y502417D01*
X1146967Y501917D01*
X1147467Y501583D01*
X1148050Y501500D01*
X1148633Y501667D01*
X1149217Y502167D01*
G01X1154900Y506500D02*
Y501500D01*
G01Y502250D02*
X1154567Y501833D01*
X1154067Y501583D01*
X1153483Y501500D01*
X1152817Y501667D01*
X1152317Y502083D01*
X1151983Y502583D01*
X1151900Y503167D01*
X1151983Y503750D01*
X1152317Y504250D01*
X1152817Y504667D01*
X1153483Y504833D01*
X1154067Y504750D01*
X1154483Y504583D01*
X1154900Y504250D01*
G01X1162517Y504833D02*
X1163517Y501500D01*
X1164600Y504833D01*
X1165683Y501500D01*
X1166683Y504833D01*
G01X1170200D02*
Y501500D01*
G01Y506167D02*
X1170033Y506250D01*
Y506417D01*
X1170200Y506500D01*
X1170367Y506417D01*
Y506250D01*
X1170200Y506167D01*
G01X1175800Y506500D02*
Y501500D01*
G01X1174633Y504833D02*
X1176967D01*
G01X1179983Y501500D02*
Y506500D01*
G01Y504083D02*
X1180400Y504500D01*
X1180817Y504750D01*
X1181483Y504833D01*
X1181983Y504750D01*
X1182567Y504417D01*
X1182817Y503917D01*
Y501500D01*
G01X1194267D02*
X1190933Y503167D01*
X1194267Y504833D01*
G01X1201967Y502250D02*
X1202467Y501833D01*
X1203050Y501583D01*
X1203800Y501500D01*
X1204550Y501667D01*
X1205133Y502000D01*
X1205550Y502583D01*
X1205633Y503250D01*
X1205467Y503917D01*
X1205050Y504333D01*
X1204467Y504667D01*
X1203883Y504750D01*
X1203300Y504667D01*
X1202550Y504333D01*
X1202800Y506500D01*
X1205050D01*
G01X1209400D02*
X1208733Y506333D01*
X1208233Y505917D01*
X1207900Y505417D01*
X1207650Y504750D01*
X1207567Y504000D01*
X1207650Y503250D01*
X1207900Y502583D01*
X1208233Y502083D01*
X1208733Y501667D01*
X1209400Y501500D01*
X1210067Y501667D01*
X1210567Y502083D01*
X1210900Y502583D01*
X1211150Y503250D01*
X1211233Y504000D01*
X1211150Y504750D01*
X1210900Y505417D01*
X1210567Y505917D01*
X1210067Y506333D01*
X1209400Y506500D01*
G01X1219100Y501333D02*
X1222100Y506500D01*
G01X1219100D02*
X1218600Y506333D01*
X1218350Y506083D01*
X1218183Y505583D01*
X1218350Y505083D01*
X1218600Y504833D01*
X1219100Y504667D01*
X1219600Y504833D01*
X1219850Y505083D01*
X1220017Y505583D01*
X1219850Y506083D01*
X1219600Y506333D01*
X1219100Y506500D01*
G01X1222100Y503167D02*
X1221600Y503000D01*
X1221350Y502750D01*
X1221183Y502250D01*
X1221350Y501750D01*
X1221600Y501500D01*
X1222100Y501333D01*
X1222600Y501500D01*
X1222850Y501750D01*
X1223017Y502250D01*
X1222850Y502750D01*
X1222600Y503000D01*
X1222100Y503167D01*
G01X1230550Y502083D02*
X1230967Y501750D01*
X1231550Y501500D01*
X1232050D01*
X1232550Y501667D01*
X1232883Y501917D01*
X1233050Y502250D01*
X1232967Y502750D01*
X1232633Y503000D01*
X1231133Y503500D01*
X1230800Y504083D01*
X1230967Y504500D01*
X1231300Y504750D01*
X1231800Y504833D01*
X1232300Y504750D01*
X1232800Y504500D01*
G01X1237400Y501500D02*
X1236900Y501583D01*
X1236400Y501917D01*
X1236067Y502500D01*
X1235900Y503167D01*
X1236067Y503833D01*
X1236400Y504417D01*
X1236900Y504750D01*
X1237400Y504833D01*
X1237900Y504750D01*
X1238400Y504417D01*
X1238733Y503833D01*
X1238817Y503167D01*
X1238733Y502500D01*
X1238400Y501917D01*
X1237900Y501583D01*
X1237400Y501500D01*
G01X1243000D02*
Y506500D01*
G01X1250100D02*
Y501500D01*
G01Y502250D02*
X1249767Y501833D01*
X1249267Y501583D01*
X1248683Y501500D01*
X1248017Y501667D01*
X1247517Y502083D01*
X1247183Y502583D01*
X1247100Y503167D01*
X1247183Y503750D01*
X1247517Y504250D01*
X1248017Y504667D01*
X1248683Y504833D01*
X1249267Y504750D01*
X1249683Y504583D01*
X1250100Y504250D01*
G01X1252950Y503750D02*
X1255617D01*
X1255367Y504333D01*
X1254950Y504667D01*
X1254367Y504833D01*
X1253783Y504750D01*
X1253283Y504500D01*
X1252950Y503917D01*
X1252783Y503417D01*
Y502917D01*
X1252950Y502417D01*
X1253367Y501917D01*
X1253867Y501583D01*
X1254450Y501500D01*
X1255033Y501667D01*
X1255617Y502167D01*
G01X1258633Y501500D02*
Y504833D01*
G01Y504167D02*
X1259050Y504500D01*
X1259467Y504750D01*
X1260050Y504833D01*
X1260467Y504750D01*
X1260967Y504500D01*
G01X1268500Y501500D02*
Y504833D01*
G01Y503917D02*
X1268750Y504333D01*
X1269167Y504667D01*
X1269750Y504833D01*
X1270333Y504667D01*
X1270750Y504333D01*
X1271000Y503917D01*
Y501500D01*
G01Y503917D02*
X1271250Y504333D01*
X1271667Y504667D01*
X1272250Y504833D01*
X1272833Y504667D01*
X1273250Y504333D01*
X1273500Y503833D01*
Y501500D01*
G01X1278100D02*
Y504833D01*
G01Y504250D02*
X1277767Y504583D01*
X1277267Y504750D01*
X1276683Y504833D01*
X1276100Y504667D01*
X1275600Y504333D01*
X1275267Y503833D01*
X1275100Y503167D01*
X1275267Y502500D01*
X1275600Y502000D01*
X1276100Y501667D01*
X1276683Y501500D01*
X1277267Y501583D01*
X1277767Y501833D01*
X1278100Y502167D01*
G01X1280950Y502083D02*
X1281367Y501750D01*
X1281950Y501500D01*
X1282450D01*
X1282950Y501667D01*
X1283283Y501917D01*
X1283450Y502250D01*
X1283367Y502750D01*
X1283033Y503000D01*
X1281533Y503500D01*
X1281200Y504083D01*
X1281367Y504500D01*
X1281700Y504750D01*
X1282200Y504833D01*
X1282700Y504750D01*
X1283200Y504500D01*
G01X1286383Y501500D02*
Y506500D01*
G01X1289050Y504833D02*
X1286383Y502917D01*
G01X1287467Y503667D02*
X1289217Y501500D01*
G01X1293233Y500583D02*
X1293567Y501667D01*
G01X1038500Y510500D02*
Y513833D01*
G01Y513250D02*
X1038167Y513583D01*
X1037667Y513750D01*
X1037083Y513833D01*
X1036500Y513667D01*
X1036000Y513333D01*
X1035667Y512833D01*
X1035500Y512167D01*
X1035667Y511500D01*
X1036000Y511000D01*
X1036500Y510667D01*
X1037083Y510500D01*
X1037667Y510583D01*
X1038167Y510833D01*
X1038500Y511167D01*
G01X1042600Y510333D02*
X1042433Y510417D01*
Y510583D01*
X1042600Y510667D01*
X1042767Y510583D01*
Y510417D01*
X1042600Y510333D01*
G01X1048867Y513167D02*
X1049200Y513417D01*
X1049450Y513833D01*
X1049617Y514417D01*
X1049450Y514917D01*
X1049117Y515250D01*
X1048533Y515500D01*
X1046283D01*
Y510500D01*
X1049033D01*
X1049617Y510833D01*
X1049950Y511333D01*
X1050117Y511917D01*
X1049950Y512500D01*
X1049450Y513000D01*
X1048867Y513167D01*
X1046283D01*
G01X1053800Y510500D02*
X1053300Y510583D01*
X1052800Y510917D01*
X1052467Y511500D01*
X1052300Y512167D01*
X1052467Y512833D01*
X1052800Y513417D01*
X1053300Y513750D01*
X1053800Y513833D01*
X1054300Y513750D01*
X1054800Y513417D01*
X1055133Y512833D01*
X1055217Y512167D01*
X1055133Y511500D01*
X1054800Y510917D01*
X1054300Y510583D01*
X1053800Y510500D01*
G01X1060900D02*
Y513833D01*
G01Y513250D02*
X1060567Y513583D01*
X1060067Y513750D01*
X1059483Y513833D01*
X1058900Y513667D01*
X1058400Y513333D01*
X1058067Y512833D01*
X1057900Y512167D01*
X1058067Y511500D01*
X1058400Y511000D01*
X1058900Y510667D01*
X1059483Y510500D01*
X1060067Y510583D01*
X1060567Y510833D01*
X1060900Y511167D01*
G01X1063833Y510500D02*
Y513833D01*
G01Y513167D02*
X1064250Y513500D01*
X1064667Y513750D01*
X1065250Y513833D01*
X1065667Y513750D01*
X1066167Y513500D01*
G01X1072100Y515500D02*
Y510500D01*
G01Y511250D02*
X1071767Y510833D01*
X1071267Y510583D01*
X1070683Y510500D01*
X1070017Y510667D01*
X1069517Y511083D01*
X1069183Y511583D01*
X1069100Y512167D01*
X1069183Y512750D01*
X1069517Y513250D01*
X1070017Y513667D01*
X1070683Y513833D01*
X1071267Y513750D01*
X1071683Y513583D01*
X1072100Y513250D01*
G01X1081800Y515500D02*
Y510500D01*
G01X1080633Y513833D02*
X1082967D01*
G01X1085983Y510500D02*
Y515500D01*
G01Y513083D02*
X1086400Y513500D01*
X1086817Y513750D01*
X1087483Y513833D01*
X1087983Y513750D01*
X1088567Y513417D01*
X1088817Y512917D01*
Y510500D01*
G01X1093000Y513833D02*
Y510500D01*
G01Y515167D02*
X1092833Y515250D01*
Y515417D01*
X1093000Y515500D01*
X1093167Y515417D01*
Y515250D01*
X1093000Y515167D01*
G01X1099933Y513417D02*
X1099350Y513750D01*
X1098850Y513833D01*
X1098183Y513667D01*
X1097683Y513333D01*
X1097350Y512750D01*
X1097267Y512167D01*
X1097350Y511583D01*
X1097683Y511083D01*
X1098183Y510667D01*
X1098850Y510500D01*
X1099433Y510667D01*
X1099933Y511000D01*
G01X1102783Y510500D02*
Y515500D01*
G01X1105450Y513833D02*
X1102783Y511917D01*
G01X1103867Y512667D02*
X1105617Y510500D01*
G01X1108383D02*
Y513833D01*
G01Y513000D02*
X1108717Y513417D01*
X1109217Y513750D01*
X1109883Y513833D01*
X1110467Y513750D01*
X1110967Y513417D01*
X1111217Y512833D01*
Y510500D01*
G01X1114150Y512750D02*
X1116817D01*
X1116567Y513333D01*
X1116150Y513667D01*
X1115567Y513833D01*
X1114983Y513750D01*
X1114483Y513500D01*
X1114150Y512917D01*
X1113983Y512417D01*
Y511917D01*
X1114150Y511417D01*
X1114567Y510917D01*
X1115067Y510583D01*
X1115650Y510500D01*
X1116233Y510667D01*
X1116817Y511167D01*
G01X1119750Y511083D02*
X1120167Y510750D01*
X1120750Y510500D01*
X1121250D01*
X1121750Y510667D01*
X1122083Y510917D01*
X1122250Y511250D01*
X1122167Y511750D01*
X1121833Y512000D01*
X1120333Y512500D01*
X1120000Y513083D01*
X1120167Y513500D01*
X1120500Y513750D01*
X1121000Y513833D01*
X1121500Y513750D01*
X1122000Y513500D01*
G01X1125350Y511083D02*
X1125767Y510750D01*
X1126350Y510500D01*
X1126850D01*
X1127350Y510667D01*
X1127683Y510917D01*
X1127850Y511250D01*
X1127767Y511750D01*
X1127433Y512000D01*
X1125933Y512500D01*
X1125600Y513083D01*
X1125767Y513500D01*
X1126100Y513750D01*
X1126600Y513833D01*
X1127100Y513750D01*
X1127600Y513500D01*
G01X1130533Y510500D02*
X1133867Y512167D01*
X1130533Y513833D01*
G01X1136717Y511417D02*
X1138883D01*
G01Y512917D02*
X1136717D01*
G01X1149000Y515500D02*
X1148333Y515333D01*
X1147833Y514917D01*
X1147500Y514417D01*
X1147250Y513750D01*
X1147167Y513000D01*
X1147250Y512250D01*
X1147500Y511583D01*
X1147833Y511083D01*
X1148333Y510667D01*
X1149000Y510500D01*
X1149667Y510667D01*
X1150167Y511083D01*
X1150500Y511583D01*
X1150750Y512250D01*
X1150833Y513000D01*
X1150750Y513750D01*
X1150500Y514417D01*
X1150167Y514917D01*
X1149667Y515333D01*
X1149000Y515500D01*
G01X1154600Y510333D02*
X1154433Y510417D01*
Y510583D01*
X1154600Y510667D01*
X1154767Y510583D01*
Y510417D01*
X1154600Y510333D01*
G01X1158783Y511083D02*
X1159367Y510667D01*
X1160033Y510500D01*
X1160700Y510667D01*
X1161283Y511167D01*
X1161700Y511917D01*
X1161867Y512667D01*
Y513583D01*
X1161700Y514333D01*
X1161283Y515000D01*
X1160783Y515333D01*
X1160200Y515500D01*
X1159533Y515333D01*
X1159033Y515000D01*
X1158700Y514500D01*
X1158533Y513833D01*
X1158700Y513250D01*
X1159117Y512667D01*
X1159617Y512333D01*
X1160200Y512250D01*
X1160867Y512417D01*
X1161367Y512833D01*
X1161867Y513583D01*
G01X1163300Y510500D02*
Y513833D01*
G01Y512917D02*
X1163550Y513333D01*
X1163967Y513667D01*
X1164550Y513833D01*
X1165133Y513667D01*
X1165550Y513333D01*
X1165800Y512917D01*
Y510500D01*
G01Y512917D02*
X1166050Y513333D01*
X1166467Y513667D01*
X1167050Y513833D01*
X1167633Y513667D01*
X1168050Y513333D01*
X1168300Y512833D01*
Y510500D01*
G01X1171400Y510333D02*
X1171233Y510417D01*
Y510583D01*
X1171400Y510667D01*
X1171567Y510583D01*
Y510417D01*
X1171400Y510333D01*
G01Y512583D02*
X1171233Y512667D01*
Y512833D01*
X1171400Y512917D01*
X1171567Y512833D01*
Y512667D01*
X1171400Y512583D01*
G01X1034250Y520500D02*
Y525500D01*
G01X1037750D02*
Y520500D01*
G01Y523000D02*
X1034250D01*
G01X1043100Y520500D02*
Y523833D01*
G01Y523250D02*
X1042767Y523583D01*
X1042267Y523750D01*
X1041683Y523833D01*
X1041100Y523667D01*
X1040600Y523333D01*
X1040267Y522833D01*
X1040100Y522167D01*
X1040267Y521500D01*
X1040600Y521000D01*
X1041100Y520667D01*
X1041683Y520500D01*
X1042267Y520583D01*
X1042767Y520833D01*
X1043100Y521167D01*
G01X1047200Y520500D02*
Y525500D01*
G01X1052300Y520500D02*
Y524750D01*
X1052467Y525167D01*
X1052800Y525417D01*
X1053300Y525500D01*
X1053800Y525333D01*
X1054050Y524917D01*
G01X1053050Y523500D02*
X1051383D01*
G01X1057317Y522167D02*
X1059483D01*
G01X1062500Y518833D02*
Y523833D01*
G01Y523083D02*
X1062917Y523500D01*
X1063333Y523750D01*
X1064000Y523833D01*
X1064583Y523750D01*
X1065167Y523333D01*
X1065417Y522750D01*
X1065500Y522167D01*
X1065417Y521583D01*
X1065167Y521000D01*
X1064667Y520667D01*
X1064000Y520500D01*
X1063417Y520583D01*
X1062833Y520833D01*
X1062500Y521167D01*
G01X1069600Y520500D02*
Y525500D01*
G01X1073783Y523833D02*
Y521500D01*
X1074117Y520917D01*
X1074617Y520583D01*
X1075200Y520500D01*
X1075783Y520583D01*
X1076283Y520917D01*
X1076617Y521500D01*
G01Y520500D02*
Y523833D01*
G01X1079633Y519250D02*
X1080217Y518917D01*
X1080883Y518833D01*
X1081467Y518917D01*
X1081967Y519333D01*
X1082300Y519917D01*
Y523833D01*
G01Y523167D02*
X1081967Y523500D01*
X1081467Y523750D01*
X1080883Y523833D01*
X1080217Y523667D01*
X1079800Y523333D01*
X1079467Y522750D01*
X1079300Y522167D01*
X1079383Y521667D01*
X1079717Y521083D01*
X1080217Y520667D01*
X1080883Y520500D01*
X1081383Y520583D01*
X1081967Y520917D01*
X1082300Y521250D01*
G01X1085233Y519250D02*
X1085817Y518917D01*
X1086483Y518833D01*
X1087067Y518917D01*
X1087567Y519333D01*
X1087900Y519917D01*
Y523833D01*
G01Y523167D02*
X1087567Y523500D01*
X1087067Y523750D01*
X1086483Y523833D01*
X1085817Y523667D01*
X1085400Y523333D01*
X1085067Y522750D01*
X1084900Y522167D01*
X1084983Y521667D01*
X1085317Y521083D01*
X1085817Y520667D01*
X1086483Y520500D01*
X1086983Y520583D01*
X1087567Y520917D01*
X1087900Y521250D01*
G01X1092000Y523833D02*
Y520500D01*
G01Y525167D02*
X1091833Y525250D01*
Y525417D01*
X1092000Y525500D01*
X1092167Y525417D01*
Y525250D01*
X1092000Y525167D01*
G01X1096183Y520500D02*
Y523833D01*
G01Y523000D02*
X1096517Y523417D01*
X1097017Y523750D01*
X1097683Y523833D01*
X1098267Y523750D01*
X1098767Y523417D01*
X1099017Y522833D01*
Y520500D01*
G01X1102033Y519250D02*
X1102617Y518917D01*
X1103283Y518833D01*
X1103867Y518917D01*
X1104367Y519333D01*
X1104700Y519917D01*
Y523833D01*
G01Y523167D02*
X1104367Y523500D01*
X1103867Y523750D01*
X1103283Y523833D01*
X1102617Y523667D01*
X1102200Y523333D01*
X1101867Y522750D01*
X1101700Y522167D01*
X1101783Y521667D01*
X1102117Y521083D01*
X1102617Y520667D01*
X1103283Y520500D01*
X1103783Y520583D01*
X1104367Y520917D01*
X1104700Y521250D01*
G01X1114400Y520333D02*
X1114233Y520417D01*
Y520583D01*
X1114400Y520667D01*
X1114567Y520583D01*
Y520417D01*
X1114400Y520333D01*
G01Y522583D02*
X1114233Y522667D01*
Y522833D01*
X1114400Y522917D01*
X1114567Y522833D01*
Y522667D01*
X1114400Y522583D01*
G01X1125600Y525500D02*
Y520500D01*
G01X1124433Y523833D02*
X1126767D01*
G01X1129783Y520500D02*
Y525500D01*
G01Y523083D02*
X1130200Y523500D01*
X1130617Y523750D01*
X1131283Y523833D01*
X1131783Y523750D01*
X1132367Y523417D01*
X1132617Y522917D01*
Y520500D01*
G01X1135550Y522750D02*
X1138217D01*
X1137967Y523333D01*
X1137550Y523667D01*
X1136967Y523833D01*
X1136383Y523750D01*
X1135883Y523500D01*
X1135550Y522917D01*
X1135383Y522417D01*
Y521917D01*
X1135550Y521417D01*
X1135967Y520917D01*
X1136467Y520583D01*
X1137050Y520500D01*
X1137633Y520667D01*
X1138217Y521167D01*
G01X1146500Y518833D02*
Y523833D01*
G01Y523083D02*
X1146917Y523500D01*
X1147333Y523750D01*
X1148000Y523833D01*
X1148583Y523750D01*
X1149167Y523333D01*
X1149417Y522750D01*
X1149500Y522167D01*
X1149417Y521583D01*
X1149167Y521000D01*
X1148667Y520667D01*
X1148000Y520500D01*
X1147417Y520583D01*
X1146833Y520833D01*
X1146500Y521167D01*
G01X1153600Y520500D02*
Y525500D01*
G01X1157783Y523833D02*
Y521500D01*
X1158117Y520917D01*
X1158617Y520583D01*
X1159200Y520500D01*
X1159783Y520583D01*
X1160283Y520917D01*
X1160617Y521500D01*
G01Y520500D02*
Y523833D01*
G01X1163633Y519250D02*
X1164217Y518917D01*
X1164883Y518833D01*
X1165467Y518917D01*
X1165967Y519333D01*
X1166300Y519917D01*
Y523833D01*
G01Y523167D02*
X1165967Y523500D01*
X1165467Y523750D01*
X1164883Y523833D01*
X1164217Y523667D01*
X1163800Y523333D01*
X1163467Y522750D01*
X1163300Y522167D01*
X1163383Y521667D01*
X1163717Y521083D01*
X1164217Y520667D01*
X1164883Y520500D01*
X1165383Y520583D01*
X1165967Y520917D01*
X1166300Y521250D01*
G01X1169233Y519250D02*
X1169817Y518917D01*
X1170483Y518833D01*
X1171067Y518917D01*
X1171567Y519333D01*
X1171900Y519917D01*
Y523833D01*
G01Y523167D02*
X1171567Y523500D01*
X1171067Y523750D01*
X1170483Y523833D01*
X1169817Y523667D01*
X1169400Y523333D01*
X1169067Y522750D01*
X1168900Y522167D01*
X1168983Y521667D01*
X1169317Y521083D01*
X1169817Y520667D01*
X1170483Y520500D01*
X1170983Y520583D01*
X1171567Y520917D01*
X1171900Y521250D01*
G01X1176000Y523833D02*
Y520500D01*
G01Y525167D02*
X1175833Y525250D01*
Y525417D01*
X1176000Y525500D01*
X1176167Y525417D01*
Y525250D01*
X1176000Y525167D01*
G01X1180183Y520500D02*
Y523833D01*
G01Y523000D02*
X1180517Y523417D01*
X1181017Y523750D01*
X1181683Y523833D01*
X1182267Y523750D01*
X1182767Y523417D01*
X1183017Y522833D01*
Y520500D01*
G01X1186033Y519250D02*
X1186617Y518917D01*
X1187283Y518833D01*
X1187867Y518917D01*
X1188367Y519333D01*
X1188700Y519917D01*
Y523833D01*
G01Y523167D02*
X1188367Y523500D01*
X1187867Y523750D01*
X1187283Y523833D01*
X1186617Y523667D01*
X1186200Y523333D01*
X1185867Y522750D01*
X1185700Y522167D01*
X1185783Y521667D01*
X1186117Y521083D01*
X1186617Y520667D01*
X1187283Y520500D01*
X1187783Y520583D01*
X1188367Y520917D01*
X1188700Y521250D01*
G01X1197233Y520500D02*
Y523833D01*
G01Y523167D02*
X1197650Y523500D01*
X1198067Y523750D01*
X1198650Y523833D01*
X1199067Y523750D01*
X1199567Y523500D01*
G01X1205500Y520500D02*
Y523833D01*
G01Y523250D02*
X1205167Y523583D01*
X1204667Y523750D01*
X1204083Y523833D01*
X1203500Y523667D01*
X1203000Y523333D01*
X1202667Y522833D01*
X1202500Y522167D01*
X1202667Y521500D01*
X1203000Y521000D01*
X1203500Y520667D01*
X1204083Y520500D01*
X1204667Y520583D01*
X1205167Y520833D01*
X1205500Y521167D01*
G01X1209600Y525500D02*
Y520500D01*
G01X1208433Y523833D02*
X1210767D01*
G01X1215200D02*
Y520500D01*
G01Y525167D02*
X1215033Y525250D01*
Y525417D01*
X1215200Y525500D01*
X1215367Y525417D01*
Y525250D01*
X1215200Y525167D01*
G01X1220800Y520500D02*
X1220300Y520583D01*
X1219800Y520917D01*
X1219467Y521500D01*
X1219300Y522167D01*
X1219467Y522833D01*
X1219800Y523417D01*
X1220300Y523750D01*
X1220800Y523833D01*
X1221300Y523750D01*
X1221800Y523417D01*
X1222133Y522833D01*
X1222217Y522167D01*
X1222133Y521500D01*
X1221800Y520917D01*
X1221300Y520583D01*
X1220800Y520500D01*
G01X1230500Y518833D02*
Y523833D01*
G01Y523083D02*
X1230917Y523500D01*
X1231333Y523750D01*
X1232000Y523833D01*
X1232583Y523750D01*
X1233167Y523333D01*
X1233417Y522750D01*
X1233500Y522167D01*
X1233417Y521583D01*
X1233167Y521000D01*
X1232667Y520667D01*
X1232000Y520500D01*
X1231417Y520583D01*
X1230833Y520833D01*
X1230500Y521167D01*
G01X1236350Y522750D02*
X1239017D01*
X1238767Y523333D01*
X1238350Y523667D01*
X1237767Y523833D01*
X1237183Y523750D01*
X1236683Y523500D01*
X1236350Y522917D01*
X1236183Y522417D01*
Y521917D01*
X1236350Y521417D01*
X1236767Y520917D01*
X1237267Y520583D01*
X1237850Y520500D01*
X1238433Y520667D01*
X1239017Y521167D01*
G01X1242033Y520500D02*
Y523833D01*
G01Y523167D02*
X1242450Y523500D01*
X1242867Y523750D01*
X1243450Y523833D01*
X1243867Y523750D01*
X1244367Y523500D01*
G01X1253900Y520500D02*
Y524750D01*
X1254067Y525167D01*
X1254400Y525417D01*
X1254900Y525500D01*
X1255400Y525333D01*
X1255650Y524917D01*
G01X1254650Y523500D02*
X1252983D01*
G01X1260000Y520500D02*
X1259500Y520583D01*
X1259000Y520917D01*
X1258667Y521500D01*
X1258500Y522167D01*
X1258667Y522833D01*
X1259000Y523417D01*
X1259500Y523750D01*
X1260000Y523833D01*
X1260500Y523750D01*
X1261000Y523417D01*
X1261333Y522833D01*
X1261417Y522167D01*
X1261333Y521500D01*
X1261000Y520917D01*
X1260500Y520583D01*
X1260000Y520500D01*
G01X1265600D02*
Y525500D01*
G01X1271200Y520500D02*
Y525500D01*
G01X1276800Y520500D02*
X1276300Y520583D01*
X1275800Y520917D01*
X1275467Y521500D01*
X1275300Y522167D01*
X1275467Y522833D01*
X1275800Y523417D01*
X1276300Y523750D01*
X1276800Y523833D01*
X1277300Y523750D01*
X1277800Y523417D01*
X1278133Y522833D01*
X1278217Y522167D01*
X1278133Y521500D01*
X1277800Y520917D01*
X1277300Y520583D01*
X1276800Y520500D01*
G01X1280317Y523833D02*
X1281317Y520500D01*
X1282400Y523833D01*
X1283483Y520500D01*
X1284483Y523833D01*
G01X1288000D02*
Y520500D01*
G01Y525167D02*
X1287833Y525250D01*
Y525417D01*
X1288000Y525500D01*
X1288167Y525417D01*
Y525250D01*
X1288000Y525167D01*
G01X1292183Y520500D02*
Y523833D01*
G01Y523000D02*
X1292517Y523417D01*
X1293017Y523750D01*
X1293683Y523833D01*
X1294267Y523750D01*
X1294767Y523417D01*
X1295017Y522833D01*
Y520500D01*
G01X1298033Y519250D02*
X1298617Y518917D01*
X1299283Y518833D01*
X1299867Y518917D01*
X1300367Y519333D01*
X1300700Y519917D01*
Y523833D01*
G01Y523167D02*
X1300367Y523500D01*
X1299867Y523750D01*
X1299283Y523833D01*
X1298617Y523667D01*
X1298200Y523333D01*
X1297867Y522750D01*
X1297700Y522167D01*
X1297783Y521667D01*
X1298117Y521083D01*
X1298617Y520667D01*
X1299283Y520500D01*
X1299783Y520583D01*
X1300367Y520917D01*
X1300700Y521250D01*
G01X1304800Y520333D02*
X1304633Y520417D01*
Y520583D01*
X1304800Y520667D01*
X1304967Y520583D01*
Y520417D01*
X1304800Y520333D01*
G01Y522583D02*
X1304633Y522667D01*
Y522833D01*
X1304800Y522917D01*
X1304967Y522833D01*
Y522667D01*
X1304800Y522583D01*
G01X1033500Y529500D02*
Y534500D01*
G01Y532000D02*
X1033917Y532500D01*
X1034417Y532750D01*
X1034917Y532833D01*
X1035667Y532667D01*
X1036167Y532333D01*
X1036500Y531750D01*
Y531083D01*
X1036333Y530417D01*
X1036000Y529917D01*
X1035417Y529583D01*
X1034917Y529500D01*
X1034417Y529583D01*
X1033917Y529833D01*
X1033500Y530250D01*
G01X1039350Y531750D02*
X1042017D01*
X1041767Y532333D01*
X1041350Y532667D01*
X1040767Y532833D01*
X1040183Y532750D01*
X1039683Y532500D01*
X1039350Y531917D01*
X1039183Y531417D01*
Y530917D01*
X1039350Y530417D01*
X1039767Y529917D01*
X1040267Y529583D01*
X1040850Y529500D01*
X1041433Y529667D01*
X1042017Y530167D01*
G01X1051300Y529500D02*
Y533750D01*
X1051467Y534167D01*
X1051800Y534417D01*
X1052300Y534500D01*
X1052800Y534333D01*
X1053050Y533917D01*
G01X1052050Y532500D02*
X1050383D01*
G01X1056233Y529500D02*
Y532833D01*
G01Y532167D02*
X1056650Y532500D01*
X1057067Y532750D01*
X1057650Y532833D01*
X1058067Y532750D01*
X1058567Y532500D01*
G01X1061750Y531750D02*
X1064417D01*
X1064167Y532333D01*
X1063750Y532667D01*
X1063167Y532833D01*
X1062583Y532750D01*
X1062083Y532500D01*
X1061750Y531917D01*
X1061583Y531417D01*
Y530917D01*
X1061750Y530417D01*
X1062167Y529917D01*
X1062667Y529583D01*
X1063250Y529500D01*
X1063833Y529667D01*
X1064417Y530167D01*
G01X1067350Y531750D02*
X1070017D01*
X1069767Y532333D01*
X1069350Y532667D01*
X1068767Y532833D01*
X1068183Y532750D01*
X1067683Y532500D01*
X1067350Y531917D01*
X1067183Y531417D01*
Y530917D01*
X1067350Y530417D01*
X1067767Y529917D01*
X1068267Y529583D01*
X1068850Y529500D01*
X1069433Y529667D01*
X1070017Y530167D01*
G01X1079300Y529500D02*
Y533750D01*
X1079467Y534167D01*
X1079800Y534417D01*
X1080300Y534500D01*
X1080800Y534333D01*
X1081050Y533917D01*
G01X1080050Y532500D02*
X1078383D01*
G01X1084233Y529500D02*
Y532833D01*
G01Y532167D02*
X1084650Y532500D01*
X1085067Y532750D01*
X1085650Y532833D01*
X1086067Y532750D01*
X1086567Y532500D01*
G01X1091000Y529500D02*
X1090500Y529583D01*
X1090000Y529917D01*
X1089667Y530500D01*
X1089500Y531167D01*
X1089667Y531833D01*
X1090000Y532417D01*
X1090500Y532750D01*
X1091000Y532833D01*
X1091500Y532750D01*
X1092000Y532417D01*
X1092333Y531833D01*
X1092417Y531167D01*
X1092333Y530500D01*
X1092000Y529917D01*
X1091500Y529583D01*
X1091000Y529500D01*
G01X1094100D02*
Y532833D01*
G01Y531917D02*
X1094350Y532333D01*
X1094767Y532667D01*
X1095350Y532833D01*
X1095933Y532667D01*
X1096350Y532333D01*
X1096600Y531917D01*
Y529500D01*
G01Y531917D02*
X1096850Y532333D01*
X1097267Y532667D01*
X1097850Y532833D01*
X1098433Y532667D01*
X1098850Y532333D01*
X1099100Y531833D01*
Y529500D01*
G01X1106550Y530083D02*
X1106967Y529750D01*
X1107550Y529500D01*
X1108050D01*
X1108550Y529667D01*
X1108883Y529917D01*
X1109050Y530250D01*
X1108967Y530750D01*
X1108633Y531000D01*
X1107133Y531500D01*
X1106800Y532083D01*
X1106967Y532500D01*
X1107300Y532750D01*
X1107800Y532833D01*
X1108300Y532750D01*
X1108800Y532500D01*
G01X1113400Y529500D02*
X1112900Y529583D01*
X1112400Y529917D01*
X1112067Y530500D01*
X1111900Y531167D01*
X1112067Y531833D01*
X1112400Y532417D01*
X1112900Y532750D01*
X1113400Y532833D01*
X1113900Y532750D01*
X1114400Y532417D01*
X1114733Y531833D01*
X1114817Y531167D01*
X1114733Y530500D01*
X1114400Y529917D01*
X1113900Y529583D01*
X1113400Y529500D01*
G01X1119000D02*
Y534500D01*
G01X1126100D02*
Y529500D01*
G01Y530250D02*
X1125767Y529833D01*
X1125267Y529583D01*
X1124683Y529500D01*
X1124017Y529667D01*
X1123517Y530083D01*
X1123183Y530583D01*
X1123100Y531167D01*
X1123183Y531750D01*
X1123517Y532250D01*
X1124017Y532667D01*
X1124683Y532833D01*
X1125267Y532750D01*
X1125683Y532583D01*
X1126100Y532250D01*
G01X1128950Y531750D02*
X1131617D01*
X1131367Y532333D01*
X1130950Y532667D01*
X1130367Y532833D01*
X1129783Y532750D01*
X1129283Y532500D01*
X1128950Y531917D01*
X1128783Y531417D01*
Y530917D01*
X1128950Y530417D01*
X1129367Y529917D01*
X1129867Y529583D01*
X1130450Y529500D01*
X1131033Y529667D01*
X1131617Y530167D01*
G01X1134633Y529500D02*
Y532833D01*
G01Y532167D02*
X1135050Y532500D01*
X1135467Y532750D01*
X1136050Y532833D01*
X1136467Y532750D01*
X1136967Y532500D01*
G01X1144500Y529500D02*
Y532833D01*
G01Y531917D02*
X1144750Y532333D01*
X1145167Y532667D01*
X1145750Y532833D01*
X1146333Y532667D01*
X1146750Y532333D01*
X1147000Y531917D01*
Y529500D01*
G01Y531917D02*
X1147250Y532333D01*
X1147667Y532667D01*
X1148250Y532833D01*
X1148833Y532667D01*
X1149250Y532333D01*
X1149500Y531833D01*
Y529500D01*
G01X1154100D02*
Y532833D01*
G01Y532250D02*
X1153767Y532583D01*
X1153267Y532750D01*
X1152683Y532833D01*
X1152100Y532667D01*
X1151600Y532333D01*
X1151267Y531833D01*
X1151100Y531167D01*
X1151267Y530500D01*
X1151600Y530000D01*
X1152100Y529667D01*
X1152683Y529500D01*
X1153267Y529583D01*
X1153767Y529833D01*
X1154100Y530167D01*
G01X1156950Y530083D02*
X1157367Y529750D01*
X1157950Y529500D01*
X1158450D01*
X1158950Y529667D01*
X1159283Y529917D01*
X1159450Y530250D01*
X1159367Y530750D01*
X1159033Y531000D01*
X1157533Y531500D01*
X1157200Y532083D01*
X1157367Y532500D01*
X1157700Y532750D01*
X1158200Y532833D01*
X1158700Y532750D01*
X1159200Y532500D01*
G01X1162383Y529500D02*
Y534500D01*
G01X1165050Y532833D02*
X1162383Y530917D01*
G01X1163467Y531667D02*
X1165217Y529500D01*
G01X1169400Y529333D02*
X1169233Y529417D01*
Y529583D01*
X1169400Y529667D01*
X1169567Y529583D01*
Y529417D01*
X1169400Y529333D01*
G01X1020417Y542667D02*
X1020917Y543167D01*
X1021500Y543417D01*
X1022167Y543500D01*
X1023000Y543333D01*
X1023583Y542917D01*
X1023750Y542417D01*
X1023667Y541917D01*
X1023333Y541500D01*
X1021667Y540667D01*
X1020917Y540083D01*
X1020417Y539250D01*
X1020250Y538500D01*
X1023750D01*
G01X1027600Y538333D02*
X1027433Y538417D01*
Y538583D01*
X1027600Y538667D01*
X1027767Y538583D01*
Y538417D01*
X1027600Y538333D01*
G01X1033200Y543500D02*
Y538500D01*
G01X1031283Y543500D02*
X1035117D01*
G01X1037383Y538500D02*
Y543500D01*
G01Y541083D02*
X1037800Y541500D01*
X1038217Y541750D01*
X1038883Y541833D01*
X1039383Y541750D01*
X1039967Y541417D01*
X1040217Y540917D01*
Y538500D01*
G01X1043150Y540750D02*
X1045817D01*
X1045567Y541333D01*
X1045150Y541667D01*
X1044567Y541833D01*
X1043983Y541750D01*
X1043483Y541500D01*
X1043150Y540917D01*
X1042983Y540417D01*
Y539917D01*
X1043150Y539417D01*
X1043567Y538917D01*
X1044067Y538583D01*
X1044650Y538500D01*
X1045233Y538667D01*
X1045817Y539167D01*
G01X1054350Y539083D02*
X1054767Y538750D01*
X1055350Y538500D01*
X1055850D01*
X1056350Y538667D01*
X1056683Y538917D01*
X1056850Y539250D01*
X1056767Y539750D01*
X1056433Y540000D01*
X1054933Y540500D01*
X1054600Y541083D01*
X1054767Y541500D01*
X1055100Y541750D01*
X1055600Y541833D01*
X1056100Y541750D01*
X1056600Y541500D01*
G01X1061200Y541833D02*
Y538500D01*
G01Y543167D02*
X1061033Y543250D01*
Y543417D01*
X1061200Y543500D01*
X1061367Y543417D01*
Y543250D01*
X1061200Y543167D01*
G01X1068300Y543500D02*
Y538500D01*
G01Y539250D02*
X1067967Y538833D01*
X1067467Y538583D01*
X1066883Y538500D01*
X1066217Y538667D01*
X1065717Y539083D01*
X1065383Y539583D01*
X1065300Y540167D01*
X1065383Y540750D01*
X1065717Y541250D01*
X1066217Y541667D01*
X1066883Y541833D01*
X1067467Y541750D01*
X1067883Y541583D01*
X1068300Y541250D01*
G01X1071150Y540750D02*
X1073817D01*
X1073567Y541333D01*
X1073150Y541667D01*
X1072567Y541833D01*
X1071983Y541750D01*
X1071483Y541500D01*
X1071150Y540917D01*
X1070983Y540417D01*
Y539917D01*
X1071150Y539417D01*
X1071567Y538917D01*
X1072067Y538583D01*
X1072650Y538500D01*
X1073233Y538667D01*
X1073817Y539167D01*
G01X1081517Y541833D02*
X1082517Y538500D01*
X1083600Y541833D01*
X1084683Y538500D01*
X1085683Y541833D01*
G01X1089200D02*
Y538500D01*
G01Y543167D02*
X1089033Y543250D01*
Y543417D01*
X1089200Y543500D01*
X1089367Y543417D01*
Y543250D01*
X1089200Y543167D01*
G01X1094800Y543500D02*
Y538500D01*
G01X1093633Y541833D02*
X1095967D01*
G01X1098983Y538500D02*
Y543500D01*
G01Y541083D02*
X1099400Y541500D01*
X1099817Y541750D01*
X1100483Y541833D01*
X1100983Y541750D01*
X1101567Y541417D01*
X1101817Y540917D01*
Y538500D01*
G01X1110350Y539083D02*
X1110767Y538750D01*
X1111350Y538500D01*
X1111850D01*
X1112350Y538667D01*
X1112683Y538917D01*
X1112850Y539250D01*
X1112767Y539750D01*
X1112433Y540000D01*
X1110933Y540500D01*
X1110600Y541083D01*
X1110767Y541500D01*
X1111100Y541750D01*
X1111600Y541833D01*
X1112100Y541750D01*
X1112600Y541500D01*
G01X1117200Y538500D02*
X1116700Y538583D01*
X1116200Y538917D01*
X1115867Y539500D01*
X1115700Y540167D01*
X1115867Y540833D01*
X1116200Y541417D01*
X1116700Y541750D01*
X1117200Y541833D01*
X1117700Y541750D01*
X1118200Y541417D01*
X1118533Y540833D01*
X1118617Y540167D01*
X1118533Y539500D01*
X1118200Y538917D01*
X1117700Y538583D01*
X1117200Y538500D01*
G01X1122800D02*
Y543500D01*
G01X1129900D02*
Y538500D01*
G01Y539250D02*
X1129567Y538833D01*
X1129067Y538583D01*
X1128483Y538500D01*
X1127817Y538667D01*
X1127317Y539083D01*
X1126983Y539583D01*
X1126900Y540167D01*
X1126983Y540750D01*
X1127317Y541250D01*
X1127817Y541667D01*
X1128483Y541833D01*
X1129067Y541750D01*
X1129483Y541583D01*
X1129900Y541250D01*
G01X1132750Y540750D02*
X1135417D01*
X1135167Y541333D01*
X1134750Y541667D01*
X1134167Y541833D01*
X1133583Y541750D01*
X1133083Y541500D01*
X1132750Y540917D01*
X1132583Y540417D01*
Y539917D01*
X1132750Y539417D01*
X1133167Y538917D01*
X1133667Y538583D01*
X1134250Y538500D01*
X1134833Y538667D01*
X1135417Y539167D01*
G01X1138433Y538500D02*
Y541833D01*
G01Y541167D02*
X1138850Y541500D01*
X1139267Y541750D01*
X1139850Y541833D01*
X1140267Y541750D01*
X1140767Y541500D01*
G01X1148300Y538500D02*
Y541833D01*
G01Y540917D02*
X1148550Y541333D01*
X1148967Y541667D01*
X1149550Y541833D01*
X1150133Y541667D01*
X1150550Y541333D01*
X1150800Y540917D01*
Y538500D01*
G01Y540917D02*
X1151050Y541333D01*
X1151467Y541667D01*
X1152050Y541833D01*
X1152633Y541667D01*
X1153050Y541333D01*
X1153300Y540833D01*
Y538500D01*
G01X1157900D02*
Y541833D01*
G01Y541250D02*
X1157567Y541583D01*
X1157067Y541750D01*
X1156483Y541833D01*
X1155900Y541667D01*
X1155400Y541333D01*
X1155067Y540833D01*
X1154900Y540167D01*
X1155067Y539500D01*
X1155400Y539000D01*
X1155900Y538667D01*
X1156483Y538500D01*
X1157067Y538583D01*
X1157567Y538833D01*
X1157900Y539167D01*
G01X1160750Y539083D02*
X1161167Y538750D01*
X1161750Y538500D01*
X1162250D01*
X1162750Y538667D01*
X1163083Y538917D01*
X1163250Y539250D01*
X1163167Y539750D01*
X1162833Y540000D01*
X1161333Y540500D01*
X1161000Y541083D01*
X1161167Y541500D01*
X1161500Y541750D01*
X1162000Y541833D01*
X1162500Y541750D01*
X1163000Y541500D01*
G01X1166183Y538500D02*
Y543500D01*
G01X1168850Y541833D02*
X1166183Y539917D01*
G01X1167267Y540667D02*
X1169017Y538500D01*
G01X1177300Y536833D02*
Y541833D01*
G01Y541083D02*
X1177717Y541500D01*
X1178133Y541750D01*
X1178800Y541833D01*
X1179383Y541750D01*
X1179967Y541333D01*
X1180217Y540750D01*
X1180300Y540167D01*
X1180217Y539583D01*
X1179967Y539000D01*
X1179467Y538667D01*
X1178800Y538500D01*
X1178217Y538583D01*
X1177633Y538833D01*
X1177300Y539167D01*
G01X1185900Y538500D02*
Y541833D01*
G01Y541250D02*
X1185567Y541583D01*
X1185067Y541750D01*
X1184483Y541833D01*
X1183900Y541667D01*
X1183400Y541333D01*
X1183067Y540833D01*
X1182900Y540167D01*
X1183067Y539500D01*
X1183400Y539000D01*
X1183900Y538667D01*
X1184483Y538500D01*
X1185067Y538583D01*
X1185567Y538833D01*
X1185900Y539167D01*
G01X1191500Y543500D02*
Y538500D01*
G01Y539250D02*
X1191167Y538833D01*
X1190667Y538583D01*
X1190083Y538500D01*
X1189417Y538667D01*
X1188917Y539083D01*
X1188583Y539583D01*
X1188500Y540167D01*
X1188583Y540750D01*
X1188917Y541250D01*
X1189417Y541667D01*
X1190083Y541833D01*
X1190667Y541750D01*
X1191083Y541583D01*
X1191500Y541250D01*
G01X1195433Y537583D02*
X1195767Y538667D01*
G01X1206800Y543500D02*
Y538500D01*
G01X1205633Y541833D02*
X1207967D01*
G01X1210983Y538500D02*
Y543500D01*
G01Y541083D02*
X1211400Y541500D01*
X1211817Y541750D01*
X1212483Y541833D01*
X1212983Y541750D01*
X1213567Y541417D01*
X1213817Y540917D01*
Y538500D01*
G01X1216750Y540750D02*
X1219417D01*
X1219167Y541333D01*
X1218750Y541667D01*
X1218167Y541833D01*
X1217583Y541750D01*
X1217083Y541500D01*
X1216750Y540917D01*
X1216583Y540417D01*
Y539917D01*
X1216750Y539417D01*
X1217167Y538917D01*
X1217667Y538583D01*
X1218250Y538500D01*
X1218833Y538667D01*
X1219417Y539167D01*
G01X1230700Y538500D02*
Y541833D01*
G01Y541250D02*
X1230367Y541583D01*
X1229867Y541750D01*
X1229283Y541833D01*
X1228700Y541667D01*
X1228200Y541333D01*
X1227867Y540833D01*
X1227700Y540167D01*
X1227867Y539500D01*
X1228200Y539000D01*
X1228700Y538667D01*
X1229283Y538500D01*
X1229867Y538583D01*
X1230367Y538833D01*
X1230700Y539167D01*
G01X1233383Y538500D02*
Y541833D01*
G01Y541000D02*
X1233717Y541417D01*
X1234217Y541750D01*
X1234883Y541833D01*
X1235467Y541750D01*
X1235967Y541417D01*
X1236217Y540833D01*
Y538500D01*
G01X1238983D02*
Y541833D01*
G01Y541000D02*
X1239317Y541417D01*
X1239817Y541750D01*
X1240483Y541833D01*
X1241067Y541750D01*
X1241567Y541417D01*
X1241817Y540833D01*
Y538500D01*
G01X1244583Y541833D02*
Y539500D01*
X1244917Y538917D01*
X1245417Y538583D01*
X1246000Y538500D01*
X1246583Y538583D01*
X1247083Y538917D01*
X1247417Y539500D01*
G01Y538500D02*
Y541833D01*
G01X1253100Y538500D02*
Y541833D01*
G01Y541250D02*
X1252767Y541583D01*
X1252267Y541750D01*
X1251683Y541833D01*
X1251100Y541667D01*
X1250600Y541333D01*
X1250267Y540833D01*
X1250100Y540167D01*
X1250267Y539500D01*
X1250600Y539000D01*
X1251100Y538667D01*
X1251683Y538500D01*
X1252267Y538583D01*
X1252767Y538833D01*
X1253100Y539167D01*
G01X1257200Y538500D02*
Y543500D01*
G01X1267233Y538500D02*
Y541833D01*
G01Y541167D02*
X1267650Y541500D01*
X1268067Y541750D01*
X1268650Y541833D01*
X1269067Y541750D01*
X1269567Y541500D01*
G01X1274000Y541833D02*
Y538500D01*
G01Y543167D02*
X1273833Y543250D01*
Y543417D01*
X1274000Y543500D01*
X1274167Y543417D01*
Y543250D01*
X1274000Y543167D01*
G01X1278183Y538500D02*
Y541833D01*
G01Y541000D02*
X1278517Y541417D01*
X1279017Y541750D01*
X1279683Y541833D01*
X1280267Y541750D01*
X1280767Y541417D01*
X1281017Y540833D01*
Y538500D01*
G01X1284033Y537250D02*
X1284617Y536917D01*
X1285283Y536833D01*
X1285867Y536917D01*
X1286367Y537333D01*
X1286700Y537917D01*
Y541833D01*
G01Y541167D02*
X1286367Y541500D01*
X1285867Y541750D01*
X1285283Y541833D01*
X1284617Y541667D01*
X1284200Y541333D01*
X1283867Y540750D01*
X1283700Y540167D01*
X1283783Y539667D01*
X1284117Y539083D01*
X1284617Y538667D01*
X1285283Y538500D01*
X1285783Y538583D01*
X1286367Y538917D01*
X1286700Y539250D01*
G01X1295150Y539083D02*
X1295567Y538750D01*
X1296150Y538500D01*
X1296650D01*
X1297150Y538667D01*
X1297483Y538917D01*
X1297650Y539250D01*
X1297567Y539750D01*
X1297233Y540000D01*
X1295733Y540500D01*
X1295400Y541083D01*
X1295567Y541500D01*
X1295900Y541750D01*
X1296400Y541833D01*
X1296900Y541750D01*
X1297400Y541500D01*
G01X1300583Y538500D02*
Y543500D01*
G01Y541083D02*
X1301000Y541500D01*
X1301417Y541750D01*
X1302083Y541833D01*
X1302583Y541750D01*
X1303167Y541417D01*
X1303417Y540917D01*
Y538500D01*
G01X1307600D02*
X1307100Y538583D01*
X1306600Y538917D01*
X1306267Y539500D01*
X1306100Y540167D01*
X1306267Y540833D01*
X1306600Y541417D01*
X1307100Y541750D01*
X1307600Y541833D01*
X1308100Y541750D01*
X1308600Y541417D01*
X1308933Y540833D01*
X1309017Y540167D01*
X1308933Y539500D01*
X1308600Y538917D01*
X1308100Y538583D01*
X1307600Y538500D01*
G01X1311783Y541833D02*
Y539500D01*
X1312117Y538917D01*
X1312617Y538583D01*
X1313200Y538500D01*
X1313783Y538583D01*
X1314283Y538917D01*
X1314617Y539500D01*
G01Y538500D02*
Y541833D01*
G01X1318800Y538500D02*
Y543500D01*
G01X1325900D02*
Y538500D01*
G01Y539250D02*
X1325567Y538833D01*
X1325067Y538583D01*
X1324483Y538500D01*
X1323817Y538667D01*
X1323317Y539083D01*
X1322983Y539583D01*
X1322900Y540167D01*
X1322983Y540750D01*
X1323317Y541250D01*
X1323817Y541667D01*
X1324483Y541833D01*
X1325067Y541750D01*
X1325483Y541583D01*
X1325900Y541250D01*
G01X1032500Y552500D02*
Y557500D01*
G01Y555000D02*
X1032917Y555500D01*
X1033417Y555750D01*
X1033917Y555833D01*
X1034667Y555667D01*
X1035167Y555333D01*
X1035500Y554750D01*
Y554083D01*
X1035333Y553417D01*
X1035000Y552917D01*
X1034417Y552583D01*
X1033917Y552500D01*
X1033417Y552583D01*
X1032917Y552833D01*
X1032500Y553250D01*
G01X1038350Y554750D02*
X1041017D01*
X1040767Y555333D01*
X1040350Y555667D01*
X1039767Y555833D01*
X1039183Y555750D01*
X1038683Y555500D01*
X1038350Y554917D01*
X1038183Y554417D01*
Y553917D01*
X1038350Y553417D01*
X1038767Y552917D01*
X1039267Y552583D01*
X1039850Y552500D01*
X1040433Y552667D01*
X1041017Y553167D01*
G01X1050800Y557500D02*
Y552500D01*
G01X1049633Y555833D02*
X1051967D01*
G01X1055150Y554750D02*
X1057817D01*
X1057567Y555333D01*
X1057150Y555667D01*
X1056567Y555833D01*
X1055983Y555750D01*
X1055483Y555500D01*
X1055150Y554917D01*
X1054983Y554417D01*
Y553917D01*
X1055150Y553417D01*
X1055567Y552917D01*
X1056067Y552583D01*
X1056650Y552500D01*
X1057233Y552667D01*
X1057817Y553167D01*
G01X1060583Y552500D02*
Y555833D01*
G01Y555000D02*
X1060917Y555417D01*
X1061417Y555750D01*
X1062083Y555833D01*
X1062667Y555750D01*
X1063167Y555417D01*
X1063417Y554833D01*
Y552500D01*
G01X1067600Y557500D02*
Y552500D01*
G01X1066433Y555833D02*
X1068767D01*
G01X1071950Y554750D02*
X1074617D01*
X1074367Y555333D01*
X1073950Y555667D01*
X1073367Y555833D01*
X1072783Y555750D01*
X1072283Y555500D01*
X1071950Y554917D01*
X1071783Y554417D01*
Y553917D01*
X1071950Y553417D01*
X1072367Y552917D01*
X1072867Y552583D01*
X1073450Y552500D01*
X1074033Y552667D01*
X1074617Y553167D01*
G01X1080300Y557500D02*
Y552500D01*
G01Y553250D02*
X1079967Y552833D01*
X1079467Y552583D01*
X1078883Y552500D01*
X1078217Y552667D01*
X1077717Y553083D01*
X1077383Y553583D01*
X1077300Y554167D01*
X1077383Y554750D01*
X1077717Y555250D01*
X1078217Y555667D01*
X1078883Y555833D01*
X1079467Y555750D01*
X1079883Y555583D01*
X1080300Y555250D01*
G01X1087917Y555833D02*
X1088917Y552500D01*
X1090000Y555833D01*
X1091083Y552500D01*
X1092083Y555833D01*
G01X1095600D02*
Y552500D01*
G01Y557167D02*
X1095433Y557250D01*
Y557417D01*
X1095600Y557500D01*
X1095767Y557417D01*
Y557250D01*
X1095600Y557167D01*
G01X1101200Y557500D02*
Y552500D01*
G01X1100033Y555833D02*
X1102367D01*
G01X1105383Y552500D02*
Y557500D01*
G01Y555083D02*
X1105800Y555500D01*
X1106217Y555750D01*
X1106883Y555833D01*
X1107383Y555750D01*
X1107967Y555417D01*
X1108217Y554917D01*
Y552500D01*
G01X1116750Y553083D02*
X1117167Y552750D01*
X1117750Y552500D01*
X1118250D01*
X1118750Y552667D01*
X1119083Y552917D01*
X1119250Y553250D01*
X1119167Y553750D01*
X1118833Y554000D01*
X1117333Y554500D01*
X1117000Y555083D01*
X1117167Y555500D01*
X1117500Y555750D01*
X1118000Y555833D01*
X1118500Y555750D01*
X1119000Y555500D01*
G01X1123600Y552500D02*
X1123100Y552583D01*
X1122600Y552917D01*
X1122267Y553500D01*
X1122100Y554167D01*
X1122267Y554833D01*
X1122600Y555417D01*
X1123100Y555750D01*
X1123600Y555833D01*
X1124100Y555750D01*
X1124600Y555417D01*
X1124933Y554833D01*
X1125017Y554167D01*
X1124933Y553500D01*
X1124600Y552917D01*
X1124100Y552583D01*
X1123600Y552500D01*
G01X1129200D02*
Y557500D01*
G01X1136300D02*
Y552500D01*
G01Y553250D02*
X1135967Y552833D01*
X1135467Y552583D01*
X1134883Y552500D01*
X1134217Y552667D01*
X1133717Y553083D01*
X1133383Y553583D01*
X1133300Y554167D01*
X1133383Y554750D01*
X1133717Y555250D01*
X1134217Y555667D01*
X1134883Y555833D01*
X1135467Y555750D01*
X1135883Y555583D01*
X1136300Y555250D01*
G01X1139150Y554750D02*
X1141817D01*
X1141567Y555333D01*
X1141150Y555667D01*
X1140567Y555833D01*
X1139983Y555750D01*
X1139483Y555500D01*
X1139150Y554917D01*
X1138983Y554417D01*
Y553917D01*
X1139150Y553417D01*
X1139567Y552917D01*
X1140067Y552583D01*
X1140650Y552500D01*
X1141233Y552667D01*
X1141817Y553167D01*
G01X1144833Y552500D02*
Y555833D01*
G01Y555167D02*
X1145250Y555500D01*
X1145667Y555750D01*
X1146250Y555833D01*
X1146667Y555750D01*
X1147167Y555500D01*
G01X1154700Y552500D02*
Y555833D01*
G01Y554917D02*
X1154950Y555333D01*
X1155367Y555667D01*
X1155950Y555833D01*
X1156533Y555667D01*
X1156950Y555333D01*
X1157200Y554917D01*
Y552500D01*
G01Y554917D02*
X1157450Y555333D01*
X1157867Y555667D01*
X1158450Y555833D01*
X1159033Y555667D01*
X1159450Y555333D01*
X1159700Y554833D01*
Y552500D01*
G01X1164300D02*
Y555833D01*
G01Y555250D02*
X1163967Y555583D01*
X1163467Y555750D01*
X1162883Y555833D01*
X1162300Y555667D01*
X1161800Y555333D01*
X1161467Y554833D01*
X1161300Y554167D01*
X1161467Y553500D01*
X1161800Y553000D01*
X1162300Y552667D01*
X1162883Y552500D01*
X1163467Y552583D01*
X1163967Y552833D01*
X1164300Y553167D01*
G01X1167150Y553083D02*
X1167567Y552750D01*
X1168150Y552500D01*
X1168650D01*
X1169150Y552667D01*
X1169483Y552917D01*
X1169650Y553250D01*
X1169567Y553750D01*
X1169233Y554000D01*
X1167733Y554500D01*
X1167400Y555083D01*
X1167567Y555500D01*
X1167900Y555750D01*
X1168400Y555833D01*
X1168900Y555750D01*
X1169400Y555500D01*
G01X1172583Y552500D02*
Y557500D01*
G01X1175250Y555833D02*
X1172583Y553917D01*
G01X1173667Y554667D02*
X1175417Y552500D01*
G01X1179600Y552333D02*
X1179433Y552417D01*
Y552583D01*
X1179600Y552667D01*
X1179767Y552583D01*
Y552417D01*
X1179600Y552333D01*
G01X1034000Y566500D02*
Y561500D01*
G01X1032833Y564833D02*
X1035167D01*
G01X1039600Y561500D02*
X1039100Y561583D01*
X1038600Y561917D01*
X1038267Y562500D01*
X1038100Y563167D01*
X1038267Y563833D01*
X1038600Y564417D01*
X1039100Y564750D01*
X1039600Y564833D01*
X1040100Y564750D01*
X1040600Y564417D01*
X1040933Y563833D01*
X1041017Y563167D01*
X1040933Y562500D01*
X1040600Y561917D01*
X1040100Y561583D01*
X1039600Y561500D01*
G01X1049300D02*
Y566500D01*
G01Y564000D02*
X1049717Y564500D01*
X1050217Y564750D01*
X1050717Y564833D01*
X1051467Y564667D01*
X1051967Y564333D01*
X1052300Y563750D01*
Y563083D01*
X1052133Y562417D01*
X1051800Y561917D01*
X1051217Y561583D01*
X1050717Y561500D01*
X1050217Y561583D01*
X1049717Y561833D01*
X1049300Y562250D01*
G01X1055150Y563750D02*
X1057817D01*
X1057567Y564333D01*
X1057150Y564667D01*
X1056567Y564833D01*
X1055983Y564750D01*
X1055483Y564500D01*
X1055150Y563917D01*
X1054983Y563417D01*
Y562917D01*
X1055150Y562417D01*
X1055567Y561917D01*
X1056067Y561583D01*
X1056650Y561500D01*
X1057233Y561667D01*
X1057817Y562167D01*
G01X1068933Y564417D02*
X1068350Y564750D01*
X1067850Y564833D01*
X1067183Y564667D01*
X1066683Y564333D01*
X1066350Y563750D01*
X1066267Y563167D01*
X1066350Y562583D01*
X1066683Y562083D01*
X1067183Y561667D01*
X1067850Y561500D01*
X1068433Y561667D01*
X1068933Y562000D01*
G01X1073200Y561500D02*
X1072700Y561583D01*
X1072200Y561917D01*
X1071867Y562500D01*
X1071700Y563167D01*
X1071867Y563833D01*
X1072200Y564417D01*
X1072700Y564750D01*
X1073200Y564833D01*
X1073700Y564750D01*
X1074200Y564417D01*
X1074533Y563833D01*
X1074617Y563167D01*
X1074533Y562500D01*
X1074200Y561917D01*
X1073700Y561583D01*
X1073200Y561500D01*
G01X1077300Y564833D02*
X1078800Y561500D01*
X1080300Y564833D01*
G01X1083150Y563750D02*
X1085817D01*
X1085567Y564333D01*
X1085150Y564667D01*
X1084567Y564833D01*
X1083983Y564750D01*
X1083483Y564500D01*
X1083150Y563917D01*
X1082983Y563417D01*
Y562917D01*
X1083150Y562417D01*
X1083567Y561917D01*
X1084067Y561583D01*
X1084650Y561500D01*
X1085233Y561667D01*
X1085817Y562167D01*
G01X1088833Y561500D02*
Y564833D01*
G01Y564167D02*
X1089250Y564500D01*
X1089667Y564750D01*
X1090250Y564833D01*
X1090667Y564750D01*
X1091167Y564500D01*
G01X1094350Y563750D02*
X1097017D01*
X1096767Y564333D01*
X1096350Y564667D01*
X1095767Y564833D01*
X1095183Y564750D01*
X1094683Y564500D01*
X1094350Y563917D01*
X1094183Y563417D01*
Y562917D01*
X1094350Y562417D01*
X1094767Y561917D01*
X1095267Y561583D01*
X1095850Y561500D01*
X1096433Y561667D01*
X1097017Y562167D01*
G01X1102700Y566500D02*
Y561500D01*
G01Y562250D02*
X1102367Y561833D01*
X1101867Y561583D01*
X1101283Y561500D01*
X1100617Y561667D01*
X1100117Y562083D01*
X1099783Y562583D01*
X1099700Y563167D01*
X1099783Y563750D01*
X1100117Y564250D01*
X1100617Y564667D01*
X1101283Y564833D01*
X1101867Y564750D01*
X1102283Y564583D01*
X1102700Y564250D01*
G01X1110900Y561500D02*
Y566500D01*
G01Y564000D02*
X1111317Y564500D01*
X1111817Y564750D01*
X1112317Y564833D01*
X1113067Y564667D01*
X1113567Y564333D01*
X1113900Y563750D01*
Y563083D01*
X1113733Y562417D01*
X1113400Y561917D01*
X1112817Y561583D01*
X1112317Y561500D01*
X1111817Y561583D01*
X1111317Y561833D01*
X1110900Y562250D01*
G01X1116250Y560000D02*
X1116750Y559833D01*
X1117417Y560000D01*
X1117833Y560333D01*
X1118167Y560750D01*
X1118667Y562083D01*
X1119750Y564833D01*
G01X1117083D02*
X1118667Y562083D01*
G01X1127950D02*
X1128367Y561750D01*
X1128950Y561500D01*
X1129450D01*
X1129950Y561667D01*
X1130283Y561917D01*
X1130450Y562250D01*
X1130367Y562750D01*
X1130033Y563000D01*
X1128533Y563500D01*
X1128200Y564083D01*
X1128367Y564500D01*
X1128700Y564750D01*
X1129200Y564833D01*
X1129700Y564750D01*
X1130200Y564500D01*
G01X1134800Y561500D02*
X1134300Y561583D01*
X1133800Y561917D01*
X1133467Y562500D01*
X1133300Y563167D01*
X1133467Y563833D01*
X1133800Y564417D01*
X1134300Y564750D01*
X1134800Y564833D01*
X1135300Y564750D01*
X1135800Y564417D01*
X1136133Y563833D01*
X1136217Y563167D01*
X1136133Y562500D01*
X1135800Y561917D01*
X1135300Y561583D01*
X1134800Y561500D01*
G01X1140400D02*
Y566500D01*
G01X1147500D02*
Y561500D01*
G01Y562250D02*
X1147167Y561833D01*
X1146667Y561583D01*
X1146083Y561500D01*
X1145417Y561667D01*
X1144917Y562083D01*
X1144583Y562583D01*
X1144500Y563167D01*
X1144583Y563750D01*
X1144917Y564250D01*
X1145417Y564667D01*
X1146083Y564833D01*
X1146667Y564750D01*
X1147083Y564583D01*
X1147500Y564250D01*
G01X1150350Y563750D02*
X1153017D01*
X1152767Y564333D01*
X1152350Y564667D01*
X1151767Y564833D01*
X1151183Y564750D01*
X1150683Y564500D01*
X1150350Y563917D01*
X1150183Y563417D01*
Y562917D01*
X1150350Y562417D01*
X1150767Y561917D01*
X1151267Y561583D01*
X1151850Y561500D01*
X1152433Y561667D01*
X1153017Y562167D01*
G01X1156033Y561500D02*
Y564833D01*
G01Y564167D02*
X1156450Y564500D01*
X1156867Y564750D01*
X1157450Y564833D01*
X1157867Y564750D01*
X1158367Y564500D01*
G01X1165900Y561500D02*
Y564833D01*
G01Y563917D02*
X1166150Y564333D01*
X1166567Y564667D01*
X1167150Y564833D01*
X1167733Y564667D01*
X1168150Y564333D01*
X1168400Y563917D01*
Y561500D01*
G01Y563917D02*
X1168650Y564333D01*
X1169067Y564667D01*
X1169650Y564833D01*
X1170233Y564667D01*
X1170650Y564333D01*
X1170900Y563833D01*
Y561500D01*
G01X1175500D02*
Y564833D01*
G01Y564250D02*
X1175167Y564583D01*
X1174667Y564750D01*
X1174083Y564833D01*
X1173500Y564667D01*
X1173000Y564333D01*
X1172667Y563833D01*
X1172500Y563167D01*
X1172667Y562500D01*
X1173000Y562000D01*
X1173500Y561667D01*
X1174083Y561500D01*
X1174667Y561583D01*
X1175167Y561833D01*
X1175500Y562167D01*
G01X1178350Y562083D02*
X1178767Y561750D01*
X1179350Y561500D01*
X1179850D01*
X1180350Y561667D01*
X1180683Y561917D01*
X1180850Y562250D01*
X1180767Y562750D01*
X1180433Y563000D01*
X1178933Y563500D01*
X1178600Y564083D01*
X1178767Y564500D01*
X1179100Y564750D01*
X1179600Y564833D01*
X1180100Y564750D01*
X1180600Y564500D01*
G01X1183783Y561500D02*
Y566500D01*
G01X1186450Y564833D02*
X1183783Y562917D01*
G01X1184867Y563667D02*
X1186617Y561500D01*
G01X1197900D02*
Y564833D01*
G01Y564250D02*
X1197567Y564583D01*
X1197067Y564750D01*
X1196483Y564833D01*
X1195900Y564667D01*
X1195400Y564333D01*
X1195067Y563833D01*
X1194900Y563167D01*
X1195067Y562500D01*
X1195400Y562000D01*
X1195900Y561667D01*
X1196483Y561500D01*
X1197067Y561583D01*
X1197567Y561833D01*
X1197900Y562167D01*
G01X1200583Y561500D02*
Y564833D01*
G01Y564000D02*
X1200917Y564417D01*
X1201417Y564750D01*
X1202083Y564833D01*
X1202667Y564750D01*
X1203167Y564417D01*
X1203417Y563833D01*
Y561500D01*
G01X1209100Y566500D02*
Y561500D01*
G01Y562250D02*
X1208767Y561833D01*
X1208267Y561583D01*
X1207683Y561500D01*
X1207017Y561667D01*
X1206517Y562083D01*
X1206183Y562583D01*
X1206100Y563167D01*
X1206183Y563750D01*
X1206517Y564250D01*
X1207017Y564667D01*
X1207683Y564833D01*
X1208267Y564750D01*
X1208683Y564583D01*
X1209100Y564250D01*
G01X1217383Y561500D02*
Y566500D01*
G01Y564083D02*
X1217800Y564500D01*
X1218217Y564750D01*
X1218883Y564833D01*
X1219383Y564750D01*
X1219967Y564417D01*
X1220217Y563917D01*
Y561500D01*
G01X1224400D02*
X1223900Y561583D01*
X1223400Y561917D01*
X1223067Y562500D01*
X1222900Y563167D01*
X1223067Y563833D01*
X1223400Y564417D01*
X1223900Y564750D01*
X1224400Y564833D01*
X1224900Y564750D01*
X1225400Y564417D01*
X1225733Y563833D01*
X1225817Y563167D01*
X1225733Y562500D01*
X1225400Y561917D01*
X1224900Y561583D01*
X1224400Y561500D01*
G01X1230000D02*
Y566500D01*
G01X1234350Y563750D02*
X1237017D01*
X1236767Y564333D01*
X1236350Y564667D01*
X1235767Y564833D01*
X1235183Y564750D01*
X1234683Y564500D01*
X1234350Y563917D01*
X1234183Y563417D01*
Y562917D01*
X1234350Y562417D01*
X1234767Y561917D01*
X1235267Y561583D01*
X1235850Y561500D01*
X1236433Y561667D01*
X1237017Y562167D01*
G01X1248300Y561500D02*
Y564833D01*
G01Y564250D02*
X1247967Y564583D01*
X1247467Y564750D01*
X1246883Y564833D01*
X1246300Y564667D01*
X1245800Y564333D01*
X1245467Y563833D01*
X1245300Y563167D01*
X1245467Y562500D01*
X1245800Y562000D01*
X1246300Y561667D01*
X1246883Y561500D01*
X1247467Y561583D01*
X1247967Y561833D01*
X1248300Y562167D01*
G01X1252400Y561500D02*
Y566500D01*
G01X1256750Y562083D02*
X1257167Y561750D01*
X1257750Y561500D01*
X1258250D01*
X1258750Y561667D01*
X1259083Y561917D01*
X1259250Y562250D01*
X1259167Y562750D01*
X1258833Y563000D01*
X1257333Y563500D01*
X1257000Y564083D01*
X1257167Y564500D01*
X1257500Y564750D01*
X1258000Y564833D01*
X1258500Y564750D01*
X1259000Y564500D01*
G01X1263600Y561500D02*
X1263100Y561583D01*
X1262600Y561917D01*
X1262267Y562500D01*
X1262100Y563167D01*
X1262267Y563833D01*
X1262600Y564417D01*
X1263100Y564750D01*
X1263600Y564833D01*
X1264100Y564750D01*
X1264600Y564417D01*
X1264933Y563833D01*
X1265017Y563167D01*
X1264933Y562500D01*
X1264600Y561917D01*
X1264100Y561583D01*
X1263600Y561500D01*
G01X1273383D02*
Y564833D01*
G01Y564000D02*
X1273717Y564417D01*
X1274217Y564750D01*
X1274883Y564833D01*
X1275467Y564750D01*
X1275967Y564417D01*
X1276217Y563833D01*
Y561500D01*
G01X1279150Y563750D02*
X1281817D01*
X1281567Y564333D01*
X1281150Y564667D01*
X1280567Y564833D01*
X1279983Y564750D01*
X1279483Y564500D01*
X1279150Y563917D01*
X1278983Y563417D01*
Y562917D01*
X1279150Y562417D01*
X1279567Y561917D01*
X1280067Y561583D01*
X1280650Y561500D01*
X1281233Y561667D01*
X1281817Y562167D01*
G01X1284750Y563750D02*
X1287417D01*
X1287167Y564333D01*
X1286750Y564667D01*
X1286167Y564833D01*
X1285583Y564750D01*
X1285083Y564500D01*
X1284750Y563917D01*
X1284583Y563417D01*
Y562917D01*
X1284750Y562417D01*
X1285167Y561917D01*
X1285667Y561583D01*
X1286250Y561500D01*
X1286833Y561667D01*
X1287417Y562167D01*
G01X1293100Y566500D02*
Y561500D01*
G01Y562250D02*
X1292767Y561833D01*
X1292267Y561583D01*
X1291683Y561500D01*
X1291017Y561667D01*
X1290517Y562083D01*
X1290183Y562583D01*
X1290100Y563167D01*
X1290183Y563750D01*
X1290517Y564250D01*
X1291017Y564667D01*
X1291683Y564833D01*
X1292267Y564750D01*
X1292683Y564583D01*
X1293100Y564250D01*
G01X1302800Y566500D02*
Y561500D01*
G01X1301633Y564833D02*
X1303967D01*
G01X1308400Y561500D02*
X1307900Y561583D01*
X1307400Y561917D01*
X1307067Y562500D01*
X1306900Y563167D01*
X1307067Y563833D01*
X1307400Y564417D01*
X1307900Y564750D01*
X1308400Y564833D01*
X1308900Y564750D01*
X1309400Y564417D01*
X1309733Y563833D01*
X1309817Y563167D01*
X1309733Y562500D01*
X1309400Y561917D01*
X1308900Y561583D01*
X1308400Y561500D01*
G01X1022000Y569500D02*
Y574500D01*
X1021000Y573500D01*
G01Y569500D02*
X1023000D01*
G01X1027600Y569333D02*
X1027433Y569417D01*
Y569583D01*
X1027600Y569667D01*
X1027767Y569583D01*
Y569417D01*
X1027600Y569333D01*
G01X1033200Y574500D02*
Y569500D01*
G01X1031283Y574500D02*
X1035117D01*
G01X1037383Y569500D02*
Y574500D01*
G01Y572083D02*
X1037800Y572500D01*
X1038217Y572750D01*
X1038883Y572833D01*
X1039383Y572750D01*
X1039967Y572417D01*
X1040217Y571917D01*
Y569500D01*
G01X1043150Y571750D02*
X1045817D01*
X1045567Y572333D01*
X1045150Y572667D01*
X1044567Y572833D01*
X1043983Y572750D01*
X1043483Y572500D01*
X1043150Y571917D01*
X1042983Y571417D01*
Y570917D01*
X1043150Y570417D01*
X1043567Y569917D01*
X1044067Y569583D01*
X1044650Y569500D01*
X1045233Y569667D01*
X1045817Y570167D01*
G01X1054350Y570083D02*
X1054767Y569750D01*
X1055350Y569500D01*
X1055850D01*
X1056350Y569667D01*
X1056683Y569917D01*
X1056850Y570250D01*
X1056767Y570750D01*
X1056433Y571000D01*
X1054933Y571500D01*
X1054600Y572083D01*
X1054767Y572500D01*
X1055100Y572750D01*
X1055600Y572833D01*
X1056100Y572750D01*
X1056600Y572500D01*
G01X1061200Y572833D02*
Y569500D01*
G01Y574167D02*
X1061033Y574250D01*
Y574417D01*
X1061200Y574500D01*
X1061367Y574417D01*
Y574250D01*
X1061200Y574167D01*
G01X1068300Y574500D02*
Y569500D01*
G01Y570250D02*
X1067967Y569833D01*
X1067467Y569583D01*
X1066883Y569500D01*
X1066217Y569667D01*
X1065717Y570083D01*
X1065383Y570583D01*
X1065300Y571167D01*
X1065383Y571750D01*
X1065717Y572250D01*
X1066217Y572667D01*
X1066883Y572833D01*
X1067467Y572750D01*
X1067883Y572583D01*
X1068300Y572250D01*
G01X1071150Y571750D02*
X1073817D01*
X1073567Y572333D01*
X1073150Y572667D01*
X1072567Y572833D01*
X1071983Y572750D01*
X1071483Y572500D01*
X1071150Y571917D01*
X1070983Y571417D01*
Y570917D01*
X1071150Y570417D01*
X1071567Y569917D01*
X1072067Y569583D01*
X1072650Y569500D01*
X1073233Y569667D01*
X1073817Y570167D01*
G01X1081517Y572833D02*
X1082517Y569500D01*
X1083600Y572833D01*
X1084683Y569500D01*
X1085683Y572833D01*
G01X1089200D02*
Y569500D01*
G01Y574167D02*
X1089033Y574250D01*
Y574417D01*
X1089200Y574500D01*
X1089367Y574417D01*
Y574250D01*
X1089200Y574167D01*
G01X1094800Y574500D02*
Y569500D01*
G01X1093633Y572833D02*
X1095967D01*
G01X1098983Y569500D02*
Y574500D01*
G01Y572083D02*
X1099400Y572500D01*
X1099817Y572750D01*
X1100483Y572833D01*
X1100983Y572750D01*
X1101567Y572417D01*
X1101817Y571917D01*
Y569500D01*
G01X1106000D02*
X1105500Y569583D01*
X1105000Y569917D01*
X1104667Y570500D01*
X1104500Y571167D01*
X1104667Y571833D01*
X1105000Y572417D01*
X1105500Y572750D01*
X1106000Y572833D01*
X1106500Y572750D01*
X1107000Y572417D01*
X1107333Y571833D01*
X1107417Y571167D01*
X1107333Y570500D01*
X1107000Y569917D01*
X1106500Y569583D01*
X1106000Y569500D01*
G01X1110183Y572833D02*
Y570500D01*
X1110517Y569917D01*
X1111017Y569583D01*
X1111600Y569500D01*
X1112183Y569583D01*
X1112683Y569917D01*
X1113017Y570500D01*
G01Y569500D02*
Y572833D01*
G01X1117200Y574500D02*
Y569500D01*
G01X1116033Y572833D02*
X1118367D01*
G01X1127150Y570083D02*
X1127567Y569750D01*
X1128150Y569500D01*
X1128650D01*
X1129150Y569667D01*
X1129483Y569917D01*
X1129650Y570250D01*
X1129567Y570750D01*
X1129233Y571000D01*
X1127733Y571500D01*
X1127400Y572083D01*
X1127567Y572500D01*
X1127900Y572750D01*
X1128400Y572833D01*
X1128900Y572750D01*
X1129400Y572500D01*
G01X1134000Y569500D02*
X1133500Y569583D01*
X1133000Y569917D01*
X1132667Y570500D01*
X1132500Y571167D01*
X1132667Y571833D01*
X1133000Y572417D01*
X1133500Y572750D01*
X1134000Y572833D01*
X1134500Y572750D01*
X1135000Y572417D01*
X1135333Y571833D01*
X1135417Y571167D01*
X1135333Y570500D01*
X1135000Y569917D01*
X1134500Y569583D01*
X1134000Y569500D01*
G01X1139600D02*
Y574500D01*
G01X1146700D02*
Y569500D01*
G01Y570250D02*
X1146367Y569833D01*
X1145867Y569583D01*
X1145283Y569500D01*
X1144617Y569667D01*
X1144117Y570083D01*
X1143783Y570583D01*
X1143700Y571167D01*
X1143783Y571750D01*
X1144117Y572250D01*
X1144617Y572667D01*
X1145283Y572833D01*
X1145867Y572750D01*
X1146283Y572583D01*
X1146700Y572250D01*
G01X1149550Y571750D02*
X1152217D01*
X1151967Y572333D01*
X1151550Y572667D01*
X1150967Y572833D01*
X1150383Y572750D01*
X1149883Y572500D01*
X1149550Y571917D01*
X1149383Y571417D01*
Y570917D01*
X1149550Y570417D01*
X1149967Y569917D01*
X1150467Y569583D01*
X1151050Y569500D01*
X1151633Y569667D01*
X1152217Y570167D01*
G01X1155233Y569500D02*
Y572833D01*
G01Y572167D02*
X1155650Y572500D01*
X1156067Y572750D01*
X1156650Y572833D01*
X1157067Y572750D01*
X1157567Y572500D01*
G01X1165100Y569500D02*
Y572833D01*
G01Y571917D02*
X1165350Y572333D01*
X1165767Y572667D01*
X1166350Y572833D01*
X1166933Y572667D01*
X1167350Y572333D01*
X1167600Y571917D01*
Y569500D01*
G01Y571917D02*
X1167850Y572333D01*
X1168267Y572667D01*
X1168850Y572833D01*
X1169433Y572667D01*
X1169850Y572333D01*
X1170100Y571833D01*
Y569500D01*
G01X1174700D02*
Y572833D01*
G01Y572250D02*
X1174367Y572583D01*
X1173867Y572750D01*
X1173283Y572833D01*
X1172700Y572667D01*
X1172200Y572333D01*
X1171867Y571833D01*
X1171700Y571167D01*
X1171867Y570500D01*
X1172200Y570000D01*
X1172700Y569667D01*
X1173283Y569500D01*
X1173867Y569583D01*
X1174367Y569833D01*
X1174700Y570167D01*
G01X1177550Y570083D02*
X1177967Y569750D01*
X1178550Y569500D01*
X1179050D01*
X1179550Y569667D01*
X1179883Y569917D01*
X1180050Y570250D01*
X1179967Y570750D01*
X1179633Y571000D01*
X1178133Y571500D01*
X1177800Y572083D01*
X1177967Y572500D01*
X1178300Y572750D01*
X1178800Y572833D01*
X1179300Y572750D01*
X1179800Y572500D01*
G01X1182983Y569500D02*
Y574500D01*
G01X1185650Y572833D02*
X1182983Y570917D01*
G01X1184067Y571667D02*
X1185817Y569500D01*
G01X1194100Y567833D02*
Y572833D01*
G01Y572083D02*
X1194517Y572500D01*
X1194933Y572750D01*
X1195600Y572833D01*
X1196183Y572750D01*
X1196767Y572333D01*
X1197017Y571750D01*
X1197100Y571167D01*
X1197017Y570583D01*
X1196767Y570000D01*
X1196267Y569667D01*
X1195600Y569500D01*
X1195017Y569583D01*
X1194433Y569833D01*
X1194100Y570167D01*
G01X1202700Y569500D02*
Y572833D01*
G01Y572250D02*
X1202367Y572583D01*
X1201867Y572750D01*
X1201283Y572833D01*
X1200700Y572667D01*
X1200200Y572333D01*
X1199867Y571833D01*
X1199700Y571167D01*
X1199867Y570500D01*
X1200200Y570000D01*
X1200700Y569667D01*
X1201283Y569500D01*
X1201867Y569583D01*
X1202367Y569833D01*
X1202700Y570167D01*
G01X1208300Y574500D02*
Y569500D01*
G01Y570250D02*
X1207967Y569833D01*
X1207467Y569583D01*
X1206883Y569500D01*
X1206217Y569667D01*
X1205717Y570083D01*
X1205383Y570583D01*
X1205300Y571167D01*
X1205383Y571750D01*
X1205717Y572250D01*
X1206217Y572667D01*
X1206883Y572833D01*
X1207467Y572750D01*
X1207883Y572583D01*
X1208300Y572250D01*
G01X1217833Y568583D02*
X1218167Y569667D01*
G01X1230700Y569500D02*
Y572833D01*
G01Y572250D02*
X1230367Y572583D01*
X1229867Y572750D01*
X1229283Y572833D01*
X1228700Y572667D01*
X1228200Y572333D01*
X1227867Y571833D01*
X1227700Y571167D01*
X1227867Y570500D01*
X1228200Y570000D01*
X1228700Y569667D01*
X1229283Y569500D01*
X1229867Y569583D01*
X1230367Y569833D01*
X1230700Y570167D01*
G01X1233383Y569500D02*
Y572833D01*
G01Y572000D02*
X1233717Y572417D01*
X1234217Y572750D01*
X1234883Y572833D01*
X1235467Y572750D01*
X1235967Y572417D01*
X1236217Y571833D01*
Y569500D01*
G01X1238983D02*
Y572833D01*
G01Y572000D02*
X1239317Y572417D01*
X1239817Y572750D01*
X1240483Y572833D01*
X1241067Y572750D01*
X1241567Y572417D01*
X1241817Y571833D01*
Y569500D01*
G01X1244583Y572833D02*
Y570500D01*
X1244917Y569917D01*
X1245417Y569583D01*
X1246000Y569500D01*
X1246583Y569583D01*
X1247083Y569917D01*
X1247417Y570500D01*
G01Y569500D02*
Y572833D01*
G01X1253100Y569500D02*
Y572833D01*
G01Y572250D02*
X1252767Y572583D01*
X1252267Y572750D01*
X1251683Y572833D01*
X1251100Y572667D01*
X1250600Y572333D01*
X1250267Y571833D01*
X1250100Y571167D01*
X1250267Y570500D01*
X1250600Y570000D01*
X1251100Y569667D01*
X1251683Y569500D01*
X1252267Y569583D01*
X1252767Y569833D01*
X1253100Y570167D01*
G01X1257200Y569500D02*
Y574500D01*
G01X1267233Y569500D02*
Y572833D01*
G01Y572167D02*
X1267650Y572500D01*
X1268067Y572750D01*
X1268650Y572833D01*
X1269067Y572750D01*
X1269567Y572500D01*
G01X1274000Y572833D02*
Y569500D01*
G01Y574167D02*
X1273833Y574250D01*
Y574417D01*
X1274000Y574500D01*
X1274167Y574417D01*
Y574250D01*
X1274000Y574167D01*
G01X1278183Y569500D02*
Y572833D01*
G01Y572000D02*
X1278517Y572417D01*
X1279017Y572750D01*
X1279683Y572833D01*
X1280267Y572750D01*
X1280767Y572417D01*
X1281017Y571833D01*
Y569500D01*
G01X1284033Y568250D02*
X1284617Y567917D01*
X1285283Y567833D01*
X1285867Y567917D01*
X1286367Y568333D01*
X1286700Y568917D01*
Y572833D01*
G01Y572167D02*
X1286367Y572500D01*
X1285867Y572750D01*
X1285283Y572833D01*
X1284617Y572667D01*
X1284200Y572333D01*
X1283867Y571750D01*
X1283700Y571167D01*
X1283783Y570667D01*
X1284117Y570083D01*
X1284617Y569667D01*
X1285283Y569500D01*
X1285783Y569583D01*
X1286367Y569917D01*
X1286700Y570250D01*
G01X1294983Y569500D02*
Y572833D01*
G01Y572000D02*
X1295317Y572417D01*
X1295817Y572750D01*
X1296483Y572833D01*
X1297067Y572750D01*
X1297567Y572417D01*
X1297817Y571833D01*
Y569500D01*
G01X1300750Y571750D02*
X1303417D01*
X1303167Y572333D01*
X1302750Y572667D01*
X1302167Y572833D01*
X1301583Y572750D01*
X1301083Y572500D01*
X1300750Y571917D01*
X1300583Y571417D01*
Y570917D01*
X1300750Y570417D01*
X1301167Y569917D01*
X1301667Y569583D01*
X1302250Y569500D01*
X1302833Y569667D01*
X1303417Y570167D01*
G01X1306350Y571750D02*
X1309017D01*
X1308767Y572333D01*
X1308350Y572667D01*
X1307767Y572833D01*
X1307183Y572750D01*
X1306683Y572500D01*
X1306350Y571917D01*
X1306183Y571417D01*
Y570917D01*
X1306350Y570417D01*
X1306767Y569917D01*
X1307267Y569583D01*
X1307850Y569500D01*
X1308433Y569667D01*
X1309017Y570167D01*
G01X1314700Y574500D02*
Y569500D01*
G01Y570250D02*
X1314367Y569833D01*
X1313867Y569583D01*
X1313283Y569500D01*
X1312617Y569667D01*
X1312117Y570083D01*
X1311783Y570583D01*
X1311700Y571167D01*
X1311783Y571750D01*
X1312117Y572250D01*
X1312617Y572667D01*
X1313283Y572833D01*
X1313867Y572750D01*
X1314283Y572583D01*
X1314700Y572250D01*
G01X1012083Y730500D02*
Y733833D01*
G01Y733000D02*
X1012417Y733417D01*
X1012917Y733750D01*
X1013583Y733833D01*
X1014167Y733750D01*
X1014667Y733417D01*
X1014917Y732833D01*
Y730500D01*
G01X1019100D02*
X1018600Y730583D01*
X1018100Y730917D01*
X1017767Y731500D01*
X1017600Y732167D01*
X1017767Y732833D01*
X1018100Y733417D01*
X1018600Y733750D01*
X1019100Y733833D01*
X1019600Y733750D01*
X1020100Y733417D01*
X1020433Y732833D01*
X1020517Y732167D01*
X1020433Y731500D01*
X1020100Y730917D01*
X1019600Y730583D01*
X1019100Y730500D01*
G01X1028800Y728833D02*
Y733833D01*
G01Y733083D02*
X1029217Y733500D01*
X1029633Y733750D01*
X1030300Y733833D01*
X1030883Y733750D01*
X1031467Y733333D01*
X1031717Y732750D01*
X1031800Y732167D01*
X1031717Y731583D01*
X1031467Y731000D01*
X1030967Y730667D01*
X1030300Y730500D01*
X1029717Y730583D01*
X1029133Y730833D01*
X1028800Y731167D01*
G01X1035900Y730500D02*
Y735500D01*
G01X1040083Y733833D02*
Y731500D01*
X1040417Y730917D01*
X1040917Y730583D01*
X1041500Y730500D01*
X1042083Y730583D01*
X1042583Y730917D01*
X1042917Y731500D01*
G01Y730500D02*
Y733833D01*
G01X1045933Y729250D02*
X1046517Y728917D01*
X1047183Y728833D01*
X1047767Y728917D01*
X1048267Y729333D01*
X1048600Y729917D01*
Y733833D01*
G01Y733167D02*
X1048267Y733500D01*
X1047767Y733750D01*
X1047183Y733833D01*
X1046517Y733667D01*
X1046100Y733333D01*
X1045767Y732750D01*
X1045600Y732167D01*
X1045683Y731667D01*
X1046017Y731083D01*
X1046517Y730667D01*
X1047183Y730500D01*
X1047683Y730583D01*
X1048267Y730917D01*
X1048600Y731250D01*
G01X1051533Y729250D02*
X1052117Y728917D01*
X1052783Y728833D01*
X1053367Y728917D01*
X1053867Y729333D01*
X1054200Y729917D01*
Y733833D01*
G01Y733167D02*
X1053867Y733500D01*
X1053367Y733750D01*
X1052783Y733833D01*
X1052117Y733667D01*
X1051700Y733333D01*
X1051367Y732750D01*
X1051200Y732167D01*
X1051283Y731667D01*
X1051617Y731083D01*
X1052117Y730667D01*
X1052783Y730500D01*
X1053283Y730583D01*
X1053867Y730917D01*
X1054200Y731250D01*
G01X1058300Y733833D02*
Y730500D01*
G01Y735167D02*
X1058133Y735250D01*
Y735417D01*
X1058300Y735500D01*
X1058467Y735417D01*
Y735250D01*
X1058300Y735167D01*
G01X1062483Y730500D02*
Y733833D01*
G01Y733000D02*
X1062817Y733417D01*
X1063317Y733750D01*
X1063983Y733833D01*
X1064567Y733750D01*
X1065067Y733417D01*
X1065317Y732833D01*
Y730500D01*
G01X1068333Y729250D02*
X1068917Y728917D01*
X1069583Y728833D01*
X1070167Y728917D01*
X1070667Y729333D01*
X1071000Y729917D01*
Y733833D01*
G01Y733167D02*
X1070667Y733500D01*
X1070167Y733750D01*
X1069583Y733833D01*
X1068917Y733667D01*
X1068500Y733333D01*
X1068167Y732750D01*
X1068000Y732167D01*
X1068083Y731667D01*
X1068417Y731083D01*
X1068917Y730667D01*
X1069583Y730500D01*
X1070083Y730583D01*
X1070667Y730917D01*
X1071000Y731250D01*
G01X1089493Y104700D02*
Y99700D01*
X1092827D01*
G01X1095510Y103033D02*
X1098010Y99700D01*
G01Y103033D02*
X1095510Y99700D01*
G01X1102360Y99533D02*
X1102193Y99617D01*
Y99783D01*
X1102360Y99867D01*
X1102527Y99783D01*
Y99617D01*
X1102360Y99533D01*
G01Y101783D02*
X1102193Y101867D01*
Y102033D01*
X1102360Y102117D01*
X1102527Y102033D01*
Y101867D01*
X1102360Y101783D01*
G01X1111060Y99700D02*
Y103033D01*
G01Y102117D02*
X1111310Y102533D01*
X1111727Y102867D01*
X1112310Y103033D01*
X1112893Y102867D01*
X1113310Y102533D01*
X1113560Y102117D01*
Y99700D01*
G01Y102117D02*
X1113810Y102533D01*
X1114227Y102867D01*
X1114810Y103033D01*
X1115393Y102867D01*
X1115810Y102533D01*
X1116060Y102033D01*
Y99700D01*
G01X1117743Y103033D02*
Y100700D01*
X1118077Y100117D01*
X1118577Y99783D01*
X1119160Y99700D01*
X1119743Y99783D01*
X1120243Y100117D01*
X1120577Y100700D01*
G01Y99700D02*
Y103033D01*
G01X1123510Y100283D02*
X1123927Y99950D01*
X1124510Y99700D01*
X1125010D01*
X1125510Y99867D01*
X1125843Y100117D01*
X1126010Y100450D01*
X1125927Y100950D01*
X1125593Y101200D01*
X1124093Y101700D01*
X1123760Y102283D01*
X1123927Y102700D01*
X1124260Y102950D01*
X1124760Y103033D01*
X1125260Y102950D01*
X1125760Y102700D01*
G01X1130360Y104700D02*
Y99700D01*
G01X1129193Y103033D02*
X1131527D01*
G01X1140060Y99700D02*
Y104700D01*
G01Y102200D02*
X1140477Y102700D01*
X1140977Y102950D01*
X1141477Y103033D01*
X1142227Y102867D01*
X1142727Y102533D01*
X1143060Y101950D01*
Y101283D01*
X1142893Y100617D01*
X1142560Y100117D01*
X1141977Y99783D01*
X1141477Y99700D01*
X1140977Y99783D01*
X1140477Y100033D01*
X1140060Y100450D01*
G01X1145910Y101950D02*
X1148577D01*
X1148327Y102533D01*
X1147910Y102867D01*
X1147327Y103033D01*
X1146743Y102950D01*
X1146243Y102700D01*
X1145910Y102117D01*
X1145743Y101617D01*
Y101117D01*
X1145910Y100617D01*
X1146327Y100117D01*
X1146827Y99783D01*
X1147410Y99700D01*
X1147993Y99867D01*
X1148577Y100367D01*
G01X1156860Y99700D02*
Y104700D01*
G01Y102200D02*
X1157277Y102700D01*
X1157777Y102950D01*
X1158277Y103033D01*
X1159027Y102867D01*
X1159527Y102533D01*
X1159860Y101950D01*
Y101283D01*
X1159693Y100617D01*
X1159360Y100117D01*
X1158777Y99783D01*
X1158277Y99700D01*
X1157777Y99783D01*
X1157277Y100033D01*
X1156860Y100450D01*
G01X1162793Y99700D02*
Y103033D01*
G01Y102367D02*
X1163210Y102700D01*
X1163627Y102950D01*
X1164210Y103033D01*
X1164627Y102950D01*
X1165127Y102700D01*
G01X1169560Y99700D02*
X1169060Y99783D01*
X1168560Y100117D01*
X1168227Y100700D01*
X1168060Y101367D01*
X1168227Y102033D01*
X1168560Y102617D01*
X1169060Y102950D01*
X1169560Y103033D01*
X1170060Y102950D01*
X1170560Y102617D01*
X1170893Y102033D01*
X1170977Y101367D01*
X1170893Y100700D01*
X1170560Y100117D01*
X1170060Y99783D01*
X1169560Y99700D01*
G01X1173743D02*
Y104700D01*
G01X1176410Y103033D02*
X1173743Y101117D01*
G01X1174827Y101867D02*
X1176577Y99700D01*
G01X1179510Y101950D02*
X1182177D01*
X1181927Y102533D01*
X1181510Y102867D01*
X1180927Y103033D01*
X1180343Y102950D01*
X1179843Y102700D01*
X1179510Y102117D01*
X1179343Y101617D01*
Y101117D01*
X1179510Y100617D01*
X1179927Y100117D01*
X1180427Y99783D01*
X1181010Y99700D01*
X1181593Y99867D01*
X1182177Y100367D01*
G01X1184943Y99700D02*
Y103033D01*
G01Y102200D02*
X1185277Y102617D01*
X1185777Y102950D01*
X1186443Y103033D01*
X1187027Y102950D01*
X1187527Y102617D01*
X1187777Y102033D01*
Y99700D01*
G01X1197560D02*
Y104700D01*
G01X1204660Y99700D02*
Y103033D01*
G01Y102450D02*
X1204327Y102783D01*
X1203827Y102950D01*
X1203243Y103033D01*
X1202660Y102867D01*
X1202160Y102533D01*
X1201827Y102033D01*
X1201660Y101367D01*
X1201827Y100700D01*
X1202160Y100200D01*
X1202660Y99867D01*
X1203243Y99700D01*
X1203827Y99783D01*
X1204327Y100033D01*
X1204660Y100367D01*
G01X1207010Y98200D02*
X1207510Y98033D01*
X1208177Y98200D01*
X1208593Y98533D01*
X1208927Y98950D01*
X1209427Y100283D01*
X1210510Y103033D01*
G01X1207843D02*
X1209427Y100283D01*
G01X1213110Y101950D02*
X1215777D01*
X1215527Y102533D01*
X1215110Y102867D01*
X1214527Y103033D01*
X1213943Y102950D01*
X1213443Y102700D01*
X1213110Y102117D01*
X1212943Y101617D01*
Y101117D01*
X1213110Y100617D01*
X1213527Y100117D01*
X1214027Y99783D01*
X1214610Y99700D01*
X1215193Y99867D01*
X1215777Y100367D01*
G01X1218793Y99700D02*
Y103033D01*
G01Y102367D02*
X1219210Y102700D01*
X1219627Y102950D01*
X1220210Y103033D01*
X1220627Y102950D01*
X1221127Y102700D01*
G01X1088893Y117200D02*
Y112200D01*
X1092227D01*
G01X1094743D02*
Y115533D01*
G01Y114700D02*
X1095077Y115117D01*
X1095577Y115450D01*
X1096243Y115533D01*
X1096827Y115450D01*
X1097327Y115117D01*
X1097577Y114533D01*
Y112200D01*
G01X1101760Y112033D02*
X1101593Y112117D01*
Y112283D01*
X1101760Y112367D01*
X1101927Y112283D01*
Y112117D01*
X1101760Y112033D01*
G01Y114283D02*
X1101593Y114367D01*
Y114533D01*
X1101760Y114617D01*
X1101927Y114533D01*
Y114367D01*
X1101760Y114283D01*
G01X1114293Y115117D02*
X1113710Y115450D01*
X1113210Y115533D01*
X1112543Y115367D01*
X1112043Y115033D01*
X1111710Y114450D01*
X1111627Y113867D01*
X1111710Y113283D01*
X1112043Y112783D01*
X1112543Y112367D01*
X1113210Y112200D01*
X1113793Y112367D01*
X1114293Y112700D01*
G01X1120060Y112200D02*
Y115533D01*
G01Y114950D02*
X1119727Y115283D01*
X1119227Y115450D01*
X1118643Y115533D01*
X1118060Y115367D01*
X1117560Y115033D01*
X1117227Y114533D01*
X1117060Y113867D01*
X1117227Y113200D01*
X1117560Y112700D01*
X1118060Y112367D01*
X1118643Y112200D01*
X1119227Y112283D01*
X1119727Y112533D01*
X1120060Y112867D01*
G01X1122743Y112200D02*
Y115533D01*
G01Y114700D02*
X1123077Y115117D01*
X1123577Y115450D01*
X1124243Y115533D01*
X1124827Y115450D01*
X1125327Y115117D01*
X1125577Y114533D01*
Y112200D01*
G01X1129760Y115533D02*
X1130593Y116575D01*
Y117200D01*
X1129968D01*
Y116575D01*
X1130593D01*
G01X1135360Y117200D02*
Y112200D01*
G01X1134193Y115533D02*
X1136527D01*
G01X1145060Y112200D02*
Y117200D01*
G01Y114700D02*
X1145477Y115200D01*
X1145977Y115450D01*
X1146477Y115533D01*
X1147227Y115367D01*
X1147727Y115033D01*
X1148060Y114450D01*
Y113783D01*
X1147893Y113117D01*
X1147560Y112617D01*
X1146977Y112283D01*
X1146477Y112200D01*
X1145977Y112283D01*
X1145477Y112533D01*
X1145060Y112950D01*
G01X1150910Y114450D02*
X1153577D01*
X1153327Y115033D01*
X1152910Y115367D01*
X1152327Y115533D01*
X1151743Y115450D01*
X1151243Y115200D01*
X1150910Y114617D01*
X1150743Y114117D01*
Y113617D01*
X1150910Y113117D01*
X1151327Y112617D01*
X1151827Y112283D01*
X1152410Y112200D01*
X1152993Y112367D01*
X1153577Y112867D01*
G01X1161860Y112200D02*
Y117200D01*
G01Y114700D02*
X1162277Y115200D01*
X1162777Y115450D01*
X1163277Y115533D01*
X1164027Y115367D01*
X1164527Y115033D01*
X1164860Y114450D01*
Y113783D01*
X1164693Y113117D01*
X1164360Y112617D01*
X1163777Y112283D01*
X1163277Y112200D01*
X1162777Y112283D01*
X1162277Y112533D01*
X1161860Y112950D01*
G01X1167793Y112200D02*
Y115533D01*
G01Y114867D02*
X1168210Y115200D01*
X1168627Y115450D01*
X1169210Y115533D01*
X1169627Y115450D01*
X1170127Y115200D01*
G01X1174560Y112200D02*
X1174060Y112283D01*
X1173560Y112617D01*
X1173227Y113200D01*
X1173060Y113867D01*
X1173227Y114533D01*
X1173560Y115117D01*
X1174060Y115450D01*
X1174560Y115533D01*
X1175060Y115450D01*
X1175560Y115117D01*
X1175893Y114533D01*
X1175977Y113867D01*
X1175893Y113200D01*
X1175560Y112617D01*
X1175060Y112283D01*
X1174560Y112200D01*
G01X1178743D02*
Y117200D01*
G01X1181410Y115533D02*
X1178743Y113617D01*
G01X1179827Y114367D02*
X1181577Y112200D01*
G01X1184510Y114450D02*
X1187177D01*
X1186927Y115033D01*
X1186510Y115367D01*
X1185927Y115533D01*
X1185343Y115450D01*
X1184843Y115200D01*
X1184510Y114617D01*
X1184343Y114117D01*
Y113617D01*
X1184510Y113117D01*
X1184927Y112617D01*
X1185427Y112283D01*
X1186010Y112200D01*
X1186593Y112367D01*
X1187177Y112867D01*
G01X1189943Y112200D02*
Y115533D01*
G01Y114700D02*
X1190277Y115117D01*
X1190777Y115450D01*
X1191443Y115533D01*
X1192027Y115450D01*
X1192527Y115117D01*
X1192777Y114533D01*
Y112200D01*
G01X1202560D02*
Y117200D01*
G01X1209660Y112200D02*
Y115533D01*
G01Y114950D02*
X1209327Y115283D01*
X1208827Y115450D01*
X1208243Y115533D01*
X1207660Y115367D01*
X1207160Y115033D01*
X1206827Y114533D01*
X1206660Y113867D01*
X1206827Y113200D01*
X1207160Y112700D01*
X1207660Y112367D01*
X1208243Y112200D01*
X1208827Y112283D01*
X1209327Y112533D01*
X1209660Y112867D01*
G01X1212010Y110700D02*
X1212510Y110533D01*
X1213177Y110700D01*
X1213593Y111033D01*
X1213927Y111450D01*
X1214427Y112783D01*
X1215510Y115533D01*
G01X1212843D02*
X1214427Y112783D01*
G01X1218110Y114450D02*
X1220777D01*
X1220527Y115033D01*
X1220110Y115367D01*
X1219527Y115533D01*
X1218943Y115450D01*
X1218443Y115200D01*
X1218110Y114617D01*
X1217943Y114117D01*
Y113617D01*
X1218110Y113117D01*
X1218527Y112617D01*
X1219027Y112283D01*
X1219610Y112200D01*
X1220193Y112367D01*
X1220777Y112867D01*
G01X1223793Y112200D02*
Y115533D01*
G01Y114867D02*
X1224210Y115200D01*
X1224627Y115450D01*
X1225210Y115533D01*
X1225627Y115450D01*
X1226127Y115200D01*
G01X1087667Y124000D02*
Y129000D01*
X1089333D01*
X1090000Y128750D01*
X1090500Y128417D01*
X1090917Y127917D01*
X1091250Y127333D01*
X1091333Y126500D01*
X1091250Y125667D01*
X1090917Y125083D01*
X1090500Y124583D01*
X1090000Y124250D01*
X1089333Y124000D01*
X1087667D01*
G01X1093933D02*
Y127333D01*
G01Y126667D02*
X1094350Y127000D01*
X1094767Y127250D01*
X1095350Y127333D01*
X1095767Y127250D01*
X1096267Y127000D01*
G01X1100700Y127333D02*
Y124000D01*
G01Y128667D02*
X1100533Y128750D01*
Y128917D01*
X1100700Y129000D01*
X1100867Y128917D01*
Y128750D01*
X1100700Y128667D01*
G01X1106300Y124000D02*
Y129000D01*
G01X1111900Y124000D02*
Y129000D01*
G01X1121517Y124000D02*
Y129000D01*
X1124683D01*
G01X1123517Y126583D02*
X1121517D01*
G01X1127533Y124000D02*
Y127333D01*
G01Y126667D02*
X1127950Y127000D01*
X1128367Y127250D01*
X1128950Y127333D01*
X1129367Y127250D01*
X1129867Y127000D01*
G01X1134300Y124000D02*
X1133800Y124083D01*
X1133300Y124417D01*
X1132967Y125000D01*
X1132800Y125667D01*
X1132967Y126333D01*
X1133300Y126917D01*
X1133800Y127250D01*
X1134300Y127333D01*
X1134800Y127250D01*
X1135300Y126917D01*
X1135633Y126333D01*
X1135717Y125667D01*
X1135633Y125000D01*
X1135300Y124417D01*
X1134800Y124083D01*
X1134300Y124000D01*
G01X1137400D02*
Y127333D01*
G01Y126417D02*
X1137650Y126833D01*
X1138067Y127167D01*
X1138650Y127333D01*
X1139233Y127167D01*
X1139650Y126833D01*
X1139900Y126417D01*
Y124000D01*
G01Y126417D02*
X1140150Y126833D01*
X1140567Y127167D01*
X1141150Y127333D01*
X1141733Y127167D01*
X1142150Y126833D01*
X1142400Y126333D01*
Y124000D01*
G01X1167483Y122333D02*
X1166650Y123167D01*
X1166233Y124000D01*
Y127333D01*
X1166650Y128167D01*
X1167483Y129000D01*
G01X1174167Y126667D02*
X1174500Y126917D01*
X1174750Y127333D01*
X1174917Y127917D01*
X1174750Y128417D01*
X1174417Y128750D01*
X1173833Y129000D01*
X1171583D01*
Y124000D01*
X1174333D01*
X1174917Y124333D01*
X1175250Y124833D01*
X1175417Y125417D01*
X1175250Y126000D01*
X1174750Y126500D01*
X1174167Y126667D01*
X1171583D01*
G01X1179100Y124000D02*
X1178433Y124083D01*
X1177850Y124417D01*
X1177350Y124917D01*
X1177017Y125500D01*
X1176850Y126167D01*
Y126833D01*
X1177017Y127500D01*
X1177350Y128083D01*
X1177850Y128583D01*
X1178433Y128917D01*
X1179100Y129000D01*
X1179767Y128917D01*
X1180350Y128583D01*
X1180850Y128083D01*
X1181183Y127500D01*
X1181350Y126833D01*
Y126167D01*
X1181183Y125500D01*
X1180850Y124917D01*
X1180350Y124417D01*
X1179767Y124083D01*
X1179100Y124000D01*
G01X1184700Y129000D02*
Y124000D01*
G01X1182783Y129000D02*
X1186617D01*
G01X1190300D02*
Y124000D01*
G01X1188383Y129000D02*
X1192217D01*
G01X1195900Y124000D02*
X1195233Y124083D01*
X1194650Y124417D01*
X1194150Y124917D01*
X1193817Y125500D01*
X1193650Y126167D01*
Y126833D01*
X1193817Y127500D01*
X1194150Y128083D01*
X1194650Y128583D01*
X1195233Y128917D01*
X1195900Y129000D01*
X1196567Y128917D01*
X1197150Y128583D01*
X1197650Y128083D01*
X1197983Y127500D01*
X1198150Y126833D01*
Y126167D01*
X1197983Y125500D01*
X1197650Y124917D01*
X1197150Y124417D01*
X1196567Y124083D01*
X1195900Y124000D01*
G01X1199333D02*
Y129000D01*
X1201500Y124833D01*
X1203667Y129000D01*
Y124000D01*
G01X1207517Y122333D02*
X1208350Y123167D01*
X1208767Y124000D01*
Y127333D01*
X1208350Y128167D01*
X1207517Y129000D01*
G01X1218300D02*
Y124000D01*
G01X1217133Y127333D02*
X1219467D01*
G01X1223900Y124000D02*
X1223400Y124083D01*
X1222900Y124417D01*
X1222567Y125000D01*
X1222400Y125667D01*
X1222567Y126333D01*
X1222900Y126917D01*
X1223400Y127250D01*
X1223900Y127333D01*
X1224400Y127250D01*
X1224900Y126917D01*
X1225233Y126333D01*
X1225317Y125667D01*
X1225233Y125000D01*
X1224900Y124417D01*
X1224400Y124083D01*
X1223900Y124000D01*
G01X1233433Y129000D02*
Y124000D01*
X1236767D01*
G01X1239450Y127333D02*
X1241950Y124000D01*
G01Y127333D02*
X1239450Y124000D01*
G01X1109833Y590500D02*
Y595500D01*
X1111833D01*
X1112500Y595250D01*
X1113000Y594667D01*
X1113167Y594000D01*
X1113000Y593333D01*
X1112583Y592833D01*
X1111833Y592583D01*
X1109833D01*
G01X1117100Y590500D02*
Y595500D01*
G01X1121283Y593833D02*
Y591500D01*
X1121617Y590917D01*
X1122117Y590583D01*
X1122700Y590500D01*
X1123283Y590583D01*
X1123783Y590917D01*
X1124117Y591500D01*
G01Y590500D02*
Y593833D01*
G01X1127133Y589250D02*
X1127717Y588917D01*
X1128383Y588833D01*
X1128967Y588917D01*
X1129467Y589333D01*
X1129800Y589917D01*
Y593833D01*
G01Y593167D02*
X1129467Y593500D01*
X1128967Y593750D01*
X1128383Y593833D01*
X1127717Y593667D01*
X1127300Y593333D01*
X1126967Y592750D01*
X1126800Y592167D01*
X1126883Y591667D01*
X1127217Y591083D01*
X1127717Y590667D01*
X1128383Y590500D01*
X1128883Y590583D01*
X1129467Y590917D01*
X1129800Y591250D01*
G01X1132733Y589250D02*
X1133317Y588917D01*
X1133983Y588833D01*
X1134567Y588917D01*
X1135067Y589333D01*
X1135400Y589917D01*
Y593833D01*
G01Y593167D02*
X1135067Y593500D01*
X1134567Y593750D01*
X1133983Y593833D01*
X1133317Y593667D01*
X1132900Y593333D01*
X1132567Y592750D01*
X1132400Y592167D01*
X1132483Y591667D01*
X1132817Y591083D01*
X1133317Y590667D01*
X1133983Y590500D01*
X1134483Y590583D01*
X1135067Y590917D01*
X1135400Y591250D01*
G01X1139500Y593833D02*
Y590500D01*
G01Y595167D02*
X1139333Y595250D01*
Y595417D01*
X1139500Y595500D01*
X1139667Y595417D01*
Y595250D01*
X1139500Y595167D01*
G01X1143683Y590500D02*
Y593833D01*
G01Y593000D02*
X1144017Y593417D01*
X1144517Y593750D01*
X1145183Y593833D01*
X1145767Y593750D01*
X1146267Y593417D01*
X1146517Y592833D01*
Y590500D01*
G01X1149533Y589250D02*
X1150117Y588917D01*
X1150783Y588833D01*
X1151367Y588917D01*
X1151867Y589333D01*
X1152200Y589917D01*
Y593833D01*
G01Y593167D02*
X1151867Y593500D01*
X1151367Y593750D01*
X1150783Y593833D01*
X1150117Y593667D01*
X1149700Y593333D01*
X1149367Y592750D01*
X1149200Y592167D01*
X1149283Y591667D01*
X1149617Y591083D01*
X1150117Y590667D01*
X1150783Y590500D01*
X1151283Y590583D01*
X1151867Y590917D01*
X1152200Y591250D01*
G01X1163233Y593417D02*
X1162650Y593750D01*
X1162150Y593833D01*
X1161483Y593667D01*
X1160983Y593333D01*
X1160650Y592750D01*
X1160567Y592167D01*
X1160650Y591583D01*
X1160983Y591083D01*
X1161483Y590667D01*
X1162150Y590500D01*
X1162733Y590667D01*
X1163233Y591000D01*
G01X1166333Y590500D02*
Y593833D01*
G01Y593167D02*
X1166750Y593500D01*
X1167167Y593750D01*
X1167750Y593833D01*
X1168167Y593750D01*
X1168667Y593500D01*
G01X1173100Y593833D02*
Y590500D01*
G01Y595167D02*
X1172933Y595250D01*
Y595417D01*
X1173100Y595500D01*
X1173267Y595417D01*
Y595250D01*
X1173100Y595167D01*
G01X1178700Y595500D02*
Y590500D01*
G01X1177533Y593833D02*
X1179867D01*
G01X1183050Y592750D02*
X1185717D01*
X1185467Y593333D01*
X1185050Y593667D01*
X1184467Y593833D01*
X1183883Y593750D01*
X1183383Y593500D01*
X1183050Y592917D01*
X1182883Y592417D01*
Y591917D01*
X1183050Y591417D01*
X1183467Y590917D01*
X1183967Y590583D01*
X1184550Y590500D01*
X1185133Y590667D01*
X1185717Y591167D01*
G01X1188733Y590500D02*
Y593833D01*
G01Y593167D02*
X1189150Y593500D01*
X1189567Y593750D01*
X1190150Y593833D01*
X1190567Y593750D01*
X1191067Y593500D01*
G01X1195500Y593833D02*
Y590500D01*
G01Y595167D02*
X1195333Y595250D01*
Y595417D01*
X1195500Y595500D01*
X1195667Y595417D01*
Y595250D01*
X1195500Y595167D01*
G01X1202600Y590500D02*
Y593833D01*
G01Y593250D02*
X1202267Y593583D01*
X1201767Y593750D01*
X1201183Y593833D01*
X1200600Y593667D01*
X1200100Y593333D01*
X1199767Y592833D01*
X1199600Y592167D01*
X1199767Y591500D01*
X1200100Y591000D01*
X1200600Y590667D01*
X1201183Y590500D01*
X1201767Y590583D01*
X1202267Y590833D01*
X1202600Y591167D01*
G01X1106417Y735500D02*
X1108500Y730500D01*
X1110583Y735500D01*
G01X1113100D02*
X1115100D01*
G01X1114100D02*
Y730500D01*
G01X1113100D02*
X1115100D01*
G01X1118033D02*
Y735500D01*
X1120033D01*
X1120700Y735250D01*
X1121200Y734667D01*
X1121367Y734000D01*
X1121200Y733333D01*
X1120783Y732833D01*
X1120033Y732583D01*
X1118033D01*
G01X1184667Y150367D02*
X1185000Y150617D01*
X1185250Y151033D01*
X1185417Y151617D01*
X1185250Y152117D01*
X1184917Y152450D01*
X1184333Y152700D01*
X1182083D01*
Y147700D01*
X1184833D01*
X1185417Y148033D01*
X1185750Y148533D01*
X1185917Y149117D01*
X1185750Y149700D01*
X1185250Y150200D01*
X1184667Y150367D01*
X1182083D01*
G01X1187517Y147700D02*
X1189600Y152700D01*
X1191683Y147700D01*
G01X1190933Y149450D02*
X1188267D01*
G01X1197033Y152283D02*
X1196533Y152533D01*
X1195950Y152700D01*
X1195283D01*
X1194533Y152450D01*
X1193950Y152033D01*
X1193533Y151533D01*
X1193200Y150700D01*
X1193117Y149950D01*
X1193283Y149200D01*
X1193533Y148700D01*
X1194033Y148200D01*
X1194617Y147867D01*
X1195200Y147700D01*
X1195783D01*
X1196367Y147867D01*
X1196867Y148117D01*
X1197283Y148450D01*
G01X1198967Y147700D02*
Y152700D01*
G01X1202133D02*
X1198967Y149617D01*
G01X1202633Y147700D02*
X1200383Y151033D01*
G01X1210167Y147700D02*
Y152700D01*
X1211833D01*
X1212500Y152450D01*
X1213000Y152117D01*
X1213417Y151617D01*
X1213750Y151033D01*
X1213833Y150200D01*
X1213750Y149367D01*
X1213417Y148783D01*
X1213000Y148283D01*
X1212500Y147950D01*
X1211833Y147700D01*
X1210167D01*
G01X1215933D02*
Y152700D01*
X1218017D01*
X1218683Y152450D01*
X1219100Y152117D01*
X1219267Y151450D01*
X1219100Y150783D01*
X1218600Y150367D01*
X1218017Y150117D01*
X1215933D01*
G01X1218017D02*
X1219267Y147700D01*
G01X1222200Y152700D02*
X1224200D01*
G01X1223200D02*
Y147700D01*
G01X1222200D02*
X1224200D01*
G01X1227133Y152700D02*
Y147700D01*
X1230467D01*
G01X1232733Y152700D02*
Y147700D01*
X1236067D01*
G01X1259900D02*
Y151033D01*
G01Y150117D02*
X1260150Y150533D01*
X1260567Y150867D01*
X1261150Y151033D01*
X1261733Y150867D01*
X1262150Y150533D01*
X1262400Y150117D01*
Y147700D01*
G01Y150117D02*
X1262650Y150533D01*
X1263067Y150867D01*
X1263650Y151033D01*
X1264233Y150867D01*
X1264650Y150533D01*
X1264900Y150033D01*
Y147700D01*
G01X1268000Y151033D02*
Y147700D01*
G01Y152367D02*
X1267833Y152450D01*
Y152617D01*
X1268000Y152700D01*
X1268167Y152617D01*
Y152450D01*
X1268000Y152367D01*
G01X1273600Y147700D02*
Y152700D01*
G01X1277950Y148283D02*
X1278367Y147950D01*
X1278950Y147700D01*
X1279450D01*
X1279950Y147867D01*
X1280283Y148117D01*
X1280450Y148450D01*
X1280367Y148950D01*
X1280033Y149200D01*
X1278533Y149700D01*
X1278200Y150283D01*
X1278367Y150700D01*
X1278700Y150950D01*
X1279200Y151033D01*
X1279700Y150950D01*
X1280200Y150700D01*
G01X1284383Y146033D02*
X1283550Y146867D01*
X1283133Y147700D01*
Y151033D01*
X1283550Y151867D01*
X1284383Y152700D01*
G01X1288483Y147700D02*
Y152700D01*
X1292317Y147700D01*
Y152700D01*
G01X1294333Y147700D02*
Y152700D01*
X1296333D01*
X1297000Y152450D01*
X1297500Y151867D01*
X1297667Y151200D01*
X1297500Y150533D01*
X1297083Y150033D01*
X1296333Y149783D01*
X1294333D01*
G01X1301600Y152700D02*
Y147700D01*
G01X1299683Y152700D02*
X1303517D01*
G01X1305450Y147700D02*
Y152700D01*
G01X1308950D02*
Y147700D01*
G01Y150200D02*
X1305450D01*
G01X1313217Y146033D02*
X1314050Y146867D01*
X1314467Y147700D01*
Y151033D01*
X1314050Y151867D01*
X1313217Y152700D01*
G01X1136167Y157700D02*
Y162700D01*
X1137833D01*
X1138500Y162450D01*
X1139000Y162117D01*
X1139417Y161617D01*
X1139750Y161033D01*
X1139833Y160200D01*
X1139750Y159367D01*
X1139417Y158783D01*
X1139000Y158283D01*
X1138500Y157950D01*
X1137833Y157700D01*
X1136167D01*
G01X1142017Y161867D02*
X1142517Y162367D01*
X1143100Y162617D01*
X1143767Y162700D01*
X1144600Y162533D01*
X1145183Y162117D01*
X1145350Y161617D01*
X1145267Y161117D01*
X1144933Y160700D01*
X1143267Y159867D01*
X1142517Y159283D01*
X1142017Y158450D01*
X1141850Y157700D01*
X1145350D01*
G01X1178750Y315500D02*
Y320500D01*
G01X1182250D02*
Y315500D01*
G01Y318000D02*
X1178750D01*
G01X1186100Y315500D02*
X1185433Y315583D01*
X1184850Y315917D01*
X1184350Y316417D01*
X1184017Y317000D01*
X1183850Y317667D01*
Y318333D01*
X1184017Y319000D01*
X1184350Y319583D01*
X1184850Y320083D01*
X1185433Y320417D01*
X1186100Y320500D01*
X1186767Y320417D01*
X1187350Y320083D01*
X1187850Y319583D01*
X1188183Y319000D01*
X1188350Y318333D01*
Y317667D01*
X1188183Y317000D01*
X1187850Y316417D01*
X1187350Y315917D01*
X1186767Y315583D01*
X1186100Y315500D01*
G01X1190033Y320500D02*
Y315500D01*
X1193367D01*
G01X1198967D02*
X1195633D01*
Y320500D01*
X1198967D01*
G01X1197633Y318083D02*
X1195633D01*
G01X1222800Y315500D02*
Y318833D01*
G01Y317917D02*
X1223050Y318333D01*
X1223467Y318667D01*
X1224050Y318833D01*
X1224633Y318667D01*
X1225050Y318333D01*
X1225300Y317917D01*
Y315500D01*
G01Y317917D02*
X1225550Y318333D01*
X1225967Y318667D01*
X1226550Y318833D01*
X1227133Y318667D01*
X1227550Y318333D01*
X1227800Y317833D01*
Y315500D01*
G01X1230900Y318833D02*
Y315500D01*
G01Y320167D02*
X1230733Y320250D01*
Y320417D01*
X1230900Y320500D01*
X1231067Y320417D01*
Y320250D01*
X1230900Y320167D01*
G01X1236500Y315500D02*
Y320500D01*
G01X1240850Y316083D02*
X1241267Y315750D01*
X1241850Y315500D01*
X1242350D01*
X1242850Y315667D01*
X1243183Y315917D01*
X1243350Y316250D01*
X1243267Y316750D01*
X1242933Y317000D01*
X1241433Y317500D01*
X1241100Y318083D01*
X1241267Y318500D01*
X1241600Y318750D01*
X1242100Y318833D01*
X1242600Y318750D01*
X1243100Y318500D01*
G01X1247283Y313833D02*
X1246450Y314667D01*
X1246033Y315500D01*
Y318833D01*
X1246450Y319667D01*
X1247283Y320500D01*
G01X1251633Y315500D02*
Y320500D01*
X1253633D01*
X1254300Y320250D01*
X1254800Y319667D01*
X1254967Y319000D01*
X1254800Y318333D01*
X1254383Y317833D01*
X1253633Y317583D01*
X1251633D01*
G01X1258900Y320500D02*
Y315500D01*
G01X1256983Y320500D02*
X1260817D01*
G01X1262750Y315500D02*
Y320500D01*
G01X1266250D02*
Y315500D01*
G01Y318000D02*
X1262750D01*
G01X1270517Y313833D02*
X1271350Y314667D01*
X1271767Y315500D01*
Y318833D01*
X1271350Y319667D01*
X1270517Y320500D01*
G01X1135167Y315700D02*
Y320700D01*
X1136833D01*
X1137500Y320450D01*
X1138000Y320117D01*
X1138417Y319617D01*
X1138750Y319033D01*
X1138833Y318200D01*
X1138750Y317367D01*
X1138417Y316783D01*
X1138000Y316283D01*
X1137500Y315950D01*
X1136833Y315700D01*
X1135167D01*
G01X1142600D02*
Y320700D01*
X1141600Y319700D01*
G01Y315700D02*
X1143600D01*
G01X1136833Y619917D02*
X1136250Y620250D01*
X1135750Y620333D01*
X1135083Y620167D01*
X1134583Y619833D01*
X1134250Y619250D01*
X1134167Y618667D01*
X1134250Y618083D01*
X1134583Y617583D01*
X1135083Y617167D01*
X1135750Y617000D01*
X1136333Y617167D01*
X1136833Y617500D01*
G01X1141100Y617000D02*
X1140600Y617083D01*
X1140100Y617417D01*
X1139767Y618000D01*
X1139600Y618667D01*
X1139767Y619333D01*
X1140100Y619917D01*
X1140600Y620250D01*
X1141100Y620333D01*
X1141600Y620250D01*
X1142100Y619917D01*
X1142433Y619333D01*
X1142517Y618667D01*
X1142433Y618000D01*
X1142100Y617417D01*
X1141600Y617083D01*
X1141100Y617000D01*
G01X1145200Y615333D02*
Y620333D01*
G01Y619583D02*
X1145617Y620000D01*
X1146033Y620250D01*
X1146700Y620333D01*
X1147283Y620250D01*
X1147867Y619833D01*
X1148117Y619250D01*
X1148200Y618667D01*
X1148117Y618083D01*
X1147867Y617500D01*
X1147367Y617167D01*
X1146700Y617000D01*
X1146117Y617083D01*
X1145533Y617333D01*
X1145200Y617667D01*
G01X1150800Y615333D02*
Y620333D01*
G01Y619583D02*
X1151217Y620000D01*
X1151633Y620250D01*
X1152300Y620333D01*
X1152883Y620250D01*
X1153467Y619833D01*
X1153717Y619250D01*
X1153800Y618667D01*
X1153717Y618083D01*
X1153467Y617500D01*
X1152967Y617167D01*
X1152300Y617000D01*
X1151717Y617083D01*
X1151133Y617333D01*
X1150800Y617667D01*
G01X1156650Y619250D02*
X1159317D01*
X1159067Y619833D01*
X1158650Y620167D01*
X1158067Y620333D01*
X1157483Y620250D01*
X1156983Y620000D01*
X1156650Y619417D01*
X1156483Y618917D01*
Y618417D01*
X1156650Y617917D01*
X1157067Y617417D01*
X1157567Y617083D01*
X1158150Y617000D01*
X1158733Y617167D01*
X1159317Y617667D01*
G01X1162333Y617000D02*
Y620333D01*
G01Y619667D02*
X1162750Y620000D01*
X1163167Y620250D01*
X1163750Y620333D01*
X1164167Y620250D01*
X1164667Y620000D01*
G01X1180417Y734500D02*
X1182500Y729500D01*
X1184583Y734500D01*
G01X1188100Y729500D02*
X1187433Y729583D01*
X1186850Y729917D01*
X1186350Y730417D01*
X1186017Y731000D01*
X1185850Y731667D01*
Y732333D01*
X1186017Y733000D01*
X1186350Y733583D01*
X1186850Y734083D01*
X1187433Y734417D01*
X1188100Y734500D01*
X1188767Y734417D01*
X1189350Y734083D01*
X1189850Y733583D01*
X1190183Y733000D01*
X1190350Y732333D01*
Y731667D01*
X1190183Y731000D01*
X1189850Y730417D01*
X1189350Y729917D01*
X1188767Y729583D01*
X1188100Y729500D01*
G01X1192033D02*
Y734500D01*
X1194033D01*
X1194700Y734250D01*
X1195200Y733667D01*
X1195367Y733000D01*
X1195200Y732333D01*
X1194783Y731833D01*
X1194033Y731583D01*
X1192033D01*
G01X1210333Y218700D02*
Y213700D01*
X1213667D01*
G01X1216350Y217033D02*
X1218850Y213700D01*
G01Y217033D02*
X1216350Y213700D01*
G01X1207333Y260500D02*
Y255500D01*
X1210667D01*
G01X1213183D02*
Y258833D01*
G01Y258000D02*
X1213517Y258417D01*
X1214017Y258750D01*
X1214683Y258833D01*
X1215267Y258750D01*
X1215767Y258417D01*
X1216017Y257833D01*
Y255500D01*
G01X1218250Y281583D02*
X1218667Y281250D01*
X1219250Y281000D01*
X1219750D01*
X1220250Y281167D01*
X1220583Y281417D01*
X1220750Y281750D01*
X1220667Y282250D01*
X1220333Y282500D01*
X1218833Y283000D01*
X1218500Y283583D01*
X1218667Y284000D01*
X1219000Y284250D01*
X1219500Y284333D01*
X1220000Y284250D01*
X1220500Y284000D01*
G01X1225100Y286000D02*
Y281000D01*
G01X1223933Y284333D02*
X1226267D01*
G01X1229283D02*
Y282000D01*
X1229617Y281417D01*
X1230117Y281083D01*
X1230700Y281000D01*
X1231283Y281083D01*
X1231783Y281417D01*
X1232117Y282000D01*
G01Y281000D02*
Y284333D01*
G01X1234800Y281000D02*
Y286000D01*
G01Y283500D02*
X1235217Y284000D01*
X1235717Y284250D01*
X1236217Y284333D01*
X1236967Y284167D01*
X1237467Y283833D01*
X1237800Y283250D01*
Y282583D01*
X1237633Y281917D01*
X1237300Y281417D01*
X1236717Y281083D01*
X1236217Y281000D01*
X1235717Y281083D01*
X1235217Y281333D01*
X1234800Y281750D01*
G01X1247500Y281000D02*
Y286000D01*
G01X1251850Y283250D02*
X1254517D01*
X1254267Y283833D01*
X1253850Y284167D01*
X1253267Y284333D01*
X1252683Y284250D01*
X1252183Y284000D01*
X1251850Y283417D01*
X1251683Y282917D01*
Y282417D01*
X1251850Y281917D01*
X1252267Y281417D01*
X1252767Y281083D01*
X1253350Y281000D01*
X1253933Y281167D01*
X1254517Y281667D01*
G01X1257283Y281000D02*
Y284333D01*
G01Y283500D02*
X1257617Y283917D01*
X1258117Y284250D01*
X1258783Y284333D01*
X1259367Y284250D01*
X1259867Y283917D01*
X1260117Y283333D01*
Y281000D01*
G01X1263133Y279750D02*
X1263717Y279417D01*
X1264383Y279333D01*
X1264967Y279417D01*
X1265467Y279833D01*
X1265800Y280417D01*
Y284333D01*
G01Y283667D02*
X1265467Y284000D01*
X1264967Y284250D01*
X1264383Y284333D01*
X1263717Y284167D01*
X1263300Y283833D01*
X1262967Y283250D01*
X1262800Y282667D01*
X1262883Y282167D01*
X1263217Y281583D01*
X1263717Y281167D01*
X1264383Y281000D01*
X1264883Y281083D01*
X1265467Y281417D01*
X1265800Y281750D01*
G01X1269900Y286000D02*
Y281000D01*
G01X1268733Y284333D02*
X1271067D01*
G01X1274083Y281000D02*
Y286000D01*
G01Y283583D02*
X1274500Y284000D01*
X1274917Y284250D01*
X1275583Y284333D01*
X1276083Y284250D01*
X1276667Y283917D01*
X1276917Y283417D01*
Y281000D01*
G01X1280017Y281917D02*
X1282183D01*
G01Y283417D02*
X1280017D01*
G01X1285117Y283083D02*
X1285700Y283667D01*
X1286200Y284000D01*
X1286867Y284167D01*
X1287450Y284000D01*
X1287867Y283667D01*
X1288200Y283167D01*
X1288283Y282583D01*
X1288200Y282083D01*
X1287867Y281583D01*
X1287367Y281167D01*
X1286783Y281000D01*
X1286117Y281167D01*
X1285533Y281667D01*
X1285200Y282417D01*
X1285117Y283250D01*
X1285283Y284333D01*
X1285533Y284917D01*
X1285950Y285500D01*
X1286533Y285917D01*
X1287117Y286000D01*
X1287700Y285833D01*
X1288117Y285417D01*
G01X1291383Y282667D02*
X1293383D01*
G01X1292300Y283750D02*
Y281583D01*
G01X1296400Y280833D02*
X1299400Y286000D01*
G01X1302417Y282667D02*
X1304583D01*
G01X1307267Y281750D02*
X1307767Y281333D01*
X1308350Y281083D01*
X1309100Y281000D01*
X1309850Y281167D01*
X1310433Y281500D01*
X1310850Y282083D01*
X1310933Y282750D01*
X1310767Y283417D01*
X1310350Y283833D01*
X1309767Y284167D01*
X1309183Y284250D01*
X1308600Y284167D01*
X1307850Y283833D01*
X1308100Y286000D01*
X1310350D01*
G01X1312200Y281000D02*
Y284333D01*
G01Y283417D02*
X1312450Y283833D01*
X1312867Y284167D01*
X1313450Y284333D01*
X1314033Y284167D01*
X1314450Y283833D01*
X1314700Y283417D01*
Y281000D01*
G01Y283417D02*
X1314950Y283833D01*
X1315367Y284167D01*
X1315950Y284333D01*
X1316533Y284167D01*
X1316950Y283833D01*
X1317200Y283333D01*
Y281000D01*
G01X1320300Y284333D02*
Y281000D01*
G01Y285667D02*
X1320133Y285750D01*
Y285917D01*
X1320300Y286000D01*
X1320467Y285917D01*
Y285750D01*
X1320300Y285667D01*
G01X1325900Y281000D02*
Y286000D01*
G01X1241083Y841667D02*
X1243083D01*
G01X1242000Y842750D02*
Y840583D01*
G01X1246100Y839833D02*
X1249100Y845000D01*
G01X1252117Y841667D02*
X1254283D01*
G01X1256967Y840750D02*
X1257467Y840333D01*
X1258050Y840083D01*
X1258800Y840000D01*
X1259550Y840167D01*
X1260133Y840500D01*
X1260550Y841083D01*
X1260633Y841750D01*
X1260467Y842417D01*
X1260050Y842833D01*
X1259467Y843167D01*
X1258883Y843250D01*
X1258300Y843167D01*
X1257550Y842833D01*
X1257800Y845000D01*
X1260050D01*
G01X1261900Y840000D02*
Y843333D01*
G01Y842417D02*
X1262150Y842833D01*
X1262567Y843167D01*
X1263150Y843333D01*
X1263733Y843167D01*
X1264150Y842833D01*
X1264400Y842417D01*
Y840000D01*
G01Y842417D02*
X1264650Y842833D01*
X1265067Y843167D01*
X1265650Y843333D01*
X1266233Y843167D01*
X1266650Y842833D01*
X1266900Y842333D01*
Y840000D01*
G01X1270000Y843333D02*
Y840000D01*
G01Y844667D02*
X1269833Y844750D01*
Y844917D01*
X1270000Y845000D01*
X1270167Y844917D01*
Y844750D01*
X1270000Y844667D01*
G01X1275600Y840000D02*
Y845000D01*
G01X1241083Y826667D02*
X1243083D01*
G01X1242000Y827750D02*
Y825583D01*
G01X1246100Y824833D02*
X1249100Y830000D01*
G01X1252117Y826667D02*
X1254283D01*
G01X1256967Y825750D02*
X1257467Y825333D01*
X1258050Y825083D01*
X1258800Y825000D01*
X1259550Y825167D01*
X1260133Y825500D01*
X1260550Y826083D01*
X1260633Y826750D01*
X1260467Y827417D01*
X1260050Y827833D01*
X1259467Y828167D01*
X1258883Y828250D01*
X1258300Y828167D01*
X1257550Y827833D01*
X1257800Y830000D01*
X1260050D01*
G01X1261900Y825000D02*
Y828333D01*
G01Y827417D02*
X1262150Y827833D01*
X1262567Y828167D01*
X1263150Y828333D01*
X1263733Y828167D01*
X1264150Y827833D01*
X1264400Y827417D01*
Y825000D01*
G01Y827417D02*
X1264650Y827833D01*
X1265067Y828167D01*
X1265650Y828333D01*
X1266233Y828167D01*
X1266650Y827833D01*
X1266900Y827333D01*
Y825000D01*
G01X1270000Y828333D02*
Y825000D01*
G01Y829667D02*
X1269833Y829750D01*
Y829917D01*
X1270000Y830000D01*
X1270167Y829917D01*
Y829750D01*
X1270000Y829667D01*
G01X1275600Y825000D02*
Y830000D01*
G01X1241083Y811667D02*
X1243083D01*
G01X1242000Y812750D02*
Y810583D01*
G01X1246100Y809833D02*
X1249100Y815000D01*
G01X1252117Y811667D02*
X1254283D01*
G01X1257217Y814167D02*
X1257717Y814667D01*
X1258300Y814917D01*
X1258967Y815000D01*
X1259800Y814833D01*
X1260383Y814417D01*
X1260550Y813917D01*
X1260467Y813417D01*
X1260133Y813000D01*
X1258467Y812167D01*
X1257717Y811583D01*
X1257217Y810750D01*
X1257050Y810000D01*
X1260550D01*
G01X1261900D02*
Y813333D01*
G01Y812417D02*
X1262150Y812833D01*
X1262567Y813167D01*
X1263150Y813333D01*
X1263733Y813167D01*
X1264150Y812833D01*
X1264400Y812417D01*
Y810000D01*
G01Y812417D02*
X1264650Y812833D01*
X1265067Y813167D01*
X1265650Y813333D01*
X1266233Y813167D01*
X1266650Y812833D01*
X1266900Y812333D01*
Y810000D01*
G01X1270000Y813333D02*
Y810000D01*
G01Y814667D02*
X1269833Y814750D01*
Y814917D01*
X1270000Y815000D01*
X1270167Y814917D01*
Y814750D01*
X1270000Y814667D01*
G01X1275600Y810000D02*
Y815000D01*
G01X1242793Y785443D02*
X1241960Y786277D01*
X1241543Y787110D01*
Y790443D01*
X1241960Y791277D01*
X1242793Y792110D01*
G01X1248810Y787110D02*
Y792110D01*
X1247810Y791110D01*
G01Y787110D02*
X1249810D01*
G01X1254410Y786943D02*
X1254243Y787027D01*
Y787193D01*
X1254410Y787277D01*
X1254577Y787193D01*
Y787027D01*
X1254410Y786943D01*
G01X1258427Y791277D02*
X1258927Y791777D01*
X1259510Y792027D01*
X1260177Y792110D01*
X1261010Y791943D01*
X1261593Y791527D01*
X1261760Y791027D01*
X1261677Y790527D01*
X1261343Y790110D01*
X1259677Y789277D01*
X1258927Y788693D01*
X1258427Y787860D01*
X1258260Y787110D01*
X1261760D01*
G01X1263110D02*
Y790443D01*
G01Y789527D02*
X1263360Y789943D01*
X1263777Y790277D01*
X1264360Y790443D01*
X1264943Y790277D01*
X1265360Y789943D01*
X1265610Y789527D01*
Y787110D01*
G01Y789527D02*
X1265860Y789943D01*
X1266277Y790277D01*
X1266860Y790443D01*
X1267443Y790277D01*
X1267860Y789943D01*
X1268110Y789443D01*
Y787110D01*
G01X1268710D02*
Y790443D01*
G01Y789527D02*
X1268960Y789943D01*
X1269377Y790277D01*
X1269960Y790443D01*
X1270543Y790277D01*
X1270960Y789943D01*
X1271210Y789527D01*
Y787110D01*
G01Y789527D02*
X1271460Y789943D01*
X1271877Y790277D01*
X1272460Y790443D01*
X1273043Y790277D01*
X1273460Y789943D01*
X1273710Y789443D01*
Y787110D01*
G01X1280243D02*
Y792110D01*
X1282410Y787943D01*
X1284577Y792110D01*
Y787110D01*
G01X1289510D02*
Y790443D01*
G01Y789860D02*
X1289177Y790193D01*
X1288677Y790360D01*
X1288093Y790443D01*
X1287510Y790277D01*
X1287010Y789943D01*
X1286677Y789443D01*
X1286510Y788777D01*
X1286677Y788110D01*
X1287010Y787610D01*
X1287510Y787277D01*
X1288093Y787110D01*
X1288677Y787193D01*
X1289177Y787443D01*
X1289510Y787777D01*
G01X1292360Y790443D02*
X1294860Y787110D01*
G01Y790443D02*
X1292360Y787110D01*
G01X1299627Y785443D02*
X1300460Y786277D01*
X1300877Y787110D01*
Y790443D01*
X1300460Y791277D01*
X1299627Y792110D01*
G01X1244877Y797230D02*
X1241543Y798897D01*
X1244877Y800563D01*
G01X1247727Y798147D02*
X1249893D01*
G01Y799647D02*
X1247727D01*
G01X1254410Y802230D02*
X1253743Y802063D01*
X1253243Y801647D01*
X1252910Y801147D01*
X1252660Y800480D01*
X1252577Y799730D01*
X1252660Y798980D01*
X1252910Y798313D01*
X1253243Y797813D01*
X1253743Y797397D01*
X1254410Y797230D01*
X1255077Y797397D01*
X1255577Y797813D01*
X1255910Y798313D01*
X1256160Y798980D01*
X1256243Y799730D01*
X1256160Y800480D01*
X1255910Y801147D01*
X1255577Y801647D01*
X1255077Y802063D01*
X1254410Y802230D01*
G01X1260010Y797063D02*
X1259843Y797147D01*
Y797313D01*
X1260010Y797397D01*
X1260177Y797313D01*
Y797147D01*
X1260010Y797063D01*
G01X1265443Y797230D02*
X1265610Y798313D01*
X1265860Y799230D01*
X1266193Y800063D01*
X1266610Y800980D01*
X1267277Y802230D01*
X1263943D01*
G01X1269377Y797980D02*
X1269877Y797563D01*
X1270460Y797313D01*
X1271210Y797230D01*
X1271960Y797397D01*
X1272543Y797730D01*
X1272960Y798313D01*
X1273043Y798980D01*
X1272877Y799647D01*
X1272460Y800063D01*
X1271877Y800397D01*
X1271293Y800480D01*
X1270710Y800397D01*
X1269960Y800063D01*
X1270210Y802230D01*
X1272460D01*
G01X1275310Y797063D02*
X1278310Y802230D01*
G01X1275310D02*
X1274810Y802063D01*
X1274560Y801813D01*
X1274393Y801313D01*
X1274560Y800813D01*
X1274810Y800563D01*
X1275310Y800397D01*
X1275810Y800563D01*
X1276060Y800813D01*
X1276227Y801313D01*
X1276060Y801813D01*
X1275810Y802063D01*
X1275310Y802230D01*
G01X1278310Y798897D02*
X1277810Y798730D01*
X1277560Y798480D01*
X1277393Y797980D01*
X1277560Y797480D01*
X1277810Y797230D01*
X1278310Y797063D01*
X1278810Y797230D01*
X1279060Y797480D01*
X1279227Y797980D01*
X1279060Y798480D01*
X1278810Y798730D01*
X1278310Y798897D01*
G01X1234540Y850500D02*
Y782000D01*
G01X1343000Y850610D02*
Y782110D01*
G54D12*
G01X907102Y628479D02*
Y635354D01*
G01X891977Y628479D02*
X907102D01*
G01X891977Y721979D02*
Y628479D01*
G01X872727D02*
Y721979D01*
G01X857602Y628479D02*
X872727D01*
G01X857602Y635354D02*
Y628479D01*
G01X898852Y712354D02*
Y635354D01*
G01D02*
X942852D01*
G01X865852Y712354D02*
Y635354D01*
G01D02*
X843852D01*
G01D02*
Y712354D01*
G01X942852D02*
X898852D01*
G01X907102Y715104D02*
Y721979D01*
G01D02*
X891977D01*
G01X857602D02*
Y715104D01*
G01X872727Y721979D02*
X857602D01*
G01X843852Y712354D02*
X865852D01*
G01X984102Y628479D02*
Y635354D01*
G01X968977Y628479D02*
X984102D01*
G01X968977Y721979D02*
Y628479D01*
G01X949727D02*
Y721979D01*
G01X934602Y628479D02*
X949727D01*
G01X934602Y635354D02*
Y628479D01*
G01X975852Y712354D02*
Y635354D01*
G01D02*
X1019852D01*
G01X942852D02*
Y712354D01*
G01X984102Y715104D02*
Y721979D01*
G01X1019852Y712354D02*
X975852D01*
G01X984102Y721979D02*
X968977D01*
G01X934602D02*
Y715104D01*
G01X949727Y721979D02*
X934602D01*
G01X1045977Y628479D02*
X1061102D01*
G01X1045977Y719229D02*
Y628479D01*
G01X1026727D02*
Y719229D01*
G01X1011602Y628479D02*
X1026727D01*
G01X1011602Y635354D02*
Y628479D01*
G01X1052852Y712354D02*
Y635354D01*
G01D02*
X1096852D01*
G01X1019852D02*
Y712354D01*
G01X1061102Y719229D02*
X1045977D01*
G01X1096852Y712354D02*
X1052852D01*
G01X1011602Y719229D02*
Y712354D01*
G01X1026727Y719229D02*
X1011602D01*
G01X1122977Y628479D02*
X1138102D01*
G01X1088602D02*
X1122977D01*
G01X1088602Y635354D02*
Y628479D01*
G01X1061102D02*
Y635354D01*
G01X1129852Y712354D02*
Y635354D01*
G01D02*
X1173852D01*
G01X1096852D02*
Y712354D01*
G01X1173852D02*
X1129852D01*
G01X1138102Y719229D02*
X1103727D01*
G01X1088602D02*
Y712354D01*
G01X1103727Y719229D02*
X1088602D01*
G01X1061102Y712354D02*
Y719229D01*
G01X1199977Y628479D02*
X1215102D01*
G01X1199977Y719229D02*
Y628479D01*
G01X1180727D02*
Y719229D01*
G01X1165602Y628479D02*
X1180727D01*
G01X1165602Y635354D02*
Y628479D01*
G01X1138102D02*
Y635354D01*
G01X1173852D02*
Y712354D01*
G01X1215102Y719229D02*
X1199977D01*
G01X1165602D02*
Y712354D01*
G01X1180727Y719229D02*
X1165602D01*
G01X1138102Y712354D02*
Y719229D01*
G01X1215102Y628479D02*
Y635354D01*
G01X1250852D02*
Y712354D01*
G01X1206852D02*
Y635354D01*
G01D02*
X1250852D01*
G01X1215102Y712354D02*
Y719229D01*
G01X1250852Y712354D02*
X1206852D01*
G54D13*
G01X303090Y319830D02*
Y303830D01*
G01X292090Y340830D02*
Y357830D01*
G01X341590Y319830D02*
Y303830D01*
G01X356482Y330153D02*
X352452Y324663D01*
X356652Y324643D01*
G01X345680Y327680D02*
G02X350362Y319860I-4190J-7820D01*
G01X348190Y321780D01*
X351420Y321950D01*
X350460Y319850D01*
G01X352590Y340830D02*
Y357830D01*
G01X439562Y301543D02*
X435532Y296053D01*
X439732Y296033D01*
G54D14*
G01X891702Y675345D02*
X891096Y675951D01*
G01X890957Y676193D02*
X891702Y676936D01*
G01X889988Y677557D02*
X891702Y679270D01*
G01X888823Y678725D02*
X891702Y681604D01*
G01X887462Y679697D02*
X891702Y683937D01*
G01X885887Y680455D02*
X891702Y686270D01*
G01X884054Y680956D02*
X891702Y688604D01*
G01X881854Y681089D02*
X891702Y690937D01*
G01Y674644D02*
X891701Y674645D01*
G01X891702Y719229D02*
Y674644D01*
G01Y701013D02*
X866886Y725829D01*
G01X891702Y698679D02*
X873002Y717379D01*
G01X891702Y696346D02*
X873002Y715046D01*
G01X891702Y694013D02*
X873002Y712712D01*
G01X891702Y691679D02*
X873002Y710379D01*
G01X891702Y689346D02*
X873002Y708046D01*
G01X891702Y687012D02*
X873002Y705711D01*
G01X891702Y684678D02*
X873002Y703378D01*
G01X891702Y682345D02*
X873002Y701045D01*
G01X891702Y680012D02*
X873002Y698711D01*
G01Y690905D02*
X891702Y709604D01*
G01X873002Y693238D02*
X891702Y711938D01*
G01X873002Y695572D02*
X891702Y714272D01*
G01X873002Y697906D02*
X891702Y716605D01*
G01X873002Y700239D02*
X891702Y718939D01*
G01Y677678D02*
X873002Y696378D01*
G01X887198Y679848D02*
X873002Y694045D01*
G01X883703Y681010D02*
X873002Y691711D01*
G01X881330Y681049D02*
X873002Y689377D01*
G01X879392Y680653D02*
X873002Y687044D01*
G01X877738Y679974D02*
X873002Y684711D01*
G01X876310Y679069D02*
X873002Y682377D01*
G01X875080Y677966D02*
X873002Y680044D01*
G01X874045Y676668D02*
X873002Y677711D01*
G01X873215Y675163D02*
X873002Y675377D01*
G01X878929Y680497D02*
X891702Y693270D01*
G01X873002Y676905D02*
X891702Y695603D01*
G01X873002Y679238D02*
X891702Y697938D01*
G01X873002Y681571D02*
X891702Y700271D01*
G01X873002Y683905D02*
X891702Y702604D01*
G01X873002Y686238D02*
X891702Y704938D01*
G01X873002Y688571D02*
X891702Y707271D01*
G01X873002Y674644D02*
Y719229D01*
G01Y674645D02*
Y674644D01*
G01X891701Y674645D02*
G03X873003I-9349J-3541D01*
G01X924420Y712629D02*
X911221Y725829D01*
G01X891779D02*
X949925D01*
G01X922087Y712629D02*
X908887Y725829D01*
G01X919754Y712629D02*
X906554Y725829D01*
G01X917420Y712629D02*
X904221Y725829D01*
G01X915087Y712629D02*
X901887Y725829D01*
G01X912754Y712629D02*
X907377Y718006D01*
G01X905840Y719543D02*
X899554Y725829D01*
G01X910421Y712629D02*
X907377Y715673D01*
G01X903507Y719543D02*
X897221Y725829D01*
G01X908086Y712629D02*
X907377Y713339D01*
G01X901173Y719543D02*
X894886Y725829D01*
G01X898840Y719543D02*
X892553Y725829D01*
G01X896507Y719543D02*
X891342Y724707D01*
G01X894172Y719543D02*
X890494Y723221D01*
G01X891927Y719455D02*
X889440Y721942D01*
G01X891702Y717347D02*
X888191Y720857D01*
G01X891702Y715014D02*
X886738Y719977D01*
G01X891702Y712680D02*
X885053Y719328D01*
G01X891702Y710347D02*
X883070Y718978D01*
G01X891702Y708014D02*
X880607Y719107D01*
G01X911061Y712629D02*
X924260Y725829D01*
G01X908727Y712629D02*
X921927Y725829D01*
G01X907377Y713613D02*
X919592Y725828D01*
G01X907377Y715946D02*
X917259Y725829D01*
G01X907377Y718280D02*
X914926Y725829D01*
G01X906307Y719543D02*
X912592Y725828D01*
G01X903972Y719543D02*
X910259Y725829D01*
G01X901639Y719543D02*
X907926Y725829D01*
G01X899306Y719543D02*
X905593Y725829D01*
G01X896972Y719543D02*
X903258Y725829D01*
G01X894639Y719543D02*
X900925Y725829D01*
G01X892306Y719543D02*
X898592Y725829D01*
G01X892015Y719543D02*
X891702Y719229D01*
G01X907157Y719543D02*
X892015D01*
G01X907377Y719504D02*
X907157Y719543D01*
G01X907377Y712629D02*
Y719504D01*
G01X934327Y712629D02*
X907377D01*
G01X856340Y725829D02*
X872925D01*
G01X891702Y705679D02*
X876553Y720829D01*
G01X874327Y723054D02*
X871552Y725829D01*
G01X891702Y703346D02*
X869219Y725829D01*
G01X871152Y719229D02*
X864552Y725829D01*
G01X868819Y719229D02*
X862219Y725829D01*
G01X866485Y719229D02*
X859885Y725829D01*
G01X864151Y719229D02*
X857551Y725829D01*
G01X861818Y719229D02*
X855779Y725267D01*
G01X859485Y719229D02*
X854613Y724101D01*
G01X857327Y719053D02*
X853752Y722628D01*
G01X857327Y716720D02*
X853752Y720295D01*
G01X857327Y714387D02*
X853752Y717961D01*
G01X856750Y712629D02*
X853752Y715628D01*
G01X854417Y712629D02*
X853752Y713295D01*
G01X873002Y702572D02*
X896258Y725829D01*
G01X873002Y704906D02*
X893925Y725829D01*
G01X873002Y707239D02*
X885106Y719344D01*
G01X873002Y709572D02*
X882382Y718952D01*
G01X873002Y711907D02*
X880270Y719174D01*
G01X873002Y714240D02*
X878496Y719734D01*
G01X873002Y716573D02*
X876971Y720542D01*
G01X873002Y718907D02*
X875655Y721560D01*
G01X870991Y719229D02*
X874536Y722775D01*
G01X868658Y719229D02*
X873618Y724189D01*
G01X866324Y719229D02*
X872924Y725829D01*
G01X863991Y719229D02*
X870591Y725829D01*
G01X855058Y712629D02*
X857327Y714899D01*
G01X861658Y719229D02*
X868258Y725829D01*
G01X853752Y713657D02*
X857327Y717232D01*
G01X859323Y719229D02*
X865923Y725829D01*
G01X853752Y715991D02*
X863590Y725829D01*
G01X853752Y718324D02*
X861257Y725829D01*
G01X853752Y720657D02*
X858923Y725829D01*
G01X853752Y722991D02*
X856590Y725829D01*
G01X872925D02*
G03X891779I9427J3024D01*
G01X853752Y723240D02*
X856340Y725829D01*
G01X853752Y712629D02*
Y723240D01*
G01X857327Y712629D02*
X853752D01*
G01X857327Y719504D02*
Y712629D01*
G01X857602Y719229D02*
X857327Y719504D01*
G01X873002Y719229D02*
X857602D01*
G01X987225Y626490D02*
X984377Y629338D01*
G01X986058Y625324D02*
X983178Y628204D01*
G01X984377D02*
Y635079D01*
G01X984420Y624629D02*
X980845Y628204D01*
G01X984069Y624629D02*
X987952Y628512D01*
G01X981735Y624629D02*
X987952Y630845D01*
G01X979402Y624629D02*
X982977Y628204D01*
G01X982086Y624629D02*
X978512Y628204D01*
G01X979752Y624629D02*
X976177Y628204D01*
G01X968702Y628679D02*
X950002Y647379D01*
G01X968702Y628204D02*
X984377D01*
G01X968702Y719504D02*
Y628204D01*
G01X950002D02*
Y719504D01*
G01X977419Y624629D02*
X973844Y628204D01*
G01X975085Y624629D02*
X971511Y628204D01*
G01X972752Y624629D02*
X969177Y628204D01*
G01X970419Y624629D02*
X950002Y645046D01*
G01X968086Y624629D02*
X950002Y642712D01*
G01X965752Y624629D02*
X950002Y640379D01*
G01X963419Y624629D02*
X950002Y638046D01*
G01X961085Y624629D02*
X950002Y635712D01*
G01X958751Y624629D02*
X950002Y633379D01*
G01X956418Y624629D02*
X950002Y631046D01*
G01X954085Y624629D02*
X950002Y628711D01*
G01X951751Y624629D02*
X948176Y628204D01*
G01X977068Y624629D02*
X980642Y628204D01*
G01X974734Y624629D02*
X978309Y628204D01*
G01X972401Y624629D02*
X975976Y628204D01*
G01X970068Y624629D02*
X973643Y628204D01*
G01X967734Y624629D02*
X971309Y628204D01*
G01X965401Y624629D02*
X968976Y628204D01*
G01X963068Y624629D02*
X968702Y630263D01*
G01X960733Y624629D02*
X968702Y632597D01*
G01X958400Y624629D02*
X968702Y634931D01*
G01X956067Y624629D02*
X968702Y637264D01*
G01X953733Y624629D02*
X968702Y639597D01*
G01X951400Y624629D02*
X968702Y641931D01*
G01X949067Y624629D02*
X968702Y644264D01*
G01X946733Y624629D02*
X968702Y646597D01*
G01X949418Y624629D02*
X945843Y628204D01*
G01X947085Y624629D02*
X943510Y628204D01*
G01X933037Y624933D02*
X936307Y628204D01*
G01X931869Y626100D02*
X934327Y628556D01*
G01X930752Y627315D02*
X934327Y630890D01*
G01X930752Y629649D02*
X934327Y633224D01*
G01Y628204D02*
X950002D01*
G01X934327Y635079D02*
Y628204D01*
G01X930752Y627218D02*
Y635079D01*
G01X944750Y624629D02*
X941175Y628204D01*
G01X942417Y624629D02*
X938842Y628204D01*
G01X940084Y624629D02*
X936509Y628204D01*
G01X937750Y624629D02*
X930752Y631627D01*
G01X935417Y624629D02*
X930752Y629294D01*
G01X944400Y624629D02*
X947975Y628204D01*
G01X942066Y624629D02*
X945640Y628203D01*
G01X939733Y624629D02*
X943307Y628204D01*
G01X937399Y624629D02*
X940974Y628203D01*
G01X935066Y624629D02*
X938640Y628203D01*
G01X985362Y624629D02*
X933340D01*
G01D02*
X930752Y627218D01*
G01X987952Y630431D02*
X984377Y634006D01*
G01X987952Y628098D02*
X984377Y631673D01*
G01Y629605D02*
X987952Y633180D01*
G01X984377Y631938D02*
X987517Y635079D01*
G01X984377Y634272D02*
X985184Y635079D01*
G01X984377D02*
X987952D01*
G01X968702Y698683D02*
X950002Y717383D01*
G01X968702Y696350D02*
X950002Y715049D01*
G01X968702Y694016D02*
X950002Y712716D01*
G01X968702Y691683D02*
X950002Y710383D01*
G01Y690901D02*
X968702Y709601D01*
G01X950002Y693234D02*
X968702Y711934D01*
G01X950002Y695568D02*
X968702Y714267D01*
G01X950002Y697901D02*
X968702Y716601D01*
G01X950002Y700234D02*
X968702Y718934D01*
G01Y689350D02*
X950002Y708049D01*
G01X968702Y687016D02*
X950002Y705716D01*
G01X968702Y684683D02*
X950002Y703383D01*
G01X968702Y682350D02*
X950002Y701048D01*
G01X968702Y680015D02*
X950002Y698715D01*
G01X968702Y677682D02*
X950002Y696382D01*
G01X968702Y675349D02*
X950002Y694048D01*
G01X968702Y673015D02*
X950002Y691715D01*
G01X968702Y670682D02*
X950002Y689382D01*
G01X968702Y668349D02*
X950002Y687048D01*
G01X968702Y666015D02*
X950002Y684715D01*
G01X968702Y663681D02*
X950002Y682381D01*
G01X968702Y661348D02*
X950002Y680047D01*
G01X968702Y659014D02*
X950002Y677714D01*
G01Y658233D02*
X968702Y676932D01*
G01X950002Y660566D02*
X968702Y679266D01*
G01X950002Y662899D02*
X968702Y681599D01*
G01X950002Y665234D02*
X968702Y683932D01*
G01X950002Y667567D02*
X968702Y686267D01*
G01X950002Y669900D02*
X968702Y688600D01*
G01X950002Y672234D02*
X968702Y690933D01*
G01X950002Y674567D02*
X968702Y693267D01*
G01X950002Y676900D02*
X968702Y695600D01*
G01X950002Y679233D02*
X968702Y697933D01*
G01X950002Y681567D02*
X968702Y700267D01*
G01X950002Y683901D02*
X968702Y702601D01*
G01X950002Y686234D02*
X968702Y704934D01*
G01X950002Y688568D02*
X968702Y707268D01*
G01Y656681D02*
X950002Y675381D01*
G01X968702Y654348D02*
X950002Y673048D01*
G01X968702Y652014D02*
X950002Y670714D01*
G01X968702Y649681D02*
X950002Y668381D01*
G01X968702Y647348D02*
X950002Y666048D01*
G01X968702Y645013D02*
X950002Y663713D01*
G01X968702Y642680D02*
X950002Y661380D01*
G01X968702Y640347D02*
X950002Y659047D01*
G01X968702Y638014D02*
X950002Y656713D01*
G01X968702Y635680D02*
X950002Y654380D01*
G01X968702Y633347D02*
X950002Y652047D01*
G01X968702Y631014D02*
X950002Y649713D01*
G01Y630232D02*
X968702Y648932D01*
G01X950002Y632565D02*
X968702Y651265D01*
G01X950002Y634898D02*
X968702Y653598D01*
G01X950002Y637232D02*
X968702Y655931D01*
G01X950002Y639565D02*
X968702Y658265D01*
G01X950002Y641898D02*
X968702Y660598D01*
G01X950002Y644232D02*
X968702Y662931D01*
G01X950002Y646565D02*
X968702Y665265D01*
G01X950002Y648899D02*
X968702Y667599D01*
G01X950002Y651233D02*
X968702Y669932D01*
G01X950002Y653566D02*
X968702Y672266D01*
G01X950002Y655899D02*
X968702Y674599D01*
G01Y701017D02*
X943889Y725829D01*
G01X934327Y635053D02*
X934300Y635079D01*
G01X934327Y632720D02*
X931967Y635079D01*
G01X934327Y630387D02*
X930752Y633961D01*
G01Y631983D02*
X933848Y635079D01*
G01X930752Y634316D02*
X931515Y635079D01*
G01X930752D02*
X934327D01*
G01X987952Y721436D02*
X983558Y725829D01*
G01X987952Y719102D02*
X981224Y725829D01*
G01X987952Y714435D02*
X984377Y718009D01*
G01X987424Y712629D02*
X984377Y715676D01*
G01X985091Y712629D02*
X984377Y713343D01*
G01Y713608D02*
X987952Y717183D01*
G01X984377Y715942D02*
X987952Y719517D01*
G01X984377Y718276D02*
X987952Y721851D01*
G01X983271Y719504D02*
X987480Y723712D01*
G01X980938Y719504D02*
X986313Y724879D01*
G01X984377Y712629D02*
Y719504D01*
G01X987952Y712629D02*
X984377D01*
G01X987952Y716769D02*
X978891Y725829D01*
G01X968779D02*
X985362D01*
G01X982883Y719504D02*
X976558Y725829D01*
G01X980549Y719504D02*
X974224Y725829D01*
G01X978216Y719504D02*
X971891Y725829D01*
G01X975883Y719504D02*
X969558Y725829D01*
G01X973548Y719504D02*
X968343Y724709D01*
G01X971215Y719504D02*
X967496Y723223D01*
G01X968882Y719504D02*
X966442Y721943D01*
G01X968702Y717350D02*
X965193Y720859D01*
G01X968702Y715017D02*
X963741Y719978D01*
G01X968702Y712684D02*
X962057Y719329D01*
G01X968702Y710350D02*
X960073Y718978D01*
G01X968702Y708017D02*
X957613Y719106D01*
G01X968702Y705684D02*
X953567Y720819D01*
G01X951317Y723067D02*
X948556Y725829D01*
G01X978605Y719504D02*
X984930Y725829D01*
G01X976271Y719504D02*
X982596Y725829D01*
G01X973938Y719504D02*
X980263Y725829D01*
G01X971605Y719504D02*
X977930Y725829D01*
G01X969271Y719504D02*
X975596Y725829D01*
G01X950002Y702569D02*
X973262Y725828D01*
G01X950002Y704902D02*
X970929Y725829D01*
G01X950002Y707235D02*
X962112Y719345D01*
G01X950002Y709569D02*
X959386Y718952D01*
G01X950002Y711902D02*
X957273Y719173D01*
G01X950002Y714235D02*
X955499Y719733D01*
G01X950002Y716569D02*
X953974Y720540D01*
G01X950002Y718903D02*
X952657Y721558D01*
G01X948269Y719504D02*
X951539Y722772D01*
G01X984377Y719504D02*
X968702D01*
G01X949925Y725829D02*
G03X968779I9427J3024D01*
G01X968702Y703350D02*
X946222Y725829D01*
G01X947881Y719504D02*
X941556Y725829D01*
G01X945548Y719504D02*
X939223Y725829D01*
G01X943214Y719504D02*
X936889Y725829D01*
G01X940881Y719504D02*
X934556Y725829D01*
G01X938546Y719504D02*
X932223Y725829D01*
G01X936213Y719504D02*
X929888Y725829D01*
G01X934327Y719058D02*
X927555Y725829D01*
G01X934327Y716725D02*
X925222Y725829D01*
G01X934327Y714390D02*
X922888Y725829D01*
G01X933755Y712629D02*
X920555Y725829D01*
G01X931422Y712629D02*
X918222Y725829D01*
G01X929088Y712629D02*
X915888Y725829D01*
G01X926754Y712629D02*
X913554Y725829D01*
G01X945936Y719504D02*
X950619Y724187D01*
G01X943603Y719504D02*
X949925Y725826D01*
G01X941270Y719504D02*
X947595Y725829D01*
G01X932061Y712629D02*
X934327Y714894D01*
G01X938936Y719504D02*
X945261Y725829D01*
G01X929728Y712629D02*
X934327Y717228D01*
G01X936603Y719504D02*
X942928Y725829D01*
G01X927395Y712629D02*
X940595Y725829D01*
G01X925062Y712629D02*
X938260Y725829D01*
G01X922727Y712629D02*
X935927Y725829D01*
G01X920394Y712629D02*
X933594Y725829D01*
G01X918061Y712629D02*
X931260Y725829D01*
G01X915727Y712629D02*
X928927Y725829D01*
G01X913394Y712629D02*
X926593Y725828D01*
G01X934327Y719504D02*
Y712629D01*
G01X950002Y719504D02*
X934327D01*
G01X987952Y635079D02*
Y627218D01*
G01D02*
X985362Y624629D01*
G01X987952Y632764D02*
X985637Y635078D01*
G01X985731Y712629D02*
X987952Y714850D01*
G01Y723240D02*
Y712629D01*
G01X985362Y725829D02*
X987952Y723240D01*
G01X1120658Y632879D02*
X1122702Y634922D01*
G01X1118325Y632879D02*
X1122702Y637256D01*
G01X1115991Y632879D02*
X1122702Y639589D01*
G01X1113658Y632879D02*
X1122702Y641922D01*
G01X1111325Y632879D02*
X1122702Y644257D01*
G01Y714829D02*
Y632879D01*
G01X1104002Y690893D02*
X1122702Y709593D01*
G01X1104002Y693226D02*
X1122702Y711926D01*
G01X1104002Y695561D02*
X1122702Y714259D01*
G01X1104002Y697894D02*
X1120937Y714829D01*
G01X1104002Y700227D02*
X1118604Y714829D01*
G01X1122702Y701024D02*
X1108897Y714829D01*
G01X1122702Y698691D02*
X1106564Y714829D01*
G01X1122702Y696358D02*
X1104231Y714829D01*
G01X1122702Y694024D02*
X1104002Y712724D01*
G01X1122702Y691691D02*
X1104002Y710391D01*
G01X1122702Y689358D02*
X1104002Y708057D01*
G01X1122702Y687023D02*
X1104002Y705723D01*
G01X1122702Y684690D02*
X1104002Y703390D01*
G01X1122702Y682357D02*
X1104002Y701056D01*
G01X1122702Y680023D02*
X1104002Y698723D01*
G01Y658224D02*
X1122702Y676924D01*
G01X1104002Y660559D02*
X1122702Y679259D01*
G01X1104002Y662892D02*
X1122702Y681592D01*
G01X1104002Y665225D02*
X1122702Y683925D01*
G01X1104002Y667559D02*
X1122702Y686258D01*
G01X1104002Y669892D02*
X1122702Y688592D01*
G01X1104002Y672225D02*
X1122702Y690925D01*
G01X1104002Y674559D02*
X1122702Y693258D01*
G01X1104002Y676892D02*
X1122702Y695592D01*
G01X1104002Y679226D02*
X1122702Y697926D01*
G01X1104002Y681560D02*
X1122702Y700259D01*
G01X1104002Y683893D02*
X1122702Y702593D01*
G01X1104002Y686226D02*
X1122702Y704926D01*
G01X1104002Y688560D02*
X1122702Y707259D01*
G01Y677690D02*
X1104002Y696390D01*
G01X1122702Y675357D02*
X1104002Y694057D01*
G01X1122702Y673023D02*
X1104002Y691723D01*
G01X1122702Y670690D02*
X1104002Y689390D01*
G01X1122702Y668356D02*
X1104002Y687056D01*
G01X1122702Y666022D02*
X1104002Y684722D01*
G01X1122702Y663689D02*
X1104002Y682389D01*
G01X1122702Y661356D02*
X1104002Y680056D01*
G01X1122702Y659023D02*
X1104002Y677722D01*
G01X1122702Y656689D02*
X1104002Y675389D01*
G01X1122702Y654356D02*
X1104002Y673056D01*
G01X1122702Y652023D02*
X1104002Y670721D01*
G01X1122702Y649688D02*
X1104002Y668388D01*
G01X1122702Y647355D02*
X1104002Y666055D01*
G01X1108990Y632879D02*
X1122702Y646590D01*
G01X1106657Y632879D02*
X1122702Y648923D01*
G01X1104324Y632879D02*
X1122702Y651257D01*
G01X1104002Y634890D02*
X1122702Y653590D01*
G01X1104002Y637224D02*
X1122702Y655923D01*
G01X1104002Y639557D02*
X1122702Y658257D01*
G01X1104002Y641890D02*
X1122702Y660590D01*
G01X1104002Y644225D02*
X1122702Y662924D01*
G01X1104002Y646558D02*
X1122702Y665258D01*
G01X1104002Y648891D02*
X1122702Y667591D01*
G01X1104002Y651225D02*
X1122702Y669924D01*
G01X1104002Y653558D02*
X1122702Y672258D01*
G01X1104002Y655891D02*
X1122702Y674591D01*
G01Y645022D02*
X1104002Y663721D01*
G01X1122702Y642688D02*
X1104002Y661388D01*
G01X1122702Y640355D02*
X1104002Y659055D01*
G01X1122702Y638022D02*
X1104002Y656721D01*
G01X1122702Y635688D02*
X1104002Y654388D01*
G01X1122702Y633354D02*
X1104002Y652054D01*
G01X1120844Y632879D02*
X1104002Y649720D01*
G01X1118510Y632879D02*
X1104002Y647387D01*
G01X1116177Y632879D02*
X1104002Y645054D01*
G01X1113844Y632879D02*
X1104002Y642720D01*
G01X1111509Y632879D02*
X1104002Y640387D01*
G01X1109176Y632879D02*
X1104002Y638054D01*
G01X1106843Y632879D02*
X1104002Y635721D01*
G01X1104509Y632879D02*
X1104002Y633386D01*
G01X1122702Y632879D02*
X1104002D01*
G01D02*
Y714829D01*
G01X1122702Y712692D02*
X1120565Y714829D01*
G01X1122702Y710359D02*
X1118231Y714829D01*
G01X1122702Y708025D02*
X1115897Y714829D01*
G01X1122702Y705692D02*
X1113564Y714829D01*
G01X1104002Y702561D02*
X1116270Y714829D01*
G01X1104002Y704894D02*
X1113937Y714829D01*
G01X1104002Y707227D02*
X1111604Y714829D01*
G01X1104002Y709561D02*
X1109270Y714829D01*
G01X1104002Y711894D02*
X1106937Y714829D01*
G01X1104002Y714228D02*
X1104604Y714829D01*
G01X1122702Y703358D02*
X1111231Y714829D01*
G01X1104002D02*
X1122702D01*
G01X1181002Y690889D02*
X1199702Y709589D01*
G01X1181002Y693223D02*
X1199702Y711922D01*
G01X1181002Y695556D02*
X1199702Y714256D01*
G01X1181002Y697889D02*
X1197941Y714829D01*
G01X1181002Y700223D02*
X1195608Y714829D01*
G01X1199702Y701029D02*
X1185901Y714829D01*
G01X1199702Y698696D02*
X1183568Y714829D01*
G01X1199702Y696361D02*
X1181234Y714829D01*
G01X1199702Y694028D02*
X1181002Y712728D01*
G01X1199702Y691695D02*
X1181002Y710394D01*
G01Y658221D02*
X1199702Y676921D01*
G01X1181002Y660554D02*
X1199702Y679254D01*
G01X1181002Y662888D02*
X1199702Y681587D01*
G01X1181002Y665221D02*
X1199702Y683921D01*
G01X1181002Y667555D02*
X1199702Y686255D01*
G01X1181002Y669888D02*
X1199702Y688588D01*
G01X1181002Y672222D02*
X1199702Y690922D01*
G01X1181002Y674555D02*
X1199702Y693255D01*
G01X1181002Y676888D02*
X1199702Y695588D01*
G01X1181002Y679222D02*
X1199702Y697922D01*
G01X1181002Y681555D02*
X1199702Y700255D01*
G01X1181002Y683888D02*
X1199702Y702588D01*
G01X1181002Y686223D02*
X1199702Y704922D01*
G01X1181002Y688556D02*
X1199702Y707256D01*
G01Y689361D02*
X1181002Y708061D01*
G01X1199702Y687028D02*
X1181002Y705728D01*
G01X1199702Y684695D02*
X1181002Y703394D01*
G01X1199702Y682361D02*
X1181002Y701061D01*
G01X1199702Y680027D02*
X1181002Y698727D01*
G01X1199702Y677694D02*
X1181002Y696393D01*
G01X1199702Y675360D02*
X1181002Y694060D01*
G01X1199702Y673027D02*
X1181002Y691727D01*
G01X1199702Y670694D02*
X1181002Y689393D01*
G01X1199702Y668360D02*
X1181002Y687060D01*
G01X1199702Y666027D02*
X1181002Y684727D01*
G01X1199702Y663694D02*
X1181002Y682392D01*
G01X1199702Y661359D02*
X1181002Y680059D01*
G01X1199702Y659026D02*
X1181002Y677726D01*
G01X1197662Y632879D02*
X1199702Y634919D01*
G01X1195328Y632879D02*
X1199702Y637252D01*
G01X1192995Y632879D02*
X1199702Y639586D01*
G01X1190662Y632879D02*
X1199702Y641919D01*
G01X1188328Y632879D02*
X1199702Y644252D01*
G01X1185995Y632879D02*
X1199702Y646585D01*
G01X1183662Y632879D02*
X1199702Y648919D01*
G01X1181327Y632879D02*
X1199702Y651253D01*
G01X1181002Y634887D02*
X1199702Y653586D01*
G01X1181002Y637220D02*
X1199702Y655920D01*
G01X1181002Y639553D02*
X1199702Y658253D01*
G01X1181002Y641887D02*
X1199702Y660586D01*
G01X1181002Y644220D02*
X1199702Y662920D01*
G01X1181002Y646553D02*
X1199702Y665253D01*
G01X1181002Y648888D02*
X1199702Y667586D01*
G01X1181002Y651221D02*
X1199702Y669921D01*
G01X1181002Y653554D02*
X1199702Y672254D01*
G01X1181002Y655888D02*
X1199702Y674587D01*
G01Y656693D02*
X1181002Y675393D01*
G01X1199702Y654359D02*
X1181002Y673059D01*
G01X1199702Y652026D02*
X1181002Y670726D01*
G01X1199702Y649693D02*
X1181002Y668393D01*
G01X1199702Y647360D02*
X1181002Y666059D01*
G01X1199702Y645025D02*
X1181002Y663725D01*
G01X1199702Y642692D02*
X1181002Y661392D01*
G01X1199702Y640359D02*
X1181002Y659058D01*
G01X1199702Y638025D02*
X1181002Y656725D01*
G01X1199702Y635692D02*
X1181002Y654392D01*
G01X1199702Y633359D02*
X1181002Y652058D01*
G01X1197847Y632879D02*
X1181002Y649725D01*
G01X1195514Y632879D02*
X1181002Y647392D01*
G01X1193181Y632879D02*
X1181002Y645057D01*
G01X1190847Y632879D02*
X1181002Y642724D01*
G01X1188514Y632879D02*
X1181002Y640391D01*
G01X1186181Y632879D02*
X1181002Y638057D01*
G01X1183846Y632879D02*
X1181002Y635724D01*
G01X1181513Y632879D02*
X1181002Y633391D01*
G01X1199702Y632879D02*
X1181002D01*
G01X1199702Y714829D02*
Y632879D01*
G01X1181002D02*
Y714829D01*
G01Y702557D02*
X1193275Y714829D01*
G01X1181002Y704890D02*
X1190940Y714829D01*
G01X1181002Y707224D02*
X1188607Y714829D01*
G01X1181002Y709557D02*
X1186274Y714829D01*
G01X1181002Y711890D02*
X1183940Y714829D01*
G01X1181002Y714224D02*
X1181607Y714829D01*
G01X1199702Y712695D02*
X1197568Y714829D01*
G01X1199702Y710362D02*
X1195235Y714829D01*
G01X1199702Y708029D02*
X1192902Y714829D01*
G01X1199702Y705696D02*
X1190569Y714829D01*
G01X1199702Y703362D02*
X1188234Y714829D01*
G01X1181002D02*
X1199702D01*
M02*
